(kicad_pcb
	(version 20260206)
	(generator "pcbnew")
	(generator_version "10.0")
	(general
		(thickness 1.21888)
		(legacy_teardrops no)
	)
	(paper "A4")
	(layers
		(0 "F.Cu" signal "TOP")
		(4 "In1.Cu" signal "SGND")
		(6 "In2.Cu" signal "IN1")
		(8 "In3.Cu" signal "IN2")
		(10 "In4.Cu" signal "SGND1")
		(2 "B.Cu" signal "BOTTOM")
		(9 "F.Adhes" user "F.Adhesive")
		(11 "B.Adhes" user "B.Adhesive")
		(13 "F.Paste" user "Top Paste")
		(15 "B.Paste" user "Bottom Paste")
		(5 "F.SilkS" user "Top Overlay")
		(7 "B.SilkS" user "Bottom Overlay")
		(1 "F.Mask" user "Top Solder")
		(3 "B.Mask" user "Bottom Solder")
		(17 "Dwgs.User" user "User.Drawings")
		(19 "Cmts.User" user "User.Comments")
		(21 "Eco1.User" user "User.Eco1")
		(23 "Eco2.User" user "User.Eco2")
		(25 "Edge.Cuts" user)
		(27 "Margin" user)
		(31 "F.CrtYd" user "Top Courtyard")
		(29 "B.CrtYd" user "Bottom Courtyard")
		(35 "F.Fab" user "Top Component Center")
		(33 "B.Fab" user "Bottom Component Center")
	)
	(setup
		(pad_to_mask_clearance 0.1016)
		(allow_soldermask_bridges_in_footprints no)
		(tenting
			(front yes)
			(back yes)
		)
		(covering
			(front no)
			(back no)
		)
		(plugging
			(front no)
			(back no)
		)
		(capping no)
		(filling no)
		(aux_axis_origin -70.8739 262.2786)
		(grid_origin -70.8739 262.2786)
		(pcbplotparams
			(layerselection 0x00000000_00000000_55555555_5755f5ff)
			(plot_on_all_layers_selection 0x00000000_00000000_00000000_00000000)
			(disableapertmacros no)
			(usegerberextensions no)
			(usegerberattributes yes)
			(usegerberadvancedattributes yes)
			(creategerberjobfile yes)
			(dashed_line_dash_ratio 12)
			(dashed_line_gap_ratio 3)
			(svgprecision 4)
			(plotframeref no)
			(mode 1)
			(useauxorigin no)
			(pdf_front_fp_property_popups yes)
			(pdf_back_fp_property_popups yes)
			(pdf_metadata yes)
			(pdf_single_document no)
			(dxfpolygonmode yes)
			(dxfimperialunits yes)
			(dxfusepcbnewfont yes)
			(psnegative no)
			(psa4output no)
			(plot_black_and_white yes)
			(sketchpadsonfab no)
			(plotpadnumbers no)
			(hidednponfab no)
			(sketchdnponfab yes)
			(crossoutdnponfab yes)
			(subtractmaskfromsilk no)
			(outputformat 1)
			(mirror no)
			(drillshape 1)
			(scaleselection 1)
			(outputdirectory "")
		)
	)
	(footprint "Vault:RESC3216X89X64NL25T25"
		(layer "F.Cu")
		(at 209.6261 92.0162 90)
		(property "Reference" "R7"
			(at 3.7 -0.393345 270)
			(unlocked yes)
			(layer "F.SilkS")
			(effects
				(font
					(size 0.762 0.762)
					(thickness 0.2286)
				)
				(justify left bottom)
			)
		)
		(property "Value" "2mOhm_1%_1206"
			(at -8.378245 7.6471 0)
			(unlocked yes)
			(layer "F.SilkS")
			(hide yes)
			(effects
				(font
					(size 0.762 0.762)
					(thickness 0.2286)
				)
				(justify left bottom)
			)
		)
		(sheetname "POWER")
		(sheetfile "POWER.kicad_sch")
		(duplicate_pad_numbers_are_jumpers no)
		(fp_line
			(start -0.2 -0.825)
			(end 0.2 -0.825)
			(stroke
				(width 0.2)
				(type solid)
			)
			(layer "F.SilkS")
		)
		(fp_line
			(start -0.2 0.825)
			(end 0.2 0.825)
			(stroke
				(width 0.2)
				(type solid)
			)
			(layer "F.SilkS")
		)
		(pad "1" smd rect
			(at -1.325 0 180)
			(size 1.85 1.5)
			(layers "F.Cu" "F.Mask" "F.Paste")
			(net "+12V_SENS")
		)
		(pad "2" smd rect
			(at 1.325 0 180)
			(size 1.85 1.5)
			(layers "F.Cu" "F.Mask" "F.Paste")
			(net "+12V")
		)
	)
	(footprint "Vault:FP-ERJ2RK-IPC_A"
		(layer "F.Cu")
		(at 167.19755 85.03403 -90)
		(property "Reference" "R95"
			(at 0.05357 1.744519 90)
			(unlocked yes)
			(layer "F.SilkS")
			(effects
				(font
					(size 0.762 0.762)
					(thickness 0.2286)
				)
			)
		)
		(property "Value" "200_1%_0402"
			(at -2.935471 7.782475 180)
			(unlocked yes)
			(layer "F.SilkS")
			(hide yes)
			(effects
				(font
					(size 0.762 0.762)
					(thickness 0.2286)
				)
			)
		)
		(sheetname "USBUart_DipSelects")
		(sheetfile "USBUart_DipSelects.kicad_sch")
		(duplicate_pad_numbers_are_jumpers no)
		(fp_line
			(start 0.83624 0.73624)
			(end -0.83624 0.73624)
			(stroke
				(width 0.2)
				(type solid)
			)
			(layer "F.SilkS")
		)
		(fp_line
			(start 0.83624 -0.73624)
			(end -0.83624 -0.73624)
			(stroke
				(width 0.2)
				(type solid)
			)
			(layer "F.SilkS")
		)
		(fp_line
			(start -1.03624 0.53624)
			(end -1.03624 -0.53624)
			(stroke
				(width 0.2)
				(type solid)
			)
			(layer "F.CrtYd")
		)
		(fp_line
			(start 1.03624 0.53624)
			(end -1.03624 0.53624)
			(stroke
				(width 0.2)
				(type solid)
			)
			(layer "F.CrtYd")
		)
		(fp_line
			(start 1.03624 0.53624)
			(end 1.03624 -0.53624)
			(stroke
				(width 0.2)
				(type solid)
			)
			(layer "F.CrtYd")
		)
		(fp_line
			(start 1.03624 -0.53624)
			(end -1.03624 -0.53624)
			(stroke
				(width 0.2)
				(type solid)
			)
			(layer "F.CrtYd")
		)
		(fp_line
			(start -1.03624 0.53624)
			(end -1.03624 -0.53624)
			(stroke
				(width 0.2)
				(type solid)
			)
			(layer "F.Fab")
		)
		(fp_line
			(start 1.03624 0.53624)
			(end -1.03624 0.53624)
			(stroke
				(width 0.2)
				(type solid)
			)
			(layer "F.Fab")
		)
		(fp_line
			(start 1.03624 0.53624)
			(end 1.03624 -0.53624)
			(stroke
				(width 0.2)
				(type solid)
			)
			(layer "F.Fab")
		)
		(fp_line
			(start 0 0.5)
			(end 0 -0.5)
			(stroke
				(width 0.1)
				(type solid)
			)
			(layer "F.Fab")
		)
		(fp_line
			(start 0.5 0)
			(end -0.5 0)
			(stroke
				(width 0.1)
				(type solid)
			)
			(layer "F.Fab")
		)
		(fp_line
			(start 1.03624 -0.53624)
			(end -1.03624 -0.53624)
			(stroke
				(width 0.2)
				(type solid)
			)
			(layer "F.Fab")
		)
		(fp_text user "${REFERENCE}"
			(at -0.00001 0.09602 270)
			(unlocked yes)
			(layer "F.Fab")
			(effects
				(font
					(face "Arial")
					(size 0.63 0.63)
					(thickness 0.1)
				)
				(justify left bottom)
			)
		)
		(pad "1" smd rect
			(at -0.50215 0 270)
			(size 0.66818 0.67248)
			(layers "F.Cu" "F.Mask" "F.Paste")
			(net "DIP_SW_UART_SEL")
			(solder_mask_margin 0)
			(solder_paste_margin 0)
		)
		(pad "2" smd rect
			(at 0.50215 0 270)
			(size 0.66818 0.67248)
			(layers "F.Cu" "F.Mask" "F.Paste")
			(net "NetD25_1")
			(solder_mask_margin 0)
			(solder_paste_margin 0)
		)
	)
	(footprint "Vault:RESC0402(1005)_N"
		(layer "F.Cu")
		(at 205.5261 127.9162)
		(property "Reference" "R70"
			(at 0.1286 3.026931 0)
			(unlocked yes)
			(layer "F.SilkS")
			(effects
				(font
					(size 0.762 0.762)
					(thickness 0.2286)
				)
			)
		)
		(property "Value" "1.21_1%_0402"
			(at -2.783081 8.468145 270)
			(unlocked yes)
			(layer "F.SilkS")
			(hide yes)
			(effects
				(font
					(size 0.762 0.762)
					(thickness 0.2286)
				)
			)
		)
		(sheetname "POWER")
		(sheetfile "POWER.kicad_sch")
		(duplicate_pad_numbers_are_jumpers no)
		(pad "1" smd rect
			(at -0.5 0 90)
			(size 0.65 0.55)
			(layers "F.Cu" "F.Mask" "F.Paste")
			(net "P3V3_VDD")
		)
		(pad "2" smd rect
			(at 0.5 0 90)
			(size 0.65 0.55)
			(layers "F.Cu" "F.Mask" "F.Paste")
			(net "P3V3_PVDD")
		)
	)
	(footprint "Vault:FP-39-30-0040-MFG"
		(layer "F.Cu")
		(at 234.1699 89.5827 90)
		(property "Reference" "J38"
			(at 5.373155 -10.4438 0)
			(unlocked yes)
			(layer "F.SilkS")
			(effects
				(font
					(size 0.762 0.762)
					(thickness 0.2286)
				)
				(justify left bottom)
			)
		)
		(property "Value" "39-30-0040"
			(at -20.802445 -1.5141 0)
			(unlocked yes)
			(layer "F.SilkS")
			(hide yes)
			(effects
				(font
					(size 0.762 0.762)
					(thickness 0.2286)
				)
				(justify left bottom)
			)
		)
		(sheetname "POWER")
		(sheetfile "POWER.kicad_sch")
		(duplicate_pad_numbers_are_jumpers no)
		(fp_line
			(start 5.0165 -6.35)
			(end 5.0165 6.731)
			(stroke
				(width 0.2)
				(type solid)
			)
			(layer "F.SilkS")
		)
		(fp_line
			(start 3.84549 -6.35)
			(end 5.0165 -6.35)
			(stroke
				(width 0.2)
				(type solid)
			)
			(layer "F.SilkS")
		)
		(fp_line
			(start -0.34551 -6.35)
			(end 0.3455 -6.35)
			(stroke
				(width 0.2)
				(type solid)
			)
			(layer "F.SilkS")
		)
		(fp_line
			(start -5.0165 -6.35)
			(end -3.8455 -6.35)
			(stroke
				(width 0.2)
				(type solid)
			)
			(layer "F.SilkS")
		)
		(fp_line
			(start -5.0165 -6.35)
			(end -5.0165 6.731)
			(stroke
				(width 0.2)
				(type solid)
			)
			(layer "F.SilkS")
		)
		(fp_line
			(start -5.0165 6.731)
			(end 5.0165 6.731)
			(stroke
				(width 0.2)
				(type solid)
			)
			(layer "F.SilkS")
		)
		(fp_circle
			(center 5.61649 -7.5438)
			(end 5.74149 -7.5438)
			(stroke
				(width 0.25)
				(type solid)
			)
			(fill no)
			(layer "F.SilkS")
		)
		(fp_line
			(start 5.1165 -14.5306)
			(end 5.1165 6.831)
			(stroke
				(width 0.2)
				(type solid)
			)
			(layer "F.CrtYd")
		)
		(fp_line
			(start -5.1165 -14.5306)
			(end 5.1165 -14.5306)
			(stroke
				(width 0.2)
				(type solid)
			)
			(layer "F.CrtYd")
		)
		(fp_line
			(start -5.1165 -14.5306)
			(end -5.1165 6.831)
			(stroke
				(width 0.2)
				(type solid)
			)
			(layer "F.CrtYd")
		)
		(fp_line
			(start -5.1165 6.831)
			(end 5.1165 6.831)
			(stroke
				(width 0.2)
				(type solid)
			)
			(layer "F.CrtYd")
		)
		(fp_line
			(start 5.1165 -14.5306)
			(end 5.1165 6.831)
			(stroke
				(width 0.2)
				(type solid)
			)
			(layer "F.Fab")
		)
		(fp_line
			(start -5.1165 -14.5306)
			(end 5.1165 -14.5306)
			(stroke
				(width 0.2)
				(type solid)
			)
			(layer "F.Fab")
		)
		(fp_line
			(start -5.1165 -14.5306)
			(end -5.1165 6.831)
			(stroke
				(width 0.2)
				(type solid)
			)
			(layer "F.Fab")
		)
		(fp_line
			(start 0 -0.5)
			(end 0 0.5)
			(stroke
				(width 0.1)
				(type solid)
			)
			(layer "F.Fab")
		)
		(fp_line
			(start -0.5 0)
			(end 0.49999 0)
			(stroke
				(width 0.1)
				(type solid)
			)
			(layer "F.Fab")
		)
		(fp_line
			(start -5.1165 6.831)
			(end 5.1165 6.831)
			(stroke
				(width 0.2)
				(type solid)
			)
			(layer "F.Fab")
		)
		(fp_text user "${REFERENCE}"
			(at -0.00186 -3.56555 90)
			(unlocked yes)
			(layer "F.Fab")
			(effects
				(font
					(face "Arial")
					(size 0.63 0.63)
					(thickness 0.1)
				)
				(justify left bottom)
			)
		)
		(pad "" np_thru_hole circle
			(at 0 -0.254 90)
			(size 2.9972 2.9972)
			(drill 2.9972)
			(layers "*.Cu" "*.Mask")
			(solder_mask_margin 0)
			(solder_paste_margin -1000)
			(thermal_bridge_angle 90)
		)
		(pad "1" thru_hole rect
			(at 2.0955 -7.5438 90)
			(size 2.75 2.75)
			(drill 1.8)
			(layers "*.Cu" "*.Mask")
			(remove_unused_layers no)
			(net "GND")
			(solder_mask_margin 0)
			(solder_paste_margin -1000)
		)
		(pad "2" thru_hole circle
			(at -2.0955 -7.5438 90)
			(size 2.75 2.75)
			(drill 1.8)
			(layers "*.Cu" "*.Mask")
			(remove_unused_layers no)
			(net "GND")
			(solder_mask_margin 0)
			(solder_paste_margin -1000)
			(thermal_bridge_angle 90)
		)
		(pad "3" thru_hole circle
			(at 2.0955 -13.0556 90)
			(size 2.75 2.75)
			(drill 1.8)
			(layers "*.Cu" "*.Mask")
			(remove_unused_layers no)
			(net "NetD12_2")
			(solder_mask_margin 0)
			(solder_paste_margin -1000)
			(thermal_bridge_angle 90)
		)
		(pad "4" thru_hole circle
			(at -2.0955 -13.0556 90)
			(size 2.75 2.75)
			(drill 1.8)
			(layers "*.Cu" "*.Mask")
			(remove_unused_layers no)
			(net "NetD12_2")
			(solder_mask_margin 0)
			(solder_paste_margin -1000)
			(thermal_bridge_angle 90)
		)
	)
	(footprint "Vault:RESC1005X40X25LL05T05"
		(layer "F.Cu")
		(at 80.3261 84.0162)
		(property "Reference" "R108"
			(at -2.8714 0.226931 0)
			(unlocked yes)
			(layer "F.SilkS")
			(effects
				(font
					(size 0.762 0.762)
					(thickness 0.2286)
				)
			)
		)
		(property "Value" "4.7K_0402"
			(at -2.352802 6.563805 270)
			(unlocked yes)
			(layer "F.SilkS")
			(hide yes)
			(effects
				(font
					(size 1.524 1.524)
					(thickness 0.254)
				)
			)
		)
		(sheetname "USER_IO_STATUS")
		(sheetfile "USER_IO_STATUS.kicad_sch")
		(duplicate_pad_numbers_are_jumpers no)
		(pad "1" smd rect
			(at -0.4 0 90)
			(size 0.45 0.45)
			(layers "F.Cu" "F.Mask" "F.Paste")
			(net "+3.3V")
		)
		(pad "2" smd rect
			(at 0.4 0 90)
			(size 0.45 0.45)
			(layers "F.Cu" "F.Mask" "F.Paste")
			(net "NetR108_2")
		)
	)
	(footprint "GNSS:GNSS Header 16-pin"
		(layer "F.Cu")
		(at 229.84861 58.1786 180)
		(property "Reference" "J13"
			(at 5.19391 1.735479 0)
			(unlocked yes)
			(layer "F.SilkS")
			(effects
				(font
					(size 0.762 0.762)
					(thickness 0.2286)
				)
			)
		)
		(property "Value" "GNSS Header 16-pin"
			(at 6.740175 4.840511 180)
			(unlocked yes)
			(layer "F.SilkS")
			(hide yes)
			(effects
				(font
					(size 0.762 0.762)
					(thickness 0.2286)
				)
			)
		)
		(sheetname "GPS_IMU_SENSORS")
		(sheetfile "GPS_IMU_SENSORS.kicad_sch")
		(duplicate_pad_numbers_are_jumpers no)
		(fp_line
			(start 8.50001 0.5)
			(end -0.49999 0.5)
			(stroke
				(width 0.0254)
				(type solid)
			)
			(layer "F.SilkS")
		)
		(fp_line
			(start 8.50001 -7.5)
			(end 8.50001 0.5)
			(stroke
				(width 0.0254)
				(type solid)
			)
			(layer "F.SilkS")
		)
		(fp_line
			(start 8.50001 -7.5)
			(end -0.49999 -7.5)
			(stroke
				(width 0.0254)
				(type solid)
			)
			(layer "F.SilkS")
		)
		(fp_line
			(start -0.49999 -7.5)
			(end -0.49999 0.5)
			(stroke
				(width 0.0254)
				(type solid)
			)
			(layer "F.SilkS")
		)
		(fp_circle
			(center 0 -0.5)
			(end 0 -0.4746)
			(stroke
				(width 0.508)
				(type solid)
			)
			(fill no)
			(layer "F.SilkS")
		)
		(fp_text user "Orig 2x4"
			(at 8.011685 -6.109 90)
			(unlocked yes)
			(layer "F.SilkS")
			(effects
				(font
					(size 0.762 0.762)
					(thickness 0.2286)
				)
				(justify left bottom)
			)
		)
		(pad "0" thru_hole circle
			(at 4.00001 -13.49998 90)
			(size 0 0)
			(drill 0.76)
			(layers "*.Cu" "*.Mask")
			(remove_unused_layers no)
			(thermal_bridge_angle 90)
		)
		(pad "0" thru_hole circle
			(at 4.00001 -1.5 90)
			(size 0 0)
			(drill 0.76)
			(layers "*.Cu" "*.Mask")
			(remove_unused_layers no)
			(thermal_bridge_angle 90)
		)
		(pad "1" smd rect
			(at 1.77751 -0.5 90)
			(size 1.12 2.105)
			(layers "F.Cu" "F.Mask" "F.Paste")
			(net "+5.0V")
		)
		(pad "2" smd rect
			(at 6.22251 -0.5 90)
			(size 1.12 2.105)
			(layers "F.Cu" "F.Mask" "F.Paste")
			(net "+3.3V")
		)
		(pad "3" smd rect
			(at 1.77751 -2.5 90)
			(size 1.12 2.105)
			(layers "F.Cu" "F.Mask" "F.Paste")
			(net "GPS2_TX")
		)
		(pad "4" smd rect
			(at 6.22251 -2.5 90)
			(size 1.12 2.105)
			(layers "F.Cu" "F.Mask" "F.Paste")
			(net "GPS2_RST")
		)
		(pad "5" smd rect
			(at 1.77751 -4.5 90)
			(size 1.12 2.105)
			(layers "F.Cu" "F.Mask" "F.Paste")
			(net "GPS2_RX")
		)
		(pad "6" smd rect
			(at 6.22251 -4.5 90)
			(size 1.12 2.105)
			(layers "F.Cu" "F.Mask" "F.Paste")
			(net "GPS2_TP1")
		)
		(pad "7" smd rect
			(at 1.77751 -6.5 90)
			(size 1.12 2.105)
			(layers "F.Cu" "F.Mask" "F.Paste")
			(net "GPS2_TP2")
		)
		(pad "8" smd rect
			(at 6.22251 -6.5 90)
			(size 1.12 2.105)
			(layers "F.Cu" "F.Mask" "F.Paste")
			(net "GND")
		)
		(pad "9" smd rect
			(at 1.77751 -8.50001 90)
			(size 1.12 2.105)
			(layers "F.Cu" "F.Mask" "F.Paste")
			(net "+5.0V")
		)
		(pad "10" smd rect
			(at 6.22251 -8.50001 90)
			(size 1.12 2.105)
			(layers "F.Cu" "F.Mask" "F.Paste")
			(net "+3.3V")
		)
		(pad "11" smd rect
			(at 1.77751 -10.50001 90)
			(size 1.12 2.105)
			(layers "F.Cu" "F.Mask" "F.Paste")
			(net "GPS2_PIN11")
		)
		(pad "12" smd rect
			(at 6.22251 -10.50001 90)
			(size 1.12 2.105)
			(layers "F.Cu" "F.Mask" "F.Paste")
			(net "GPS2_PIN12")
		)
		(pad "13" smd rect
			(at 1.77751 -12.5 90)
			(size 1.12 2.105)
			(layers "F.Cu" "F.Mask" "F.Paste")
			(net "GPS2_PIN13")
		)
		(pad "14" smd rect
			(at 6.22251 -12.5 90)
			(size 1.12 2.105)
			(layers "F.Cu" "F.Mask" "F.Paste")
			(net "GPS2_PIN14")
		)
		(pad "15" smd rect
			(at 1.77751 -14.5 90)
			(size 1.12 2.105)
			(layers "F.Cu" "F.Mask" "F.Paste")
			(net "GPS2_PIN15")
		)
		(pad "16" smd rect
			(at 6.22251 -14.5 90)
			(size 1.12 2.105)
			(layers "F.Cu" "F.Mask" "F.Paste")
			(net "GND")
		)
	)
	(footprint "FPGA_CONN:SingleFPGAConn"
		(layer "F.Cu")
		(at 162.57841 95.87725 -90)
		(property "Reference" "J35"
			(at -0.39436 -23.455129 270)
			(unlocked yes)
			(layer "F.SilkS")
			(effects
				(font
					(size 0.762 0.762)
					(thickness 0.2286)
				)
			)
		)
		(property "Value" "Single FPGA Conn"
			(at 9.25452 3.621231 270)
			(unlocked yes)
			(layer "F.SilkS")
			(hide yes)
			(effects
				(font
					(size 0.762 0.762)
					(thickness 0.2286)
				)
			)
		)
		(sheetname "FPGA")
		(sheetfile "FPGA.kicad_sch")
		(duplicate_pad_numbers_are_jumpers no)
		(fp_line
			(start -1.40005 1.24993)
			(end -1.40005 0.70002)
			(stroke
				(width 0.15011)
				(type solid)
			)
			(layer "F.SilkS")
		)
		(fp_line
			(start 1.40004 1.24993)
			(end -1.40005 1.24993)
			(stroke
				(width 0.15011)
				(type solid)
			)
			(layer "F.SilkS")
		)
		(fp_line
			(start 1.40004 1.24993)
			(end 1.99999 0.70002)
			(stroke
				(width 0.15011)
				(type solid)
			)
			(layer "F.SilkS")
		)
		(fp_line
			(start -2 0.70002)
			(end -2 0.03302)
			(stroke
				(width 0.15011)
				(type solid)
			)
			(layer "F.SilkS")
		)
		(fp_line
			(start -1.40005 0.70002)
			(end -2 0.70002)
			(stroke
				(width 0.15011)
				(type solid)
			)
			(layer "F.SilkS")
		)
		(fp_line
			(start 1.99999 0.70002)
			(end 1.99999 0.03302)
			(stroke
				(width 0.15011)
				(type solid)
			)
			(layer "F.SilkS")
		)
		(fp_line
			(start -2 -20.03298)
			(end -2 -20.69999)
			(stroke
				(width 0.15011)
				(type solid)
			)
			(layer "F.SilkS")
		)
		(fp_line
			(start 1.99999 -20.03298)
			(end 1.99999 -20.69999)
			(stroke
				(width 0.15011)
				(type solid)
			)
			(layer "F.SilkS")
		)
		(fp_line
			(start -1.40005 -20.69999)
			(end -2 -20.69999)
			(stroke
				(width 0.15011)
				(type solid)
			)
			(layer "F.SilkS")
		)
		(fp_line
			(start -1.40005 -20.69999)
			(end -1.40005 -21.2499)
			(stroke
				(width 0.15011)
				(type solid)
			)
			(layer "F.SilkS")
		)
		(fp_line
			(start 1.99999 -20.69999)
			(end 1.40004 -21.2499)
			(stroke
				(width 0.15011)
				(type solid)
			)
			(layer "F.SilkS")
		)
		(fp_line
			(start 1.40004 -21.2499)
			(end -1.40005 -21.2499)
			(stroke
				(width 0.15011)
				(type solid)
			)
			(layer "F.SilkS")
		)
		(fp_circle
			(center 3.5052 -0.22454)
			(end 3.30505 -0.22454)
			(stroke
				(width 0.40005)
				(type solid)
			)
			(fill no)
			(layer "F.SilkS")
		)
		(pad "1" smd rect
			(at 2.02488 -0.24994 270)
			(size 1.54991 0.24994)
			(layers "F.Cu" "F.Mask" "F.Paste")
			(net "GPS1_PIN15")
		)
		(pad "2" smd rect
			(at -2.02489 -0.24994 270)
			(size 1.54991 0.24994)
			(layers "F.Cu" "F.Mask" "F.Paste")
			(net "GPS1_PIN13")
		)
		(pad "3" smd rect
			(at 2.02488 -0.75007 270)
			(size 1.54991 0.24994)
			(layers "F.Cu" "F.Mask" "F.Paste")
			(net "GPS1_PIN14")
		)
		(pad "4" smd rect
			(at -2.02489 -0.75007 270)
			(size 1.54991 0.24994)
			(layers "F.Cu" "F.Mask" "F.Paste")
			(net "GPS1_PIN11")
		)
		(pad "5" smd rect
			(at 2.02488 -1.24994 270)
			(size 1.54991 0.24994)
			(layers "F.Cu" "F.Mask" "F.Paste")
			(net "GPS1_PIN12")
		)
		(pad "6" smd rect
			(at -2.02489 -1.24994 270)
			(size 1.54991 0.24994)
			(layers "F.Cu" "F.Mask" "F.Paste")
		)
		(pad "7" smd rect
			(at 2.02488 -1.75006 270)
			(size 1.54991 0.24994)
			(layers "F.Cu" "F.Mask" "F.Paste")
		)
		(pad "8" smd rect
			(at -2.02489 -1.75006 270)
			(size 1.54991 0.24994)
			(layers "F.Cu" "F.Mask" "F.Paste")
			(net "MAC_USB_PWR")
		)
		(pad "9" smd rect
			(at 2.02488 -2.24994 270)
			(size 1.54991 0.24994)
			(layers "F.Cu" "F.Mask" "F.Paste")
			(net "GND")
		)
		(pad "10" smd rect
			(at -2.02489 -2.24994 270)
			(size 1.54991 0.24994)
			(layers "F.Cu" "F.Mask" "F.Paste")
			(net "GND")
		)
		(pad "11" smd rect
			(at 2.02488 -2.75006 270)
			(size 1.54991 0.24994)
			(layers "F.Cu" "F.Mask" "F.Paste")
			(net "MAC_RF_OUT")
		)
		(pad "12" smd rect
			(at -2.02489 -2.75006 270)
			(size 1.54991 0.24994)
			(layers "F.Cu" "F.Mask" "F.Paste")
		)
		(pad "13" smd rect
			(at 2.02488 -3.24993 270)
			(size 1.54991 0.24994)
			(layers "F.Cu" "F.Mask" "F.Paste")
			(net "MAC_RF_OUT")
		)
		(pad "14" smd rect
			(at -2.02489 -3.24993 270)
			(size 1.54991 0.24994)
			(layers "F.Cu" "F.Mask" "F.Paste")
		)
		(pad "15" smd rect
			(at 2.02488 -3.75006 270)
			(size 1.54991 0.24994)
			(layers "F.Cu" "F.Mask" "F.Paste")
			(net "ANT1_OUT")
		)
		(pad "16" smd rect
			(at -2.02489 -3.75006 270)
			(size 1.54991 0.24994)
			(layers "F.Cu" "F.Mask" "F.Paste")
			(net "ANT3_IN")
		)
		(pad "17" smd rect
			(at 2.02488 -4.24993 270)
			(size 1.54991 0.24994)
			(layers "F.Cu" "F.Mask" "F.Paste")
			(net "ANT2_OUT")
		)
		(pad "18" smd rect
			(at -2.02489 -4.24993 270)
			(size 1.54991 0.24994)
			(layers "F.Cu" "F.Mask" "F.Paste")
			(net "ANT4_IN")
		)
		(pad "19" smd rect
			(at 2.02488 -4.75006 270)
			(size 1.54991 0.24994)
			(layers "F.Cu" "F.Mask" "F.Paste")
			(net "GND")
		)
		(pad "20" smd rect
			(at -2.02489 -4.75006 270)
			(size 1.54991 0.24994)
			(layers "F.Cu" "F.Mask" "F.Paste")
			(net "GND")
		)
		(pad "21" smd rect
			(at 2.02488 -5.24993 270)
			(size 1.54991 0.24994)
			(layers "F.Cu" "F.Mask" "F.Paste")
			(net "ANT1_IN")
		)
		(pad "22" smd rect
			(at -2.02489 -5.24993 270)
			(size 1.54991 0.24994)
			(layers "F.Cu" "F.Mask" "F.Paste")
		)
		(pad "23" smd rect
			(at 2.02488 -5.75006 270)
			(size 1.54991 0.24994)
			(layers "F.Cu" "F.Mask" "F.Paste")
			(net "ANT2_IN")
		)
		(pad "24" smd rect
			(at -2.02489 -5.75006 270)
			(size 1.54991 0.24994)
			(layers "F.Cu" "F.Mask" "F.Paste")
		)
		(pad "25" smd rect
			(at 2.02488 -6.24993 270)
			(size 1.54991 0.24994)
			(layers "F.Cu" "F.Mask" "F.Paste")
			(net "ANT3_OUT")
		)
		(pad "26" smd rect
			(at -2.02489 -6.24993 270)
			(size 1.54991 0.24994)
			(layers "F.Cu" "F.Mask" "F.Paste")
			(net "MAC_TX")
		)
		(pad "27" smd rect
			(at 2.02488 -6.75005 270)
			(size 1.54991 0.24994)
			(layers "F.Cu" "F.Mask" "F.Paste")
			(net "ANT4_OUT")
		)
		(pad "28" smd rect
			(at -2.02489 -6.75005 270)
			(size 1.54991 0.24994)
			(layers "F.Cu" "F.Mask" "F.Paste")
			(net "MAC_RX")
		)
		(pad "29" smd rect
			(at 2.02488 -7.24993 270)
			(size 1.54991 0.24994)
			(layers "F.Cu" "F.Mask" "F.Paste")
			(net "GND")
		)
		(pad "30" smd rect
			(at -2.02489 -7.24993 270)
			(size 1.54991 0.24994)
			(layers "F.Cu" "F.Mask" "F.Paste")
			(net "GND")
		)
		(pad "31" smd rect
			(at 2.02488 -7.75005 270)
			(size 1.54991 0.24994)
			(layers "F.Cu" "F.Mask" "F.Paste")
		)
		(pad "32" smd rect
			(at -2.02489 -7.75005 270)
			(size 1.54991 0.24994)
			(layers "F.Cu" "F.Mask" "F.Paste")
		)
		(pad "33" smd rect
			(at 2.02488 -8.24992 270)
			(size 1.54991 0.24994)
			(layers "F.Cu" "F.Mask" "F.Paste")
			(net "NetJ35_33")
		)
		(pad "34" smd rect
			(at -2.02489 -8.24992 270)
			(size 1.54991 0.24994)
			(layers "F.Cu" "F.Mask" "F.Paste")
		)
		(pad "35" smd rect
			(at 2.02488 -8.75005 270)
			(size 1.54991 0.24994)
			(layers "F.Cu" "F.Mask" "F.Paste")
			(net "MAC_ALARM")
		)
		(pad "36" smd rect
			(at -2.02489 -8.75005 270)
			(size 1.54991 0.24994)
			(layers "F.Cu" "F.Mask" "F.Paste")
		)
		(pad "37" smd rect
			(at 2.02488 -9.24992 270)
			(size 1.54991 0.24994)
			(layers "F.Cu" "F.Mask" "F.Paste")
			(net "MAC_BITE")
		)
		(pad "38" smd rect
			(at -2.02489 -9.24992 270)
			(size 1.54991 0.24994)
			(layers "F.Cu" "F.Mask" "F.Paste")
		)
		(pad "39" smd rect
			(at 2.02488 -9.75005 270)
			(size 1.54991 0.24994)
			(layers "F.Cu" "F.Mask" "F.Paste")
			(net "GND")
		)
		(pad "40" smd rect
			(at -2.02489 -9.75005 270)
			(size 1.54991 0.24994)
			(layers "F.Cu" "F.Mask" "F.Paste")
			(net "GND")
		)
		(pad "41" smd rect
			(at 2.02488 -10.24992 270)
			(size 1.54991 0.24994)
			(layers "F.Cu" "F.Mask" "F.Paste")
		)
		(pad "42" smd rect
			(at -2.02489 -10.24992 270)
			(size 1.54991 0.24994)
			(layers "F.Cu" "F.Mask" "F.Paste")
		)
		(pad "43" smd rect
			(at 2.02488 -10.75005 270)
			(size 1.54991 0.24994)
			(layers "F.Cu" "F.Mask" "F.Paste")
			(net "FPGA_MAC_PPS_OUT-")
		)
		(pad "44" smd rect
			(at -2.02489 -10.75005 270)
			(size 1.54991 0.24994)
			(layers "F.Cu" "F.Mask" "F.Paste")
		)
		(pad "45" smd rect
			(at 2.02488 -11.24992 270)
			(size 1.54991 0.24994)
			(layers "F.Cu" "F.Mask" "F.Paste")
		)
		(pad "46" smd rect
			(at -2.02489 -11.24992 270)
			(size 1.54991 0.24994)
			(layers "F.Cu" "F.Mask" "F.Paste")
		)
		(pad "47" smd rect
			(at 2.02488 -11.75004 270)
			(size 1.54991 0.24994)
			(layers "F.Cu" "F.Mask" "F.Paste")
			(net "FPGA_MAC_PPS_IN0-")
		)
		(pad "48" smd rect
			(at -2.02489 -11.75004 270)
			(size 1.54991 0.24994)
			(layers "F.Cu" "F.Mask" "F.Paste")
		)
		(pad "49" smd rect
			(at 2.02488 -12.24992 270)
			(size 1.54991 0.24994)
			(layers "F.Cu" "F.Mask" "F.Paste")
			(net "GND")
		)
		(pad "50" smd rect
			(at -2.02489 -12.24992 270)
			(size 1.54991 0.24994)
			(layers "F.Cu" "F.Mask" "F.Paste")
			(net "GND")
		)
		(pad "51" smd rect
			(at 2.02488 -12.75004 270)
			(size 1.54991 0.24994)
			(layers "F.Cu" "F.Mask" "F.Paste")
		)
		(pad "52" smd rect
			(at -2.02489 -12.75004 270)
			(size 1.54991 0.24994)
			(layers "F.Cu" "F.Mask" "F.Paste")
		)
		(pad "53" smd rect
			(at 2.02488 -13.24991 270)
			(size 1.54991 0.24994)
			(layers "F.Cu" "F.Mask" "F.Paste")
			(net "FPGA_MAC_PPS_IN1-")
		)
		(pad "54" smd rect
			(at -2.02489 -13.24991 270)
			(size 1.54991 0.24994)
			(layers "F.Cu" "F.Mask" "F.Paste")
		)
		(pad "55" smd rect
			(at 2.02488 -13.75004 270)
			(size 1.54991 0.24994)
			(layers "F.Cu" "F.Mask" "F.Paste")
			(net "BNO_XIN32_C")
		)
		(pad "56" smd rect
			(at -2.02489 -13.75004 270)
			(size 1.54991 0.24994)
			(layers "F.Cu" "F.Mask" "F.Paste")
		)
		(pad "57" smd rect
			(at 2.02488 -14.24991 270)
			(size 1.54991 0.24994)
			(layers "F.Cu" "F.Mask" "F.Paste")
			(net "BNO_XOUT32_C")
		)
		(pad "58" smd rect
			(at -2.02489 -14.24991 270)
			(size 1.54991 0.24994)
			(layers "F.Cu" "F.Mask" "F.Paste")
		)
		(pad "59" smd rect
			(at 2.02488 -14.75004 270)
			(size 1.54991 0.24994)
			(layers "F.Cu" "F.Mask" "F.Paste")
			(net "GND")
		)
		(pad "60" smd rect
			(at -2.02489 -14.75004 270)
			(size 1.54991 0.24994)
			(layers "F.Cu" "F.Mask" "F.Paste")
			(net "GND")
		)
		(pad "61" smd rect
			(at 2.02488 -15.24991 270)
			(size 1.54991 0.24994)
			(layers "F.Cu" "F.Mask" "F.Paste")
			(net "SDA")
		)
		(pad "62" smd rect
			(at -2.02489 -15.24991 270)
			(size 1.54991 0.24994)
			(layers "F.Cu" "F.Mask" "F.Paste")
		)
		(pad "63" smd rect
			(at 2.02488 -15.75004 270)
			(size 1.54991 0.24994)
			(layers "F.Cu" "F.Mask" "F.Paste")
			(net "BNO_INT")
		)
		(pad "64" smd rect
			(at -2.02489 -15.75004 270)
			(size 1.54991 0.24994)
			(layers "F.Cu" "F.Mask" "F.Paste")
		)
		(pad "65" smd rect
			(at 2.02488 -16.24991 270)
			(size 1.54991 0.24994)
			(layers "F.Cu" "F.Mask" "F.Paste")
			(net "GPS2_PIN15")
		)
		(pad "66" smd rect
			(at -2.02489 -16.24991 270)
			(size 1.54991 0.24994)
			(layers "F.Cu" "F.Mask" "F.Paste")
		)
		(pad "67" smd rect
			(at 2.02488 -16.75003 270)
			(size 1.54991 0.24994)
			(layers "F.Cu" "F.Mask" "F.Paste")
			(net "SCL")
		)
		(pad "68" smd rect
			(at -2.02489 -16.75003 270)
			(size 1.54991 0.24994)
			(layers "F.Cu" "F.Mask" "F.Paste")
		)
		(pad "69" smd rect
			(at 2.02488 -17.24991 270)
			(size 1.54991 0.24994)
			(layers "F.Cu" "F.Mask" "F.Paste")
			(net "GND")
		)
		(pad "70" smd rect
			(at -2.02489 -17.24991 270)
			(size 1.54991 0.24994)
			(layers "F.Cu" "F.Mask" "F.Paste")
			(net "GND")
		)
		(pad "71" smd rect
			(at 2.02488 -17.75003 270)
			(size 1.54991 0.24994)
			(layers "F.Cu" "F.Mask" "F.Paste")
			(net "UART1_TXD")
		)
		(pad "72" smd rect
			(at -2.02489 -17.75003 270)
			(size 1.54991 0.24994)
			(layers "F.Cu" "F.Mask" "F.Paste")
			(net "MAC_USB+")
		)
		(pad "73" smd rect
			(at 2.02488 -18.2499 270)
			(size 1.54991 0.24994)
			(layers "F.Cu" "F.Mask" "F.Paste")
			(net "GPS2_PIN13")
		)
		(pad "74" smd rect
			(at -2.02489 -18.2499 270)
			(size 1.54991 0.24994)
			(layers "F.Cu" "F.Mask" "F.Paste")
			(net "MAC_USB-")
		)
		(pad "75" smd rect
			(at 2.02488 -18.75003 270)
			(size 1.54991 0.24994)
			(layers "F.Cu" "F.Mask" "F.Paste")
			(net "GPS2_PIN11")
		)
		(pad "76" smd rect
			(at -2.02489 -18.75003 270)
			(size 1.54991 0.24994)
			(layers "F.Cu" "F.Mask" "F.Paste")
			(net "GPS2_PIN12")
		)
		(pad "77" smd rect
			(at 2.02488 -19.2499 270)
			(size 1.54991 0.24994)
			(layers "F.Cu" "F.Mask" "F.Paste")
			(net "UART1_RXD")
		)
		(pad "78" smd rect
			(at -2.02489 -19.2499 270)
			(size 1.54991 0.24994)
			(layers "F.Cu" "F.Mask" "F.Paste")
			(net "GPS2_PIN14")
		)
		(pad "79" smd rect
			(at 2.02488 -19.75003 270)
			(size 1.54991 0.24994)
			(layers "F.Cu" "F.Mask" "F.Paste")
			(net "GPS1_RX")
		)
		(pad "80" smd rect
			(at -2.02489 -19.75003 270)
			(size 1.54991 0.24994)
			(layers "F.Cu" "F.Mask" "F.Paste")
			(net "GPS1_TX")
		)
		(pad "81" smd rect
			(at 0.01135 1.17625 270)
			(size 1.70002 1.35001)
			(layers "F.Cu" "F.Mask" "F.Paste")
		)
		(pad "82" thru_hole circle
			(at 0 0 270)
			(size 0.55016 0.55016)
			(drill 0.55016)
			(layers "*.Cu" "*.Mask")
			(remove_unused_layers no)
			(thermal_bridge_angle 90)
		)
		(pad "83" thru_hole circle
			(at 0 -19.99996 270)
			(size 0.55016 0.55016)
			(drill 0.55016)
			(layers "*.Cu" "*.Mask")
			(remove_unused_layers no)
			(thermal_bridge_angle 90)
		)
		(pad "84" smd rect
			(at 0.01135 -21.17375 270)
			(size 1.70002 1.35001)
			(layers "F.Cu" "F.Mask" "F.Paste")
		)
	)
	(footprint "Vault:RESC1005X40X25LL05T05"
		(layer "F.Cu")
		(at 183.4261 86.1162 90)
		(property "Reference" "R56"
			(at -0.3714 -1.073069 90)
			(unlocked yes)
			(layer "F.SilkS")
			(effects
				(font
					(size 0.762 0.762)
					(thickness 0.2286)
				)
			)
		)
		(property "Value" "DNI_4.7K_0402"
			(at -3.151351 5.29409 0)
			(unlocked yes)
			(layer "F.SilkS")
			(hide yes)
			(effects
				(font
					(size 0.762 0.762)
					(thickness 0.2286)
				)
			)
		)
		(sheetname "GPS_IMU_SENSORS")
		(sheetfile "GPS_IMU_SENSORS.kicad_sch")
		(duplicate_pad_numbers_are_jumpers no)
		(pad "1" smd rect
			(at -0.4 0 180)
			(size 0.45 0.45)
			(layers "F.Cu" "F.Mask" "F.Paste")
			(net "GND")
		)
		(pad "2" smd rect
			(at 0.4 0 180)
			(size 0.45 0.45)
			(layers "F.Cu" "F.Mask" "F.Paste")
			(net "NetR53_1")
		)
	)
	(footprint "Vault:FP-CC0603-DA-MFG"
		(layer "F.Cu")
		(at 215.3261 116.0162 -90)
		(property "Reference" "C9"
			(at 4.2 -0.493345 90)
			(unlocked yes)
			(layer "F.SilkS")
			(effects
				(font
					(size 0.762 0.762)
					(thickness 0.2286)
				)
				(justify left bottom)
			)
		)
		(property "Value" "0.1uF_50V_0603"
			(at 5.939845 3.6529 0)
			(unlocked yes)
			(layer "F.SilkS")
			(hide yes)
			(effects
				(font
					(size 0.762 0.762)
					(thickness 0.2286)
				)
				(justify left bottom)
			)
		)
		(sheetname "POWER")
		(sheetfile "POWER.kicad_sch")
		(duplicate_pad_numbers_are_jumpers no)
		(fp_line
			(start 0.85 0.85)
			(end -0.85 0.85)
			(stroke
				(width 0.2)
				(type solid)
			)
			(layer "F.SilkS")
		)
		(fp_line
			(start 0.85 -0.85)
			(end -0.85 -0.85)
			(stroke
				(width 0.2)
				(type solid)
			)
			(layer "F.SilkS")
		)
		(fp_line
			(start -1.35 0.75)
			(end -1.35 -0.75)
			(stroke
				(width 0.2)
				(type solid)
			)
			(layer "F.CrtYd")
		)
		(fp_line
			(start 1.35 0.75)
			(end -1.35 0.75)
			(stroke
				(width 0.2)
				(type solid)
			)
			(layer "F.CrtYd")
		)
		(fp_line
			(start 1.35 0.75)
			(end 1.35 -0.75)
			(stroke
				(width 0.2)
				(type solid)
			)
			(layer "F.CrtYd")
		)
		(fp_line
			(start 1.35 -0.75)
			(end -1.35 -0.75)
			(stroke
				(width 0.2)
				(type solid)
			)
			(layer "F.CrtYd")
		)
		(fp_line
			(start -1.35 0.75)
			(end -1.35 -0.75)
			(stroke
				(width 0.2)
				(type solid)
			)
			(layer "F.Fab")
		)
		(fp_line
			(start 1.35 0.75)
			(end -1.35 0.75)
			(stroke
				(width 0.2)
				(type solid)
			)
			(layer "F.Fab")
		)
		(fp_line
			(start 1.35 0.75)
			(end 1.35 -0.75)
			(stroke
				(width 0.2)
				(type solid)
			)
			(layer "F.Fab")
		)
		(fp_line
			(start 0 0.5)
			(end 0 -0.5)
			(stroke
				(width 0.1)
				(type solid)
			)
			(layer "F.Fab")
		)
		(fp_line
			(start 0.5 0)
			(end -0.5 0)
			(stroke
				(width 0.1)
				(type solid)
			)
			(layer "F.Fab")
		)
		(fp_line
			(start 1.35 -0.75)
			(end -1.35 -0.75)
			(stroke
				(width 0.2)
				(type solid)
			)
			(layer "F.Fab")
		)
		(fp_text user "${REFERENCE}"
			(at -0.00001 0.09602 270)
			(unlocked yes)
			(layer "F.Fab")
			(effects
				(font
					(face "Arial")
					(size 0.63 0.63)
					(thickness 0.1)
				)
				(justify left bottom)
			)
		)
		(pad "1" smd rect
			(at -0.75 0 270)
			(size 0.8 0.9)
			(layers "F.Cu" "F.Mask" "F.Paste")
			(net "NetC9_1")
			(solder_mask_margin 0)
			(solder_paste_margin 0)
		)
		(pad "2" smd rect
			(at 0.75 0 270)
			(size 0.8 0.9)
			(layers "F.Cu" "F.Mask" "F.Paste")
			(net "P5V_FB")
			(solder_mask_margin 0)
			(solder_paste_margin 0)
		)
	)
	(footprint "Vault:FP-C1005-050-0_05-IPC_A"
		(layer "F.Cu")
		(at 203.7261 111.8162 90)
		(property "Reference" "C5"
			(at -1.4 -0.293345 270)
			(unlocked yes)
			(layer "F.SilkS")
			(effects
				(font
					(size 0.762 0.762)
					(thickness 0.2286)
				)
				(justify left bottom)
			)
		)
		(property "Value" "2.2uF_16V_0402"
			(at -16.624845 29.5119 0)
			(unlocked yes)
			(layer "F.SilkS")
			(hide yes)
			(effects
				(font
					(size 0.762 0.762)
					(thickness 0.2286)
				)
				(justify left bottom)
			)
		)
		(sheetname "POWER")
		(sheetfile "POWER.kicad_sch")
		(duplicate_pad_numbers_are_jumpers no)
		(fp_line
			(start -0.83624 -0.73623)
			(end 0.83624 -0.73623)
			(stroke
				(width 0.2)
				(type solid)
			)
			(layer "F.SilkS")
		)
		(fp_line
			(start -0.83624 0.73624)
			(end 0.83624 0.73624)
			(stroke
				(width 0.2)
				(type solid)
			)
			(layer "F.SilkS")
		)
		(fp_line
			(start 1.03624 -0.53623)
			(end 1.03624 0.53624)
			(stroke
				(width 0.2)
				(type solid)
			)
			(layer "F.CrtYd")
		)
		(fp_line
			(start -1.03624 -0.53623)
			(end 1.03624 -0.53623)
			(stroke
				(width 0.2)
				(type solid)
			)
			(layer "F.CrtYd")
		)
		(fp_line
			(start -1.03624 -0.53623)
			(end -1.03624 0.53624)
			(stroke
				(width 0.2)
				(type solid)
			)
			(layer "F.CrtYd")
		)
		(fp_line
			(start -1.03624 0.53624)
			(end 1.03624 0.53624)
			(stroke
				(width 0.2)
				(type solid)
			)
			(layer "F.CrtYd")
		)
		(fp_line
			(start 1.03624 -0.53623)
			(end 1.03624 0.53624)
			(stroke
				(width 0.2)
				(type solid)
			)
			(layer "F.Fab")
		)
		(fp_line
			(start -1.03624 -0.53623)
			(end 1.03624 -0.53623)
			(stroke
				(width 0.2)
				(type solid)
			)
			(layer "F.Fab")
		)
		(fp_line
			(start -1.03624 -0.53623)
			(end -1.03624 0.53624)
			(stroke
				(width 0.2)
				(type solid)
			)
			(layer "F.Fab")
		)
		(fp_line
			(start 0 -0.5)
			(end 0 0.5)
			(stroke
				(width 0.1)
				(type solid)
			)
			(layer "F.Fab")
		)
		(fp_line
			(start -0.5 0)
			(end 0.5 0)
			(stroke
				(width 0.1)
				(type solid)
			)
			(layer "F.Fab")
		)
		(fp_line
			(start -1.03624 0.53624)
			(end 1.03624 0.53624)
			(stroke
				(width 0.2)
				(type solid)
			)
			(layer "F.Fab")
		)
		(fp_text user "${REFERENCE}"
			(at -0.00001 0.09602 90)
			(unlocked yes)
			(layer "F.Fab")
			(effects
				(font
					(face "Arial")
					(size 0.63 0.63)
					(thickness 0.1)
				)
				(justify left bottom)
			)
		)
		(pad "1" smd rect
			(at -0.46658 0 90)
			(size 0.73933 0.67248)
			(layers "F.Cu" "F.Mask" "F.Paste")
			(net "P5V_PVDD")
			(solder_mask_margin 0)
			(solder_paste_margin 0)
		)
		(pad "2" smd rect
			(at 0.46657 0 90)
			(size 0.73933 0.67248)
			(layers "F.Cu" "F.Mask" "F.Paste")
			(net "GND")
			(solder_mask_margin 0)
			(solder_paste_margin 0)
		)
	)
	(footprint "Vault:RESC3116X65X50ML20T20"
		(layer "F.Cu")
		(at 155.9123 89.7162)
		(property "Reference" "R47"
			(at 3.9286 -0.073079 0)
			(unlocked yes)
			(layer "F.SilkS")
			(effects
				(font
					(size 0.762 0.762)
					(thickness 0.2286)
				)
			)
		)
		(property "Value" "DNI_0_5%_1206"
			(at 7.27402 3.291071 0)
			(unlocked yes)
			(layer "F.SilkS")
			(hide yes)
			(effects
				(font
					(size 0.762 0.762)
					(thickness 0.2286)
				)
			)
		)
		(sheetname "MAC")
		(sheetfile "MAC.kicad_sch")
		(duplicate_pad_numbers_are_jumpers no)
		(fp_line
			(start -0.35 -0.85)
			(end 0.35 -0.85)
			(stroke
				(width 0.2)
				(type solid)
			)
			(layer "F.SilkS")
		)
		(fp_line
			(start -0.35 0.85)
			(end 0.35 0.85)
			(stroke
				(width 0.2)
				(type solid)
			)
			(layer "F.SilkS")
		)
		(pad "1" smd rect
			(at -1.475 0 90)
			(size 1.9 1.45)
			(layers "F.Cu" "F.Mask" "F.Paste")
			(net "MAC_VCC")
		)
		(pad "2" smd rect
			(at 1.475 0 90)
			(size 1.9 1.45)
			(layers "F.Cu" "F.Mask" "F.Paste")
			(net "+3.3V")
		)
	)
	(footprint "SA53:SolderSocket"
		(layer "F.Cu")
		(at 125.7301 138.2162 90)
		(property "Reference" "SKT10"
			(at -3.426921 -0.575395 0)
			(unlocked yes)
			(layer "F.SilkS")
			(effects
				(font
					(size 0.762 0.762)
					(thickness 0.2286)
				)
			)
		)
		(property "Value" "0332-0-43-80-18-27-10-0"
			(at -2.910071 16.1362 0)
			(unlocked yes)
			(layer "F.SilkS")
			(hide yes)
			(effects
				(font
					(size 0.762 0.762)
					(thickness 0.2286)
				)
			)
		)
		(sheetname "MAC")
		(sheetfile "MAC.kicad_sch")
		(duplicate_pad_numbers_are_jumpers no)
		(pad "1" thru_hole circle
			(at 0 0 90)
			(size 2.54 2.54)
			(drill 2.0066)
			(layers "*.Cu" "*.Mask")
			(remove_unused_layers no)
			(net "MAC_PPS_OUT")
			(thermal_bridge_angle 90)
		)
	)
	(footprint "Resistors:RESC2012X50N"
		(layer "F.Cu")
		(at 199.41136 139.37763)
		(property "Reference" "R18"
			(at -0.68526 -1.068085 0)
			(unlocked yes)
			(layer "F.SilkS")
			(effects
				(font
					(size 0.762 0.762)
					(thickness 0.2286)
				)
				(justify left bottom)
			)
		)
		(property "Value" "CRCW080533R0FKEA"
			(at -5.5249 -8.929165 0)
			(unlocked yes)
			(layer "F.SilkS")
			(hide yes)
			(effects
				(font
					(size 0.762 0.762)
					(thickness 0.2286)
				)
				(justify left bottom)
			)
		)
		(sheetname "PCIe_JTAG")
		(sheetfile "PCIe_JTAG.kicad_sch")
		(duplicate_pad_numbers_are_jumpers no)
		(fp_line
			(start 0 0.762)
			(end 0 -0.762)
			(stroke
				(width 0.1524)
				(type solid)
			)
			(layer "F.SilkS")
		)
		(pad "1" smd rect
			(at -1 0 90)
			(size 1.45 0.95)
			(layers "F.Cu" "F.Mask" "F.Paste")
			(net "FPGA_TCK")
		)
		(pad "2" smd rect
			(at 1 0 90)
			(size 1.45 0.95)
			(layers "F.Cu" "F.Mask" "F.Paste")
			(net "NetR18_2")
		)
	)
	(footprint "Vault:FP-GRM31C-0_2-e0_3_0_8-IPC_C"
		(layer "F.Cu")
		(at 212.1261 103.0162 90)
		(property "Reference" "C12"
			(at 4 -0.393345 270)
			(unlocked yes)
			(layer "F.SilkS")
			(effects
				(font
					(size 0.762 0.762)
					(thickness 0.2286)
				)
				(justify left bottom)
			)
		)
		(property "Value" "4.7uF_50V_1206"
			(at -25.814045 1.90131 0)
			(unlocked yes)
			(layer "F.SilkS")
			(hide yes)
			(effects
				(font
					(size 0.762 0.762)
					(thickness 0.2286)
				)
				(justify left bottom)
			)
		)
		(sheetname "POWER")
		(sheetfile "POWER.kicad_sch")
		(duplicate_pad_numbers_are_jumpers no)
		(fp_line
			(start -0.39847 -0.9)
			(end 0.39846 -0.9)
			(stroke
				(width 0.2)
				(type solid)
			)
			(layer "F.SilkS")
		)
		(fp_line
			(start -0.39847 0.9)
			(end 0.39846 0.9)
			(stroke
				(width 0.2)
				(type solid)
			)
			(layer "F.SilkS")
		)
		(fp_line
			(start 1.9531 -1)
			(end 1.9531 1)
			(stroke
				(width 0.2)
				(type solid)
			)
			(layer "F.CrtYd")
		)
		(fp_line
			(start -1.9531 -1)
			(end 1.9531 -1)
			(stroke
				(width 0.2)
				(type solid)
			)
			(layer "F.CrtYd")
		)
		(fp_line
			(start -1.9531 -1)
			(end -1.9531 1)
			(stroke
				(width 0.2)
				(type solid)
			)
			(layer "F.CrtYd")
		)
		(fp_line
			(start -1.9531 1)
			(end 1.9531 1)
			(stroke
				(width 0.2)
				(type solid)
			)
			(layer "F.CrtYd")
		)
		(fp_line
			(start 1.9531 -1)
			(end 1.9531 1)
			(stroke
				(width 0.2)
				(type solid)
			)
			(layer "F.Fab")
		)
		(fp_line
			(start -1.9531 -1)
			(end 1.9531 -1)
			(stroke
				(width 0.2)
				(type solid)
			)
			(layer "F.Fab")
		)
		(fp_line
			(start -1.9531 -1)
			(end -1.9531 1)
			(stroke
				(width 0.2)
				(type solid)
			)
			(layer "F.Fab")
		)
		(fp_line
			(start 0 -0.5)
			(end 0 0.5)
			(stroke
				(width 0.1)
				(type solid)
			)
			(layer "F.Fab")
		)
		(fp_line
			(start -0.5 0)
			(end 0.5 0)
			(stroke
				(width 0.1)
				(type solid)
			)
			(layer "F.Fab")
		)
		(fp_line
			(start -1.9531 1)
			(end 1.9531 1)
			(stroke
				(width 0.2)
				(type solid)
			)
			(layer "F.Fab")
		)
		(fp_text user "${REFERENCE}"
			(at -0.00001 0.09602 90)
			(unlocked yes)
			(layer "F.Fab")
			(effects
				(font
					(face "Arial")
					(size 0.63 0.63)
					(thickness 0.1)
				)
				(justify left bottom)
			)
		)
		(pad "1" smd rect
			(at -1.27578 0 90)
			(size 1.15464 1.7062)
			(layers "F.Cu" "F.Mask" "F.Paste")
			(net "+12V")
			(solder_mask_margin 0)
			(solder_paste_margin 0)
		)
		(pad "2" smd rect
			(at 1.27578 0 90)
			(size 1.15464 1.7062)
			(layers "F.Cu" "F.Mask" "F.Paste")
			(net "GND")
			(solder_mask_margin 0)
			(solder_paste_margin 0)
		)
	)
	(footprint "Vault:FP-SOD323-MFG"
		(layer "F.Cu")
		(at 223.3261 114.5162)
		(property "Reference" "D21"
			(at 0.828605 1.426931 0)
			(unlocked yes)
			(layer "F.SilkS")
			(effects
				(font
					(size 0.762 0.762)
					(thickness 0.2286)
				)
			)
		)
		(property "Value" "SD103AWS-7-F"
			(at 7.096465 2.452871 0)
			(unlocked yes)
			(layer "F.SilkS")
			(hide yes)
			(effects
				(font
					(size 0.762 0.762)
					(thickness 0.2286)
				)
			)
		)
		(sheetname "POWER")
		(sheetfile "POWER.kicad_sch")
		(duplicate_pad_numbers_are_jumpers no)
		(fp_line
			(start -0.9 -0.7)
			(end 0.9 -0.7)
			(stroke
				(width 0.2)
				(type solid)
			)
			(layer "F.SilkS")
		)
		(fp_line
			(start -0.9 -0.6)
			(end -0.9 -0.7)
			(stroke
				(width 0.2)
				(type solid)
			)
			(layer "F.SilkS")
		)
		(fp_line
			(start -0.9 0.7)
			(end -0.9 0.6)
			(stroke
				(width 0.2)
				(type solid)
			)
			(layer "F.SilkS")
		)
		(fp_line
			(start -0.9 0.7)
			(end 0.9 0.7)
			(stroke
				(width 0.2)
				(type solid)
			)
			(layer "F.SilkS")
		)
		(fp_line
			(start 0.9 -0.6)
			(end 0.9 -0.7)
			(stroke
				(width 0.2)
				(type solid)
			)
			(layer "F.SilkS")
		)
		(fp_line
			(start 0.9 0.7)
			(end 0.9 0.6)
			(stroke
				(width 0.2)
				(type solid)
			)
			(layer "F.SilkS")
		)
		(fp_circle
			(center -1.9 0)
			(end -1.9 -0.125)
			(stroke
				(width 0.25)
				(type solid)
			)
			(fill no)
			(layer "F.SilkS")
		)
		(fp_line
			(start -1.45 -0.8)
			(end 1.45 -0.8)
			(stroke
				(width 0.2)
				(type solid)
			)
			(layer "F.CrtYd")
		)
		(fp_line
			(start -1.45 0.8)
			(end -1.45 -0.8)
			(stroke
				(width 0.2)
				(type solid)
			)
			(layer "F.CrtYd")
		)
		(fp_line
			(start -1.45 0.8)
			(end 1.45 0.8)
			(stroke
				(width 0.2)
				(type solid)
			)
			(layer "F.CrtYd")
		)
		(fp_line
			(start 1.45 0.8)
			(end 1.45 -0.8)
			(stroke
				(width 0.2)
				(type solid)
			)
			(layer "F.CrtYd")
		)
		(fp_line
			(start -1.45 -0.8)
			(end 1.45 -0.8)
			(stroke
				(width 0.2)
				(type solid)
			)
			(layer "F.Fab")
		)
		(fp_line
			(start -1.45 0.8)
			(end -1.45 -0.8)
			(stroke
				(width 0.2)
				(type solid)
			)
			(layer "F.Fab")
		)
		(fp_line
			(start -1.45 0.8)
			(end 1.45 0.8)
			(stroke
				(width 0.2)
				(type solid)
			)
			(layer "F.Fab")
		)
		(fp_line
			(start -0.5 0)
			(end 0.5 0)
			(stroke
				(width 0.1)
				(type solid)
			)
			(layer "F.Fab")
		)
		(fp_line
			(start 0 0.5)
			(end 0 -0.5)
			(stroke
				(width 0.1)
				(type solid)
			)
			(layer "F.Fab")
		)
		(fp_line
			(start 1.45 0.8)
			(end 1.45 -0.8)
			(stroke
				(width 0.2)
				(type solid)
			)
			(layer "F.Fab")
		)
		(fp_text user "${REFERENCE}"
			(at -0.00001 0.10711 360)
			(unlocked yes)
			(layer "F.Fab")
			(effects
				(font
					(face "Arial")
					(size 0.63 0.63)
					(thickness 0.1)
				)
				(justify left bottom)
			)
		)
		(pad "1" smd rect
			(at -1.055 0)
			(size 0.59 0.45)
			(layers "F.Cu" "F.Mask" "F.Paste")
			(net "NetC3_1")
			(solder_mask_margin 0)
			(solder_paste_margin 0)
		)
		(pad "2" smd rect
			(at 1.055 0)
			(size 0.59 0.45)
			(layers "F.Cu" "F.Mask" "F.Paste")
			(net "P5V_PVDD")
			(solder_mask_margin 0)
			(solder_paste_margin 0)
		)
	)
	(footprint "GNSS:GNSS"
		(locked yes)
		(layer "F.Cu")
		(at 84.1536 70.8286)
		(property "Reference" "U9"
			(at -0.6275 -5.419055 0)
			(unlocked yes)
			(layer "F.SilkS")
			(effects
				(font
					(size 0.762 0.762)
					(thickness 0.2286)
				)
				(justify left bottom)
			)
		)
		(property "Value" "RCB-F9T"
			(at -9.8007 23.073645 0)
			(unlocked yes)
			(layer "F.SilkS")
			(hide yes)
			(effects
				(font
					(size 0.762 0.762)
					(thickness 0.2286)
				)
				(justify left bottom)
			)
		)
		(sheetname "GPS_IMU_SENSORS")
		(sheetfile "GPS_IMU_SENSORS.kicad_sch")
		(duplicate_pad_numbers_are_jumpers no)
		(fp_line
			(start -6.11 -20.47)
			(end 61.07 -20.47)
			(stroke
				(width 0.254)
				(type solid)
			)
			(layer "F.SilkS")
		)
		(fp_line
			(start -6.11 11.28)
			(end -6.11 -20.47)
			(stroke
				(width 0.254)
				(type solid)
			)
			(layer "F.SilkS")
		)
		(fp_line
			(start -6.11 11.28)
			(end 61.07 11.28)
			(stroke
				(width 0.254)
				(type solid)
			)
			(layer "F.SilkS")
		)
		(fp_line
			(start 61.07 11.28)
			(end 61.07 -20.47)
			(stroke
				(width 0.254)
				(type solid)
			)
			(layer "F.SilkS")
		)
		(pad "0" thru_hole circle
			(at 0 -2 270)
			(size 0 0)
			(drill 0.76)
			(layers "*.Cu" "*.Mask")
			(remove_unused_layers no)
			(thermal_bridge_angle 90)
		)
		(pad "0" thru_hole circle
			(at 0 2 270)
			(size 0 0)
			(drill 0.76)
			(layers "*.Cu" "*.Mask")
			(remove_unused_layers no)
			(thermal_bridge_angle 90)
		)
		(pad "1" smd rect
			(at -2.2225 3 270)
			(size 1.12 2.105)
			(layers "F.Cu" "F.Mask" "F.Paste")
			(net "+5.0V")
		)
		(pad "2" smd rect
			(at 2.2225 3 270)
			(size 1.12 2.105)
			(layers "F.Cu" "F.Mask" "F.Paste")
			(net "+3.3V")
		)
		(pad "3" smd rect
			(at -2.2225 1 270)
			(size 1.12 2.105)
			(layers "F.Cu" "F.Mask" "F.Paste")
			(net "GPS1_TX")
		)
		(pad "4" smd rect
			(at 2.2225 1 270)
			(size 1.12 2.105)
			(layers "F.Cu" "F.Mask" "F.Paste")
			(net "GPS1_RST")
		)
		(pad "5" smd rect
			(at -2.2225 -1 270)
			(size 1.12 2.105)
			(layers "F.Cu" "F.Mask" "F.Paste")
			(net "GPS1_RX")
		)
		(pad "6" smd rect
			(at 2.2225 -1 270)
			(size 1.12 2.105)
			(layers "F.Cu" "F.Mask" "F.Paste")
			(net "GPS1_TP1")
		)
		(pad "7" smd rect
			(at -2.2225 -3 270)
			(size 1.12 2.105)
			(layers "F.Cu" "F.Mask" "F.Paste")
			(net "GPS1_TP2")
		)
		(pad "8" smd rect
			(at 2.2225 -3 270)
			(size 1.12 2.105)
			(layers "F.Cu" "F.Mask" "F.Paste")
			(net "GND")
		)
	)
	(footprint "SA53:SA53_Header"
		(layer "F.Cu")
		(at 142.66107 112.99691 180)
		(property "Reference" "J31"
			(at 3.046095 -8.854759 180)
			(unlocked yes)
			(layer "F.SilkS")
			(effects
				(font
					(size 0.762 0.762)
					(thickness 0.2286)
				)
			)
		)
		(property "Value" "SA53_Header"
			(at 7.655515 4.548351 180)
			(unlocked yes)
			(layer "F.SilkS")
			(hide yes)
			(effects
				(font
					(size 0.762 0.762)
					(thickness 0.2286)
				)
			)
		)
		(sheetname "MAC")
		(sheetfile "MAC.kicad_sch")
		(duplicate_pad_numbers_are_jumpers no)
		(fp_circle
			(center 6.42 0.07199)
			(end 6.42 0.19899)
			(stroke
				(width 0.254)
				(type solid)
			)
			(fill no)
			(layer "F.SilkS")
		)
		(pad "1" smd rect
			(at 5 0.07199 270)
			(size 0.25 1.8)
			(layers "F.Cu" "F.Mask" "F.Paste")
			(net "MAC_PPS_IN1+")
		)
		(pad "2" smd rect
			(at 1 0.07199 270)
			(size 0.25 1.8)
			(layers "F.Cu" "F.Mask" "F.Paste")
			(net "MAC_USB+")
		)
		(pad "3" smd rect
			(at 5 -0.43601 270)
			(size 0.25 1.8)
			(layers "F.Cu" "F.Mask" "F.Paste")
			(net "MAC_PPS_IN1-")
		)
		(pad "4" smd rect
			(at 1 -0.43601 270)
			(size 0.25 1.8)
			(layers "F.Cu" "F.Mask" "F.Paste")
			(net "MAC_USB-")
		)
		(pad "5" smd rect
			(at 5 -0.94401 270)
			(size 0.25 1.8)
			(layers "F.Cu" "F.Mask" "F.Paste")
			(net "MAC_PPS_IN0+")
		)
		(pad "6" smd rect
			(at 1 -0.94401 270)
			(size 0.25 1.8)
			(layers "F.Cu" "F.Mask" "F.Paste")
			(net "MAC_USB_PWR")
		)
		(pad "7" smd rect
			(at 5 -1.45201 270)
			(size 0.25 1.8)
			(layers "F.Cu" "F.Mask" "F.Paste")
			(net "MAC_PPS_IN0-")
		)
		(pad "8" smd rect
			(at 1 -1.45201 270)
			(size 0.25 1.8)
			(layers "F.Cu" "F.Mask" "F.Paste")
			(net "GND")
		)
		(pad "9" smd rect
			(at 5 -1.96001 270)
			(size 0.25 1.8)
			(layers "F.Cu" "F.Mask" "F.Paste")
			(net "GND")
		)
		(pad "10" smd rect
			(at 1 -1.96001 270)
			(size 0.25 1.8)
			(layers "F.Cu" "F.Mask" "F.Paste")
		)
		(pad "11" smd rect
			(at 5 -2.46801 270)
			(size 0.25 1.8)
			(layers "F.Cu" "F.Mask" "F.Paste")
		)
		(pad "12" smd rect
			(at 1 -2.46801 270)
			(size 0.25 1.8)
			(layers "F.Cu" "F.Mask" "F.Paste")
		)
		(pad "13" smd rect
			(at 5 -2.97601 270)
			(size 0.25 1.8)
			(layers "F.Cu" "F.Mask" "F.Paste")
		)
		(pad "14" smd rect
			(at 1 -2.97601 270)
			(size 0.25 1.8)
			(layers "F.Cu" "F.Mask" "F.Paste")
		)
		(pad "15" smd rect
			(at 5 -3.48401 270)
			(size 0.25 1.8)
			(layers "F.Cu" "F.Mask" "F.Paste")
			(net "GND")
		)
		(pad "16" smd rect
			(at 1 -3.48401 270)
			(size 0.25 1.8)
			(layers "F.Cu" "F.Mask" "F.Paste")
		)
		(pad "17" smd rect
			(at 5 -3.99201 270)
			(size 0.25 1.8)
			(layers "F.Cu" "F.Mask" "F.Paste")
			(net "MAC_PPS_OUT+")
		)
		(pad "18" smd rect
			(at 1 -3.99201 270)
			(size 0.25 1.8)
			(layers "F.Cu" "F.Mask" "F.Paste")
		)
		(pad "19" smd rect
			(at 5 -4.50001 270)
			(size 0.25 1.8)
			(layers "F.Cu" "F.Mask" "F.Paste")
			(net "MAC_PPS_OUT-")
		)
		(pad "20" smd rect
			(at 1 -4.50001 270)
			(size 0.25 1.8)
			(layers "F.Cu" "F.Mask" "F.Paste")
			(net "MAC_ALARM")
		)
		(zone
			(layer "F.Cu")
			(hatch edge 0.5)
			(connect_pads
				(clearance 0)
			)
			(min_thickness 0.25)
			(keepout
				(tracks allowed)
				(vias allowed)
				(pads allowed)
				(copperpour not_allowed)
				(footprints allowed)
			)
			(placement
				(enabled no)
				(sheetname "")
			)
			(fill
				(thermal_gap 0.5)
				(thermal_bridge_width 0.5)
				(island_removal_mode 0)
			)
			(polygon
				(pts
					(xy 135.99358 120.0662) (xy 135.99359 110.0662) (xy 143.49359 110.0662) (xy 143.49358 120.0662)
				)
			)
		)
	)
	(footprint "Vault:RESC1608X55X25NL10T15"
		(layer "F.Cu")
		(at 77.5761 135.6162 180)
		(property "Reference" "R34"
			(at -0.2286 1.473079 0)
			(unlocked yes)
			(layer "F.SilkS")
			(effects
				(font
					(size 0.762 0.762)
					(thickness 0.2286)
				)
			)
		)
		(property "Value" "49.9R"
			(at -2.884671 3.186595 90)
			(unlocked yes)
			(layer "F.SilkS")
			(hide yes)
			(effects
				(font
					(size 0.762 0.762)
					(thickness 0.2286)
				)
			)
		)
		(sheetname "USER_IO")
		(sheetfile "USER_IO.kicad_sch")
		(duplicate_pad_numbers_are_jumpers no)
		(pad "1" smd rect
			(at -0.7 0 270)
			(size 0.9 0.7)
			(layers "F.Cu" "F.Mask" "F.Paste")
			(net "NetR34_1")
		)
		(pad "2" smd rect
			(at 0.7 0 270)
			(size 0.9 0.7)
			(layers "F.Cu" "F.Mask" "F.Paste")
			(net "NetAN4_1")
		)
	)
	(footprint "SamacSys:155124M173200"
		(layer "F.Cu")
		(at 58.4511 82.6662 90)
		(property "Reference" "D14"
			(at -4.7 -0.231655 90)
			(unlocked yes)
			(layer "F.SilkS")
			(effects
				(font
					(size 0.762 0.762)
					(thickness 0.2286)
				)
				(justify left bottom)
			)
		)
		(property "Value" "155124M173200"
			(at -4.043045 -0.5715 0)
			(unlocked yes)
			(layer "F.SilkS")
			(hide yes)
			(effects
				(font
					(size 0.762 0.762)
					(thickness 0.2286)
				)
				(justify left bottom)
			)
		)
		(sheetname "USER_IO_STATUS")
		(sheetfile "USER_IO_STATUS.kicad_sch")
		(duplicate_pad_numbers_are_jumpers no)
		(fp_line
			(start -0.8 0.5)
			(end 0.8 0.5)
			(stroke
				(width 0.1)
				(type solid)
			)
			(layer "F.SilkS")
		)
		(fp_arc
			(start -2 -0.1)
			(mid -1.95 -0.05)
			(end -2 0)
			(stroke
				(width 0.1)
				(type solid)
			)
			(layer "F.SilkS")
		)
		(fp_arc
			(start -2 0)
			(mid -2.05 -0.05)
			(end -2 -0.1)
			(stroke
				(width 0.1)
				(type solid)
			)
			(layer "F.SilkS")
		)
		(pad "1" smd rect
			(at -1.4 0 180)
			(size 0.9 0.6)
			(layers "F.Cu" "F.Mask" "F.Paste")
			(net "+3.3V")
		)
		(pad "2" smd rect
			(at -0.45 -0.325 90)
			(size 0.6 0.55)
			(layers "F.Cu" "F.Mask" "F.Paste")
			(net "NetD14_2")
		)
		(pad "3" smd rect
			(at 0.45 -0.325 90)
			(size 0.6 0.55)
			(layers "F.Cu" "F.Mask" "F.Paste")
			(net "NetD14_3")
		)
		(pad "4" smd rect
			(at 1.4 0 180)
			(size 0.9 0.6)
			(layers "F.Cu" "F.Mask" "F.Paste")
			(net "NetD14_4")
		)
	)
	(footprint "Vault:RESC1609X50X30NL10T20"
		(layer "F.Cu")
		(at 113.8761 84.8286 -90)
		(property "Reference" "R12"
			(at 2.2714 -0.026931 90)
			(unlocked yes)
			(layer "F.SilkS")
			(effects
				(font
					(size 0.762 0.762)
					(thickness 0.2286)
				)
			)
		)
		(property "Value" "110R"
			(at -2.884671 2.24708 180)
			(unlocked yes)
			(layer "F.SilkS")
			(hide yes)
			(effects
				(font
					(size 0.762 0.762)
					(thickness 0.2286)
				)
			)
		)
		(sheetname "MAC")
		(sheetfile "MAC.kicad_sch")
		(duplicate_pad_numbers_are_jumpers no)
		(pad "1" smd rect
			(at -0.625 0)
			(size 0.95 0.8)
			(layers "F.Cu" "F.Mask" "F.Paste")
			(net "MAC_PPS_OUT-")
		)
		(pad "2" smd rect
			(at 0.625 0)
			(size 0.95 0.8)
			(layers "F.Cu" "F.Mask" "F.Paste")
			(net "MAC_PPS_OUT+")
		)
	)
	(footprint "Vault:RESC1005X40X25NL05T05"
		(layer "F.Cu")
		(at 211.3261 75.6162)
		(property "Reference" "R102"
			(at 0.1286 -0.973079 0)
			(unlocked yes)
			(layer "F.SilkS")
			(effects
				(font
					(size 0.762 0.762)
					(thickness 0.2286)
				)
			)
		)
		(property "Value" "DNI_27_1%_0402"
			(at -2.732271 10.296375 270)
			(unlocked yes)
			(layer "F.SilkS")
			(hide yes)
			(effects
				(font
					(size 0.762 0.762)
					(thickness 0.2286)
				)
			)
		)
		(sheetname "USBUart_DipSelects")
		(sheetfile "USBUart_DipSelects.kicad_sch")
		(duplicate_pad_numbers_are_jumpers no)
		(pad "1" smd rect
			(at -0.45 0 90)
			(size 0.55 0.55)
			(layers "F.Cu" "F.Mask" "F.Paste")
			(net "GPS2_TX_FPGA")
		)
		(pad "2" smd rect
			(at 0.45 0 90)
			(size 0.55 0.55)
			(layers "F.Cu" "F.Mask" "F.Paste")
			(net "GPS2_TX")
		)
	)
	(footprint "Vault:RESC3116X65X50ML20T20"
		(layer "F.Cu")
		(at 155.9123 86.8162)
		(property "Reference" "R45"
			(at 4.0286 0.026931 0)
			(unlocked yes)
			(layer "F.SilkS")
			(effects
				(font
					(size 0.762 0.762)
					(thickness 0.2286)
				)
			)
		)
		(property "Value" "0_5%_1206"
			(at 4.35396 3.291071 0)
			(unlocked yes)
			(layer "F.SilkS")
			(hide yes)
			(effects
				(font
					(size 0.762 0.762)
					(thickness 0.2286)
				)
			)
		)
		(sheetname "MAC")
		(sheetfile "MAC.kicad_sch")
		(duplicate_pad_numbers_are_jumpers no)
		(fp_line
			(start -0.35 -0.85)
			(end 0.35 -0.85)
			(stroke
				(width 0.2)
				(type solid)
			)
			(layer "F.SilkS")
		)
		(fp_line
			(start -0.35 0.85)
			(end 0.35 0.85)
			(stroke
				(width 0.2)
				(type solid)
			)
			(layer "F.SilkS")
		)
		(pad "1" smd rect
			(at -1.475 0 90)
			(size 1.9 1.45)
			(layers "F.Cu" "F.Mask" "F.Paste")
			(net "MAC_VCC")
		)
		(pad "2" smd rect
			(at 1.475 0 90)
			(size 1.9 1.45)
			(layers "F.Cu" "F.Mask" "F.Paste")
			(net "+5.0V")
		)
	)
	(footprint "Passives:FUSM1608X60N"
		(layer "F.Cu")
		(at 214.2261 95.6162 180)
		(property "Reference" "F1"
			(at 1.2 0.706655 0)
			(unlocked yes)
			(layer "F.SilkS")
			(effects
				(font
					(size 0.762 0.762)
					(thickness 0.2286)
				)
				(justify left bottom)
			)
		)
		(property "Value" "FUSE_0603_5.00A"
			(at 2.1929 -4.987045 0)
			(unlocked yes)
			(layer "F.SilkS")
			(hide yes)
			(effects
				(font
					(size 0.762 0.762)
					(thickness 0.2286)
				)
				(justify left bottom)
			)
		)
		(sheetname "POWER")
		(sheetfile "POWER.kicad_sch")
		(duplicate_pad_numbers_are_jumpers no)
		(fp_line
			(start 0 -0.5)
			(end 0 0.5)
			(stroke
				(width 0.1524)
				(type solid)
			)
			(layer "F.SilkS")
		)
		(pad "1" smd rect
			(at -0.69 0 270)
			(size 1 0.72)
			(layers "F.Cu" "F.Mask" "F.Paste")
			(net "NetD12_1")
		)
		(pad "2" smd rect
			(at 0.69 0 270)
			(size 1 0.72)
			(layers "F.Cu" "F.Mask" "F.Paste")
			(net "+12V_SENS")
		)
	)
	(footprint "Vault:FP-0402-L_1_0_0_05-W_0_5-IPC_C"
		(layer "F.Cu")
		(at 189.8261 83.0162)
		(property "Reference" "C65"
			(at 0.1286 -1.873079 0)
			(unlocked yes)
			(layer "F.SilkS")
			(effects
				(font
					(size 0.762 0.762)
					(thickness 0.2286)
				)
			)
		)
		(property "Value" "1uF_0402"
			(at -2.795791 1.459885 270)
			(unlocked yes)
			(layer "F.SilkS")
			(hide yes)
			(effects
				(font
					(size 0.762 0.762)
					(thickness 0.2286)
				)
			)
		)
		(sheetname "GPS_IMU_SENSORS")
		(sheetfile "GPS_IMU_SENSORS.kicad_sch")
		(duplicate_pad_numbers_are_jumpers no)
		(fp_line
			(start -0.63624 -0.675)
			(end 0.63624 -0.675)
			(stroke
				(width 0.2)
				(type solid)
			)
			(layer "F.SilkS")
		)
		(fp_line
			(start -0.63624 0.675)
			(end 0.63624 0.675)
			(stroke
				(width 0.2)
				(type solid)
			)
			(layer "F.SilkS")
		)
		(fp_line
			(start -0.73624 -0.375)
			(end 0.73624 -0.375)
			(stroke
				(width 0.2)
				(type solid)
			)
			(layer "F.CrtYd")
		)
		(fp_line
			(start -0.73624 0.375)
			(end -0.73624 -0.375)
			(stroke
				(width 0.2)
				(type solid)
			)
			(layer "F.CrtYd")
		)
		(fp_line
			(start -0.73624 0.375)
			(end 0.73624 0.375)
			(stroke
				(width 0.2)
				(type solid)
			)
			(layer "F.CrtYd")
		)
		(fp_line
			(start 0.73624 0.375)
			(end 0.73624 -0.375)
			(stroke
				(width 0.2)
				(type solid)
			)
			(layer "F.CrtYd")
		)
		(fp_line
			(start -0.73624 -0.375)
			(end 0.73624 -0.375)
			(stroke
				(width 0.2)
				(type solid)
			)
			(layer "F.Fab")
		)
		(fp_line
			(start -0.73624 0.375)
			(end -0.73624 -0.375)
			(stroke
				(width 0.2)
				(type solid)
			)
			(layer "F.Fab")
		)
		(fp_line
			(start -0.73624 0.375)
			(end 0.73624 0.375)
			(stroke
				(width 0.2)
				(type solid)
			)
			(layer "F.Fab")
		)
		(fp_line
			(start -0.5 0)
			(end 0.5 0)
			(stroke
				(width 0.1)
				(type solid)
			)
			(layer "F.Fab")
		)
		(fp_line
			(start 0 0.5)
			(end 0 -0.5)
			(stroke
				(width 0.1)
				(type solid)
			)
			(layer "F.Fab")
		)
		(fp_line
			(start 0.73624 0.375)
			(end 0.73624 -0.375)
			(stroke
				(width 0.2)
				(type solid)
			)
			(layer "F.Fab")
		)
		(fp_text user "${REFERENCE}"
			(at -0.00001 0.09602 360)
			(unlocked yes)
			(layer "F.Fab")
			(effects
				(font
					(face "Arial")
					(size 0.63 0.63)
					(thickness 0.1)
				)
				(justify left bottom)
			)
		)
		(pad "1" smd rect
			(at -0.37856 0)
			(size 0.51535 0.47247)
			(layers "F.Cu" "F.Mask" "F.Paste")
			(net "NetC65_1")
			(solder_mask_margin 0)
			(solder_paste_margin 0)
		)
		(pad "2" smd rect
			(at 0.37856 0)
			(size 0.51535 0.47247)
			(layers "F.Cu" "F.Mask" "F.Paste")
			(net "GND")
			(solder_mask_margin 0)
			(solder_paste_margin 0)
		)
	)
	(footprint "Vault:RESC1005X40X25LL05T05"
		(layer "F.Cu")
		(at 171.0261 101.8162)
		(property "Reference" "R49"
			(at 2.4286 0.226931 0)
			(unlocked yes)
			(layer "F.SilkS")
			(effects
				(font
					(size 0.762 0.762)
					(thickness 0.2286)
				)
			)
		)
		(property "Value" "0_1%_0402"
			(at -2.579871 6.66536 270)
			(unlocked yes)
			(layer "F.SilkS")
			(hide yes)
			(effects
				(font
					(size 0.762 0.762)
					(thickness 0.2286)
				)
			)
		)
		(sheetname "FPGA")
		(sheetfile "FPGA.kicad_sch")
		(duplicate_pad_numbers_are_jumpers no)
		(pad "1" smd rect
			(at -0.4 0 90)
			(size 0.45 0.45)
			(layers "F.Cu" "F.Mask" "F.Paste")
			(net "MAC_FREQ_CTRL")
		)
		(pad "2" smd rect
			(at 0.4 0 90)
			(size 0.45 0.45)
			(layers "F.Cu" "F.Mask" "F.Paste")
			(net "NetJ35_33")
		)
	)
	(footprint "Vault:RESC1608X55X30NL15T15"
		(layer "F.Cu")
		(at 82.1261 139.6162 -90)
		(property "Reference" "R32"
			(at 2.7714 -0.026921 90)
			(unlocked yes)
			(layer "F.SilkS")
			(effects
				(font
					(size 0.762 0.762)
					(thickness 0.2286)
				)
			)
		)
		(property "Value" "4.7K"
			(at -3.087871 2.37404 180)
			(unlocked yes)
			(layer "F.SilkS")
			(hide yes)
			(effects
				(font
					(size 0.762 0.762)
					(thickness 0.2286)
				)
			)
		)
		(sheetname "USER_IO")
		(sheetfile "USER_IO.kicad_sch")
		(duplicate_pad_numbers_are_jumpers no)
		(pad "1" smd rect
			(at -0.75 0)
			(size 0.95 0.95)
			(layers "F.Cu" "F.Mask" "F.Paste")
			(net "ANT4_IO_IN")
		)
		(pad "2" smd rect
			(at 0.75 0)
			(size 0.95 0.95)
			(layers "F.Cu" "F.Mask" "F.Paste")
			(net "+3.3V")
		)
	)
	(footprint "Vault:RESC1608X55X30NL15T15"
		(layer "F.Cu")
		(at 101.6261 82.9162)
		(property "Reference" "R26"
			(at 3.14763 0.055781 0)
			(unlocked yes)
			(layer "F.SilkS")
			(effects
				(font
					(size 0.762 0.762)
					(thickness 0.2286)
				)
			)
		)
		(property "Value" "4.7K"
			(at -3.087881 2.37404 270)
			(unlocked yes)
			(layer "F.SilkS")
			(hide yes)
			(effects
				(font
					(size 0.762 0.762)
					(thickness 0.2286)
				)
			)
		)
		(sheetname "GPS_IMU_SENSORS")
		(sheetfile "GPS_IMU_SENSORS.kicad_sch")
		(duplicate_pad_numbers_are_jumpers no)
		(pad "1" smd rect
			(at -0.75 0 90)
			(size 0.95 0.95)
			(layers "F.Cu" "F.Mask" "F.Paste")
			(net "SDA")
		)
		(pad "2" smd rect
			(at 0.75 0 90)
			(size 0.95 0.95)
			(layers "F.Cu" "F.Mask" "F.Paste")
			(net "+3.3V")
		)
	)
	(footprint "Vault:FP-0402-L_1_0_1-W_0_5_0_1-IPC_C"
		(layer "F.Cu")
		(at 226.1261 125.7162 180)
		(property "Reference" "C83"
			(at 1.6714 -0.026931 0)
			(unlocked yes)
			(layer "F.SilkS")
			(effects
				(font
					(size 0.762 0.762)
					(thickness 0.2286)
				)
			)
		)
		(property "Value" "0.1uF_25V_0402"
			(at -2.465551 9.839215 90)
			(unlocked yes)
			(layer "F.SilkS")
			(hide yes)
			(effects
				(font
					(size 0.762 0.762)
					(thickness 0.2286)
				)
			)
		)
		(sheetname "POWER")
		(sheetfile "POWER.kicad_sch")
		(duplicate_pad_numbers_are_jumpers no)
		(fp_line
			(start 0.65607 0.7)
			(end -0.65607 0.7)
			(stroke
				(width 0.2)
				(type solid)
			)
			(layer "F.SilkS")
		)
		(fp_line
			(start 0.65607 -0.7)
			(end -0.65607 -0.7)
			(stroke
				(width 0.2)
				(type solid)
			)
			(layer "F.SilkS")
		)
		(fp_line
			(start 0.75607 0.4)
			(end -0.75606 0.4)
			(stroke
				(width 0.2)
				(type solid)
			)
			(layer "F.CrtYd")
		)
		(fp_line
			(start 0.75607 -0.4)
			(end 0.75607 0.4)
			(stroke
				(width 0.2)
				(type solid)
			)
			(layer "F.CrtYd")
		)
		(fp_line
			(start 0.75607 -0.4)
			(end -0.75606 -0.4)
			(stroke
				(width 0.2)
				(type solid)
			)
			(layer "F.CrtYd")
		)
		(fp_line
			(start -0.75606 -0.4)
			(end -0.75606 0.4)
			(stroke
				(width 0.2)
				(type solid)
			)
			(layer "F.CrtYd")
		)
		(fp_line
			(start 0.75607 0.4)
			(end -0.75606 0.4)
			(stroke
				(width 0.2)
				(type solid)
			)
			(layer "F.Fab")
		)
		(fp_line
			(start 0.75607 -0.4)
			(end 0.75607 0.4)
			(stroke
				(width 0.2)
				(type solid)
			)
			(layer "F.Fab")
		)
		(fp_line
			(start 0.75607 -0.4)
			(end -0.75606 -0.4)
			(stroke
				(width 0.2)
				(type solid)
			)
			(layer "F.Fab")
		)
		(fp_line
			(start 0.5 0)
			(end -0.5 0)
			(stroke
				(width 0.1)
				(type solid)
			)
			(layer "F.Fab")
		)
		(fp_line
			(start 0 -0.5)
			(end 0 0.5)
			(stroke
				(width 0.1)
				(type solid)
			)
			(layer "F.Fab")
		)
		(fp_line
			(start -0.75606 -0.4)
			(end -0.75606 0.4)
			(stroke
				(width 0.2)
				(type solid)
			)
			(layer "F.Fab")
		)
		(fp_text user "${REFERENCE}"
			(at -0.00001 0.09601 180)
			(unlocked yes)
			(layer "F.Fab")
			(effects
				(font
					(face "Arial")
					(size 0.63 0.63)
					(thickness 0.1)
				)
				(justify left bottom)
			)
		)
		(pad "1" smd rect
			(at -0.36553 0 180)
			(size 0.58106 0.51213)
			(layers "F.Cu" "F.Mask" "F.Paste")
			(net "+3.3V")
			(solder_mask_margin 0)
			(solder_paste_margin 0)
		)
		(pad "2" smd rect
			(at 0.36554 0 180)
			(size 0.58106 0.51213)
			(layers "F.Cu" "F.Mask" "F.Paste")
			(net "GND")
			(solder_mask_margin 0)
			(solder_paste_margin 0)
		)
	)
	(footprint "Vault:FP-GRM31C-0_2-e0_3_0_8-IPC_C"
		(layer "F.Cu")
		(at 216.9261 119.6162 90)
		(property "Reference" "C76"
			(at 0.46924 -2.601729 90)
			(unlocked yes)
			(layer "F.SilkS")
			(effects
				(font
					(size 0.762 0.762)
					(thickness 0.2286)
				)
			)
		)
		(property "Value" "4.7uF_50V_1206"
			(at 8.594615 2.719551 90)
			(unlocked yes)
			(layer "F.SilkS")
			(hide yes)
			(effects
				(font
					(size 0.762 0.762)
					(thickness 0.2286)
				)
			)
		)
		(sheetname "POWER")
		(sheetfile "POWER.kicad_sch")
		(duplicate_pad_numbers_are_jumpers no)
		(fp_line
			(start -0.39847 -0.9)
			(end 0.39847 -0.9)
			(stroke
				(width 0.2)
				(type solid)
			)
			(layer "F.SilkS")
		)
		(fp_line
			(start -0.39847 0.9)
			(end 0.39847 0.9)
			(stroke
				(width 0.2)
				(type solid)
			)
			(layer "F.SilkS")
		)
		(fp_line
			(start 1.9531 -1)
			(end 1.9531 1)
			(stroke
				(width 0.2)
				(type solid)
			)
			(layer "F.CrtYd")
		)
		(fp_line
			(start -1.9531 -1)
			(end 1.9531 -1)
			(stroke
				(width 0.2)
				(type solid)
			)
			(layer "F.CrtYd")
		)
		(fp_line
			(start -1.9531 -1)
			(end -1.9531 1)
			(stroke
				(width 0.2)
				(type solid)
			)
			(layer "F.CrtYd")
		)
		(fp_line
			(start -1.9531 1)
			(end 1.9531 1)
			(stroke
				(width 0.2)
				(type solid)
			)
			(layer "F.CrtYd")
		)
		(fp_line
			(start 1.9531 -1)
			(end 1.9531 1)
			(stroke
				(width 0.2)
				(type solid)
			)
			(layer "F.Fab")
		)
		(fp_line
			(start -1.9531 -1)
			(end 1.9531 -1)
			(stroke
				(width 0.2)
				(type solid)
			)
			(layer "F.Fab")
		)
		(fp_line
			(start -1.9531 -1)
			(end -1.9531 1)
			(stroke
				(width 0.2)
				(type solid)
			)
			(layer "F.Fab")
		)
		(fp_line
			(start 0 -0.5)
			(end 0 0.5)
			(stroke
				(width 0.1)
				(type solid)
			)
			(layer "F.Fab")
		)
		(fp_line
			(start -0.5 0)
			(end 0.5 0)
			(stroke
				(width 0.1)
				(type solid)
			)
			(layer "F.Fab")
		)
		(fp_line
			(start -1.9531 1)
			(end 1.9531 1)
			(stroke
				(width 0.2)
				(type solid)
			)
			(layer "F.Fab")
		)
		(fp_text user "${REFERENCE}"
			(at -0.00002 0.09601 90)
			(unlocked yes)
			(layer "F.Fab")
			(effects
				(font
					(face "Arial")
					(size 0.63 0.63)
					(thickness 0.1)
				)
				(justify left bottom)
			)
		)
		(pad "1" smd rect
			(at -1.27578 0 90)
			(size 1.15464 1.7062)
			(layers "F.Cu" "F.Mask" "F.Paste")
			(net "+12V")
			(solder_mask_margin 0)
			(solder_paste_margin 0)
		)
		(pad "2" smd rect
			(at 1.27578 0 90)
			(size 1.15464 1.7062)
			(layers "F.Cu" "F.Mask" "F.Paste")
			(net "GND")
			(solder_mask_margin 0)
			(solder_paste_margin 0)
		)
	)
	(footprint "Vault:FP-STPS5L60S-MFG"
		(layer "F.Cu")
		(at 221.9261 97.9162)
		(property "Reference" "D19"
			(at 0.2286 -3.773069 0)
			(unlocked yes)
			(layer "F.SilkS")
			(effects
				(font
					(size 0.762 0.762)
					(thickness 0.2286)
				)
			)
		)
		(property "Value" "STPS5L60S"
			(at -6.491471 3.76976 270)
			(unlocked yes)
			(layer "F.SilkS")
			(hide yes)
			(effects
				(font
					(size 0.762 0.762)
					(thickness 0.2286)
				)
			)
		)
		(sheetname "POWER")
		(sheetfile "POWER.kicad_sch")
		(duplicate_pad_numbers_are_jumpers no)
		(fp_line
			(start -3.575 -3.125)
			(end 3.575 -3.125)
			(stroke
				(width 0.2)
				(type solid)
			)
			(layer "F.SilkS")
		)
		(fp_line
			(start -3.575 -2.025)
			(end -3.575 -3.125)
			(stroke
				(width 0.2)
				(type solid)
			)
			(layer "F.SilkS")
		)
		(fp_line
			(start -3.575 3.125)
			(end -3.575 2.025)
			(stroke
				(width 0.2)
				(type solid)
			)
			(layer "F.SilkS")
		)
		(fp_line
			(start -3.575 3.125)
			(end 3.575 3.125)
			(stroke
				(width 0.2)
				(type solid)
			)
			(layer "F.SilkS")
		)
		(fp_line
			(start 3.575 -2.025)
			(end 3.575 -3.125)
			(stroke
				(width 0.2)
				(type solid)
			)
			(layer "F.SilkS")
		)
		(fp_line
			(start 3.575 3.125)
			(end 3.575 2.025)
			(stroke
				(width 0.2)
				(type solid)
			)
			(layer "F.SilkS")
		)
		(fp_circle
			(center -4.7 -0.025)
			(end -4.7 -0.15)
			(stroke
				(width 0.25)
				(type solid)
			)
			(fill no)
			(layer "F.SilkS")
		)
		(fp_line
			(start -4.195 -3.225)
			(end 4.195 -3.225)
			(stroke
				(width 0.2)
				(type solid)
			)
			(layer "F.CrtYd")
		)
		(fp_line
			(start -4.195 3.225)
			(end -4.195 -3.225)
			(stroke
				(width 0.2)
				(type solid)
			)
			(layer "F.CrtYd")
		)
		(fp_line
			(start -4.195 3.225)
			(end 4.195 3.225)
			(stroke
				(width 0.2)
				(type solid)
			)
			(layer "F.CrtYd")
		)
		(fp_line
			(start 4.195 3.225)
			(end 4.195 -3.225)
			(stroke
				(width 0.2)
				(type solid)
			)
			(layer "F.CrtYd")
		)
		(fp_line
			(start -4.195 -3.225)
			(end 4.195 -3.225)
			(stroke
				(width 0.2)
				(type solid)
			)
			(layer "F.Fab")
		)
		(fp_line
			(start -4.195 3.225)
			(end -4.195 -3.225)
			(stroke
				(width 0.2)
				(type solid)
			)
			(layer "F.Fab")
		)
		(fp_line
			(start -4.195 3.225)
			(end 4.195 3.225)
			(stroke
				(width 0.2)
				(type solid)
			)
			(layer "F.Fab")
		)
		(fp_line
			(start -0.5 0)
			(end 0.5 0)
			(stroke
				(width 0.1)
				(type solid)
			)
			(layer "F.Fab")
		)
		(fp_line
			(start 0 0.5)
			(end 0 -0.5)
			(stroke
				(width 0.1)
				(type solid)
			)
			(layer "F.Fab")
		)
		(fp_line
			(start 4.195 3.225)
			(end 4.195 -3.225)
			(stroke
				(width 0.2)
				(type solid)
			)
			(layer "F.Fab")
		)
		(fp_text user "${REFERENCE}"
			(at -0.00001 0.09602 360)
			(unlocked yes)
			(layer "F.Fab")
			(effects
				(font
					(face "Arial")
					(size 0.63 0.63)
					(thickness 0.1)
				)
				(justify left bottom)
			)
		)
		(pad "1" smd rect
			(at -3.325 0)
			(size 1.54 3.14)
			(layers "F.Cu" "F.Mask" "F.Paste")
			(net "NetD12_1")
			(solder_mask_margin 0)
			(solder_paste_margin 0)
		)
		(pad "2" smd rect
			(at 3.325 0)
			(size 1.54 3.14)
			(layers "F.Cu" "F.Mask" "F.Paste")
			(net "+12V_PCIE")
			(solder_mask_margin 0)
			(solder_paste_margin 0)
		)
	)
	(footprint "SA53:SolderSocket"
		(layer "F.Cu")
		(at 99.3261 94.9162 90)
		(property "Reference" "SKT2"
			(at -0.226921 -6.7714 0)
			(unlocked yes)
			(layer "F.SilkS")
			(effects
				(font
					(size 0.762 0.762)
					(thickness 0.2286)
				)
			)
		)
		(property "Value" "0332-0-43-80-18-27-10-0"
			(at -2.910071 16.1362 0)
			(unlocked yes)
			(layer "F.SilkS")
			(hide yes)
			(effects
				(font
					(size 0.762 0.762)
					(thickness 0.2286)
				)
			)
		)
		(sheetname "MAC")
		(sheetfile "MAC.kicad_sch")
		(duplicate_pad_numbers_are_jumpers no)
		(pad "1" thru_hole circle
			(at 0 0 90)
			(size 2.54 2.54)
			(drill 2.0066)
			(layers "*.Cu" "*.Mask")
			(remove_unused_layers no)
			(net "MAC_FREQ_CTRL")
			(thermal_bridge_angle 90)
		)
	)
	(footprint "Connectors:SAMTEC_HTST-105-01-L-DV-A"
		(layer "F.Cu")
		(at 212.8061 138.9462)
		(property "Reference" "U5"
			(at -10.386655 -2.43 90)
			(unlocked yes)
			(layer "F.SilkS")
			(effects
				(font
					(size 0.762 0.762)
					(thickness 0.2286)
				)
				(justify left bottom)
			)
		)
		(property "Value" "HTST-105-01-L-DV-A"
			(at -0.5217 18.090245 0)
			(unlocked yes)
			(layer "F.SilkS")
			(hide yes)
			(effects
				(font
					(size 0.762 0.762)
					(thickness 0.2286)
				)
				(justify left bottom)
			)
		)
		(sheetname "PCIe_JTAG")
		(sheetfile "PCIe_JTAG.kicad_sch")
		(duplicate_pad_numbers_are_jumpers no)
		(fp_line
			(start -10.16 -4.635)
			(end -6.065 -4.635)
			(stroke
				(width 0.2)
				(type solid)
			)
			(layer "F.SilkS")
		)
		(fp_line
			(start -10.16 4.635)
			(end -10.16 -4.635)
			(stroke
				(width 0.2)
				(type solid)
			)
			(layer "F.SilkS")
		)
		(fp_line
			(start -10.16 4.635)
			(end -6.065 4.635)
			(stroke
				(width 0.2)
				(type solid)
			)
			(layer "F.SilkS")
		)
		(fp_line
			(start 6.065 -4.635)
			(end 10.16 -4.635)
			(stroke
				(width 0.2)
				(type solid)
			)
			(layer "F.SilkS")
		)
		(fp_line
			(start 6.065 4.635)
			(end 10.16 4.635)
			(stroke
				(width 0.2)
				(type solid)
			)
			(layer "F.SilkS")
		)
		(fp_line
			(start 10.16 4.635)
			(end 10.16 -4.635)
			(stroke
				(width 0.2)
				(type solid)
			)
			(layer "F.SilkS")
		)
		(fp_circle
			(center -7.62 5.715)
			(end -7.62 5.08)
			(stroke
				(width 0.2)
				(type solid)
			)
			(fill no)
			(layer "F.SilkS")
		)
		(pad "" np_thru_hole circle
			(at -3.81 0)
			(size 1.676 1.676)
			(drill 1.676)
			(layers "*.Cu" "*.Mask")
			(thermal_bridge_angle 90)
		)
		(pad "" np_thru_hole circle
			(at 3.81 0)
			(size 1.676 1.676)
			(drill 1.676)
			(layers "*.Cu" "*.Mask")
			(thermal_bridge_angle 90)
		)
		(pad "1" smd rect
			(at -5.08 3.43)
			(size 1.27 5.08)
			(layers "F.Cu" "F.Mask" "F.Paste")
			(net "NetR18_2")
		)
		(pad "2" smd rect
			(at -5.08 -3.43)
			(size 1.27 5.08)
			(layers "F.Cu" "F.Mask" "F.Paste")
			(net "GND")
		)
		(pad "3" smd rect
			(at -2.54 3.43)
			(size 1.27 5.08)
			(layers "F.Cu" "F.Mask" "F.Paste")
			(net "NetR19_2")
		)
		(pad "4" smd rect
			(at -2.54 -3.43)
			(size 1.27 5.08)
			(layers "F.Cu" "F.Mask" "F.Paste")
			(net "+3.3V")
		)
		(pad "5" smd rect
			(at 0 3.43)
			(size 1.27 5.08)
			(layers "F.Cu" "F.Mask" "F.Paste")
			(net "NetR20_2")
		)
		(pad "6" smd rect
			(at 0 -3.43)
			(size 1.27 5.08)
			(layers "F.Cu" "F.Mask" "F.Paste")
			(net "+3.3V")
		)
		(pad "7" smd rect
			(at 2.54 3.43)
			(size 1.27 5.08)
			(layers "F.Cu" "F.Mask" "F.Paste")
		)
		(pad "8" smd rect
			(at 2.54 -3.43)
			(size 1.27 5.08)
			(layers "F.Cu" "F.Mask" "F.Paste")
		)
		(pad "9" smd rect
			(at 5.08 3.43)
			(size 1.27 5.08)
			(layers "F.Cu" "F.Mask" "F.Paste")
			(net "NetR21_2")
		)
		(pad "10" smd rect
			(at 5.08 -3.43)
			(size 1.27 5.08)
			(layers "F.Cu" "F.Mask" "F.Paste")
			(net "GND")
		)
	)
	(footprint "Vault:RESC1608X55X25LL10T15"
		(layer "F.Cu")
		(at 130.9261 87.9162)
		(property "Reference" "R11"
			(at 0.128605 1.126931 0)
			(unlocked yes)
			(layer "F.SilkS")
			(effects
				(font
					(size 0.762 0.762)
					(thickness 0.2286)
				)
			)
		)
		(property "Value" "4.7K"
			(at -2.630671 2.57724 270)
			(unlocked yes)
			(layer "F.SilkS")
			(hide yes)
			(effects
				(font
					(size 0.762 0.762)
					(thickness 0.2286)
				)
			)
		)
		(sheetname "MAC")
		(sheetfile "MAC.kicad_sch")
		(duplicate_pad_numbers_are_jumpers no)
		(pad "1" smd rect
			(at -0.65 0 90)
			(size 0.8 0.6)
			(layers "F.Cu" "F.Mask" "F.Paste")
			(net "GND")
		)
		(pad "2" smd rect
			(at 0.65 0 90)
			(size 0.8 0.6)
			(layers "F.Cu" "F.Mask" "F.Paste")
			(net "FPGA_MAC_PPS_DIFF_IN0")
		)
	)
	(footprint "Vault:CAPC1608X87X45ML20T05"
		(layer "F.Cu")
		(at 88.1261 79.3286 90)
		(property "Reference" "C61"
			(at -1.25 3.593345 90)
			(unlocked yes)
			(layer "F.SilkS")
			(effects
				(font
					(size 0.762 0.762)
					(thickness 0.2286)
				)
				(justify left bottom)
			)
		)
		(property "Value" "0.1uF"
			(at -3.382645 -0.2921 0)
			(unlocked yes)
			(layer "F.SilkS")
			(hide yes)
			(effects
				(font
					(size 0.762 0.762)
					(thickness 0.2286)
				)
				(justify left bottom)
			)
		)
		(sheetname "GPS_IMU_SENSORS")
		(sheetfile "GPS_IMU_SENSORS.kicad_sch")
		(duplicate_pad_numbers_are_jumpers no)
		(pad "1" smd rect
			(at -0.7 0 180)
			(size 1.1 1.05)
			(layers "F.Cu" "F.Mask" "F.Paste")
			(net "GND")
		)
		(pad "2" smd rect
			(at 0.7 0 180)
			(size 1.1 1.05)
			(layers "F.Cu" "F.Mask" "F.Paste")
			(net "+5.0V")
		)
	)
	(footprint "Vault:FP-MK212BG-MFG"
		(layer "F.Cu")
		(at 218.8761 60.5786 180)
		(property "Reference" "C34"
			(at 3.0214 -0.026921 0)
			(unlocked yes)
			(layer "F.SilkS")
			(effects
				(font
					(size 0.762 0.762)
					(thickness 0.2286)
				)
			)
		)
		(property "Value" "10uF"
			(at -3.240271 2.22164 90)
			(unlocked yes)
			(layer "F.SilkS")
			(hide yes)
			(effects
				(font
					(size 0.762 0.762)
					(thickness 0.2286)
				)
			)
		)
		(sheetname "GPS_IMU_SENSORS")
		(sheetfile "GPS_IMU_SENSORS.kicad_sch")
		(duplicate_pad_numbers_are_jumpers no)
		(fp_line
			(start 0.125 0.725)
			(end -0.125 0.725)
			(stroke
				(width 0.2)
				(type solid)
			)
			(layer "F.SilkS")
		)
		(fp_line
			(start 0.125 -0.725)
			(end -0.125 -0.725)
			(stroke
				(width 0.2)
				(type solid)
			)
			(layer "F.SilkS")
		)
		(fp_line
			(start 1.6 0.825)
			(end -1.6 0.825)
			(stroke
				(width 0.2)
				(type solid)
			)
			(layer "F.CrtYd")
		)
		(fp_line
			(start 1.6 -0.825)
			(end 1.6 0.825)
			(stroke
				(width 0.2)
				(type solid)
			)
			(layer "F.CrtYd")
		)
		(fp_line
			(start 1.6 -0.825)
			(end -1.6 -0.825)
			(stroke
				(width 0.2)
				(type solid)
			)
			(layer "F.CrtYd")
		)
		(fp_line
			(start -1.6 -0.825)
			(end -1.6 0.825)
			(stroke
				(width 0.2)
				(type solid)
			)
			(layer "F.CrtYd")
		)
		(fp_line
			(start 1.6 0.825)
			(end -1.6 0.825)
			(stroke
				(width 0.2)
				(type solid)
			)
			(layer "F.Fab")
		)
		(fp_line
			(start 1.6 -0.825)
			(end 1.6 0.825)
			(stroke
				(width 0.2)
				(type solid)
			)
			(layer "F.Fab")
		)
		(fp_line
			(start 1.6 -0.825)
			(end -1.6 -0.825)
			(stroke
				(width 0.2)
				(type solid)
			)
			(layer "F.Fab")
		)
		(fp_line
			(start 0.5 0)
			(end -0.5 0)
			(stroke
				(width 0.1)
				(type solid)
			)
			(layer "F.Fab")
		)
		(fp_line
			(start 0 -0.5)
			(end 0 0.5)
			(stroke
				(width 0.1)
				(type solid)
			)
			(layer "F.Fab")
		)
		(fp_line
			(start -1.6 -0.825)
			(end -1.6 0.825)
			(stroke
				(width 0.2)
				(type solid)
			)
			(layer "F.Fab")
		)
		(fp_text user "${REFERENCE}"
			(at -0.00001 0.09602 180)
			(unlocked yes)
			(layer "F.Fab")
			(effects
				(font
					(face "Arial")
					(size 0.63 0.63)
					(thickness 0.1)
				)
				(justify left bottom)
			)
		)
		(pad "1" smd rect
			(at -1 0 180)
			(size 1 1.25)
			(layers "F.Cu" "F.Mask" "F.Paste")
			(net "+3.3V")
			(solder_mask_margin 0)
			(solder_paste_margin 0)
		)
		(pad "2" smd rect
			(at 1 0 180)
			(size 1 1.25)
			(layers "F.Cu" "F.Mask" "F.Paste")
			(net "GND")
			(solder_mask_margin 0)
			(solder_paste_margin 0)
		)
	)
	(footprint "Vault:CAPC1608X87X45ML20T05"
		(layer "F.Cu")
		(at 80.6261 125.8662 -90)
		(property "Reference" "C27"
			(at 2.7714 -0.026931 90)
			(unlocked yes)
			(layer "F.SilkS")
			(effects
				(font
					(size 0.762 0.762)
					(thickness 0.2286)
				)
			)
		)
		(property "Value" "0.1uF"
			(at 2.069035 2.630671 270)
			(unlocked yes)
			(layer "F.SilkS")
			(hide yes)
			(effects
				(font
					(size 0.762 0.762)
					(thickness 0.2286)
				)
			)
		)
		(sheetname "USER_IO")
		(sheetfile "USER_IO.kicad_sch")
		(duplicate_pad_numbers_are_jumpers no)
		(pad "1" smd rect
			(at -0.7 0)
			(size 1.1 1.05)
			(layers "F.Cu" "F.Mask" "F.Paste")
			(net "+3.3V")
		)
		(pad "2" smd rect
			(at 0.7 0)
			(size 1.1 1.05)
			(layers "F.Cu" "F.Mask" "F.Paste")
			(net "GND")
		)
	)
	(footprint "Vault:CAPC1608X87X45ML20T05"
		(layer "F.Cu")
		(at 92.1261 74.5786 90)
		(property "Reference" "C59"
			(at -4.25 1.343345 90)
			(unlocked yes)
			(layer "F.SilkS")
			(effects
				(font
					(size 0.762 0.762)
					(thickness 0.2286)
				)
				(justify left bottom)
			)
		)
		(property "Value" "0.1uF"
			(at -3.382645 -0.2921 0)
			(unlocked yes)
			(layer "F.SilkS")
			(hide yes)
			(effects
				(font
					(size 0.762 0.762)
					(thickness 0.2286)
				)
				(justify left bottom)
			)
		)
		(sheetname "GPS_IMU_SENSORS")
		(sheetfile "GPS_IMU_SENSORS.kicad_sch")
		(duplicate_pad_numbers_are_jumpers no)
		(pad "1" smd rect
			(at -0.7 0 180)
			(size 1.1 1.05)
			(layers "F.Cu" "F.Mask" "F.Paste")
			(net "GND")
		)
		(pad "2" smd rect
			(at 0.7 0 180)
			(size 1.1 1.05)
			(layers "F.Cu" "F.Mask" "F.Paste")
			(net "+3.3V")
		)
	)
	(footprint "Vault:FP-CC0402-MFG"
		(layer "F.Cu")
		(at 235.7261 63.2162 90)
		(property "Reference" "C91"
			(at 0.428605 -1.773079 90)
			(unlocked yes)
			(layer "F.SilkS")
			(effects
				(font
					(size 0.762 0.762)
					(thickness 0.2286)
				)
			)
		)
		(property "Value" "10nF_50V_0402"
			(at 9.02662 2.389351 90)
			(unlocked yes)
			(layer "F.SilkS")
			(hide yes)
			(effects
				(font
					(size 0.762 0.762)
					(thickness 0.2286)
				)
			)
		)
		(sheetname "USBUart_DipSelects")
		(sheetfile "USBUart_DipSelects.kicad_sch")
		(duplicate_pad_numbers_are_jumpers no)
		(fp_line
			(start -0.525 -0.675)
			(end 0.525 -0.675)
			(stroke
				(width 0.2)
				(type solid)
			)
			(layer "F.SilkS")
		)
		(fp_line
			(start -0.53033 0.68067)
			(end 0.51967 0.68067)
			(stroke
				(width 0.2)
				(type solid)
			)
			(layer "F.SilkS")
		)
		(fp_line
			(start 0.875 -0.475)
			(end 0.875 0.475)
			(stroke
				(width 0.2)
				(type solid)
			)
			(layer "F.CrtYd")
		)
		(fp_line
			(start -0.875 -0.475)
			(end 0.875 -0.475)
			(stroke
				(width 0.2)
				(type solid)
			)
			(layer "F.CrtYd")
		)
		(fp_line
			(start -0.875 -0.475)
			(end -0.875 0.475)
			(stroke
				(width 0.2)
				(type solid)
			)
			(layer "F.CrtYd")
		)
		(fp_line
			(start -0.875 0.475)
			(end 0.875 0.475)
			(stroke
				(width 0.2)
				(type solid)
			)
			(layer "F.CrtYd")
		)
		(fp_line
			(start 0 -0.5)
			(end 0 0.5)
			(stroke
				(width 0.1)
				(type solid)
			)
			(layer "F.Fab")
		)
		(fp_line
			(start 0.875 -0.475)
			(end 0.875 0.475)
			(stroke
				(width 0.2)
				(type solid)
			)
			(layer "F.Fab")
		)
		(fp_line
			(start -0.875 -0.475)
			(end 0.875 -0.475)
			(stroke
				(width 0.2)
				(type solid)
			)
			(layer "F.Fab")
		)
		(fp_line
			(start -0.875 -0.475)
			(end -0.875 0.475)
			(stroke
				(width 0.2)
				(type solid)
			)
			(layer "F.Fab")
		)
		(fp_line
			(start -0.5 0)
			(end 0.5 0)
			(stroke
				(width 0.1)
				(type solid)
			)
			(layer "F.Fab")
		)
		(fp_line
			(start -0.875 0.475)
			(end 0.875 0.475)
			(stroke
				(width 0.2)
				(type solid)
			)
			(layer "F.Fab")
		)
		(fp_text user "${REFERENCE}"
			(at -0.00001 0.09601 90)
			(unlocked yes)
			(layer "F.Fab")
			(effects
				(font
					(face "Arial")
					(size 0.63 0.63)
					(thickness 0.1)
				)
				(justify left bottom)
			)
		)
		(pad "1" smd rect
			(at -0.5 0 90)
			(size 0.5 0.5)
			(layers "F.Cu" "F.Mask" "F.Paste")
			(net "NetC91_1")
			(solder_mask_margin 0)
			(solder_paste_margin 0)
		)
		(pad "2" smd rect
			(at 0.5 0 90)
			(size 0.5 0.5)
			(layers "F.Cu" "F.Mask" "F.Paste")
			(net "GND")
			(solder_mask_margin 0)
			(solder_paste_margin 0)
		)
	)
	(footprint "Vault:M08A_L"
		(layer "F.Cu")
		(at 118.6261 86.0786)
		(property "Reference" "U4"
			(at 1.028595 -3.235469 0)
			(unlocked yes)
			(layer "F.SilkS")
			(effects
				(font
					(size 0.762 0.762)
					(thickness 0.2286)
				)
			)
		)
		(property "Value" "DS90LV028AQMA"
			(at 6.71518 4.180071 0)
			(unlocked yes)
			(layer "F.SilkS")
			(hide yes)
			(effects
				(font
					(size 0.762 0.762)
					(thickness 0.2286)
				)
			)
		)
		(sheetname "MAC")
		(sheetfile "MAC.kicad_sch")
		(duplicate_pad_numbers_are_jumpers no)
		(fp_line
			(start -1 -2.5)
			(end 1 -2.5)
			(stroke
				(width 0.2)
				(type solid)
			)
			(layer "F.SilkS")
		)
		(fp_line
			(start -1 2.5)
			(end -1 -2.5)
			(stroke
				(width 0.2)
				(type solid)
			)
			(layer "F.SilkS")
		)
		(fp_line
			(start -1 2.5)
			(end 1 2.5)
			(stroke
				(width 0.2)
				(type solid)
			)
			(layer "F.SilkS")
		)
		(fp_line
			(start 1 2.5)
			(end 1 -2.5)
			(stroke
				(width 0.2)
				(type solid)
			)
			(layer "F.SilkS")
		)
		(fp_circle
			(center -2.35 -2.755)
			(end -2.35 -2.88)
			(stroke
				(width 0.25)
				(type solid)
			)
			(fill no)
			(layer "F.SilkS")
		)
		(fp_circle
			(center -0.2 -1.7)
			(end -0.2 -1.9)
			(stroke
				(width 0.4)
				(type solid)
			)
			(fill no)
			(layer "F.SilkS")
		)
		(pad "1" smd oval
			(at -2.35 -1.905 90)
			(size 0.6 1.9)
			(layers "F.Cu" "F.Mask" "F.Paste")
			(net "MAC_PPS_OUT-")
		)
		(pad "2" smd oval
			(at -2.35 -0.635 90)
			(size 0.6 1.9)
			(layers "F.Cu" "F.Mask" "F.Paste")
			(net "MAC_PPS_OUT+")
		)
		(pad "3" smd oval
			(at -2.35 0.635 90)
			(size 0.6 1.9)
			(layers "F.Cu" "F.Mask" "F.Paste")
		)
		(pad "4" smd oval
			(at -2.35 1.905 90)
			(size 0.6 1.9)
			(layers "F.Cu" "F.Mask" "F.Paste")
		)
		(pad "5" smd oval
			(at 2.35 1.905 90)
			(size 0.6 1.9)
			(layers "F.Cu" "F.Mask" "F.Paste")
			(net "GND")
		)
		(pad "6" smd oval
			(at 2.35 0.635 90)
			(size 0.6 1.9)
			(layers "F.Cu" "F.Mask" "F.Paste")
		)
		(pad "7" smd oval
			(at 2.35 -0.635 90)
			(size 0.6 1.9)
			(layers "F.Cu" "F.Mask" "F.Paste")
			(net "FPGA_MAC_PPSDIFF_OUT")
		)
		(pad "8" smd oval
			(at 2.35 -1.905 90)
			(size 0.6 1.9)
			(layers "F.Cu" "F.Mask" "F.Paste")
			(net "+3.3V")
		)
	)
	(footprint "Vault:FP-IHLP-2525EZ-FP_2_413x3-MFG"
		(layer "F.Cu")
		(at 219.7261 109.9162)
		(property "Reference" "L1"
			(at 3.906655 2.1 270)
			(unlocked yes)
			(layer "F.SilkS")
			(effects
				(font
					(size 0.762 0.762)
					(thickness 0.2286)
				)
				(justify left bottom)
			)
		)
		(property "Value" "2.2uH_10A"
			(at -22.3845 0.209845 0)
			(unlocked yes)
			(layer "F.SilkS")
			(hide yes)
			(effects
				(font
					(size 0.762 0.762)
					(thickness 0.2286)
				)
				(justify left bottom)
			)
		)
		(sheetname "POWER")
		(sheetfile "POWER.kicad_sch")
		(duplicate_pad_numbers_are_jumpers no)
		(fp_line
			(start -3.362 -3.362)
			(end 3.362 -3.362)
			(stroke
				(width 0.2)
				(type solid)
			)
			(layer "F.SilkS")
		)
		(fp_line
			(start -3.362 -2.0895)
			(end -3.362 -3.362)
			(stroke
				(width 0.2)
				(type solid)
			)
			(layer "F.SilkS")
		)
		(fp_line
			(start -3.362 3.362)
			(end -3.362 2.0895)
			(stroke
				(width 0.2)
				(type solid)
			)
			(layer "F.SilkS")
		)
		(fp_line
			(start -3.362 3.362)
			(end 3.362 3.362)
			(stroke
				(width 0.2)
				(type solid)
			)
			(layer "F.SilkS")
		)
		(fp_line
			(start 3.362 -2.0895)
			(end 3.362 -3.362)
			(stroke
				(width 0.2)
				(type solid)
			)
			(layer "F.SilkS")
		)
		(fp_line
			(start 3.362 3.362)
			(end 3.362 2.0895)
			(stroke
				(width 0.2)
				(type solid)
			)
			(layer "F.SilkS")
		)
		(fp_line
			(start -4.2275 -3.462)
			(end 4.2275 -3.462)
			(stroke
				(width 0.2)
				(type solid)
			)
			(layer "F.CrtYd")
		)
		(fp_line
			(start -4.2275 3.462)
			(end -4.2275 -3.462)
			(stroke
				(width 0.2)
				(type solid)
			)
			(layer "F.CrtYd")
		)
		(fp_line
			(start -4.2275 3.462)
			(end 4.2275 3.462)
			(stroke
				(width 0.2)
				(type solid)
			)
			(layer "F.CrtYd")
		)
		(fp_line
			(start 4.2275 3.462)
			(end 4.2275 -3.462)
			(stroke
				(width 0.2)
				(type solid)
			)
			(layer "F.CrtYd")
		)
		(fp_line
			(start -4.2275 -3.462)
			(end 4.2275 -3.462)
			(stroke
				(width 0.2)
				(type solid)
			)
			(layer "F.Fab")
		)
		(fp_line
			(start -4.2275 3.462)
			(end -4.2275 -3.462)
			(stroke
				(width 0.2)
				(type solid)
			)
			(layer "F.Fab")
		)
		(fp_line
			(start -4.2275 3.462)
			(end 4.2275 3.462)
			(stroke
				(width 0.2)
				(type solid)
			)
			(layer "F.Fab")
		)
		(fp_line
			(start -0.5 0)
			(end 0.5 0)
			(stroke
				(width 0.1)
				(type solid)
			)
			(layer "F.Fab")
		)
		(fp_line
			(start 0 0.5)
			(end 0 -0.5)
			(stroke
				(width 0.1)
				(type solid)
			)
			(layer "F.Fab")
		)
		(fp_line
			(start 4.2275 3.462)
			(end 4.2275 -3.462)
			(stroke
				(width 0.2)
				(type solid)
			)
			(layer "F.Fab")
		)
		(fp_text user "${REFERENCE}"
			(at -0.00001 0.10711 360)
			(unlocked yes)
			(layer "F.Fab")
			(effects
				(font
					(face "Arial")
					(size 0.63 0.63)
					(thickness 0.1)
				)
				(justify left bottom)
			)
		)
		(pad "1" smd rect
			(at -2.921 0)
			(size 2.413 3.429)
			(layers "F.Cu" "F.Mask" "F.Paste")
			(net "NetL1_1")
			(solder_mask_margin 0)
			(solder_paste_margin 0)
		)
		(pad "2" smd rect
			(at 2.921 0)
			(size 2.413 3.429)
			(layers "F.Cu" "F.Mask" "F.Paste")
			(net "P5V_SENSE")
			(solder_mask_margin 0)
			(solder_paste_margin 0)
		)
	)
	(footprint "Vault:CAPC1608X87X45ML20T05"
		(layer "F.Cu")
		(at 207.4261 85.7162 -90)
		(property "Reference" "C2"
			(at -1.6 -0.993345 90)
			(unlocked yes)
			(layer "F.SilkS")
			(effects
				(font
					(size 0.762 0.762)
					(thickness 0.2286)
				)
				(justify left bottom)
			)
		)
		(property "Value" "0.1uF"
			(at 2.225445 1.4493 0)
			(unlocked yes)
			(layer "F.SilkS")
			(hide yes)
			(effects
				(font
					(size 0.762 0.762)
					(thickness 0.2286)
				)
				(justify left bottom)
			)
		)
		(sheetname "POWER")
		(sheetfile "POWER.kicad_sch")
		(duplicate_pad_numbers_are_jumpers no)
		(pad "1" smd rect
			(at -0.7 0)
			(size 1.1 1.05)
			(layers "F.Cu" "F.Mask" "F.Paste")
			(net "GND")
		)
		(pad "2" smd rect
			(at 0.7 0)
			(size 1.1 1.05)
			(layers "F.Cu" "F.Mask" "F.Paste")
			(net "+12V")
		)
	)
	(footprint "Vault:CAPC1608X87X45ML20T05"
		(layer "F.Cu")
		(at 233.0261 59.2162 180)
		(property "Reference" "C37"
			(at -0.7286 1.273079 0)
			(unlocked yes)
			(layer "F.SilkS")
			(effects
				(font
					(size 0.762 0.762)
					(thickness 0.2286)
				)
			)
		)
		(property "Value" "0.1uF"
			(at 2.069035 2.630671 180)
			(unlocked yes)
			(layer "F.SilkS")
			(hide yes)
			(effects
				(font
					(size 0.762 0.762)
					(thickness 0.2286)
				)
			)
		)
		(sheetname "GPS_IMU_SENSORS")
		(sheetfile "GPS_IMU_SENSORS.kicad_sch")
		(duplicate_pad_numbers_are_jumpers no)
		(pad "1" smd rect
			(at -0.7 0 270)
			(size 1.1 1.05)
			(layers "F.Cu" "F.Mask" "F.Paste")
			(net "GND")
		)
		(pad "2" smd rect
			(at 0.7 0 270)
			(size 1.1 1.05)
			(layers "F.Cu" "F.Mask" "F.Paste")
			(net "+5.0V")
		)
	)
	(footprint "Vault:CAPC1608X87X45ML20T05"
		(layer "F.Cu")
		(at 77.3261 65.2162 -90)
		(property "Reference" "C54"
			(at -2.8714 -0.073069 270)
			(unlocked yes)
			(layer "F.SilkS")
			(effects
				(font
					(size 0.762 0.762)
					(thickness 0.2286)
				)
			)
		)
		(property "Value" "0.1uF"
			(at 2.069035 2.630671 270)
			(unlocked yes)
			(layer "F.SilkS")
			(hide yes)
			(effects
				(font
					(size 0.762 0.762)
					(thickness 0.2286)
				)
			)
		)
		(sheetname "GPS_IMU_SENSORS")
		(sheetfile "GPS_IMU_SENSORS.kicad_sch")
		(duplicate_pad_numbers_are_jumpers no)
		(pad "1" smd rect
			(at -0.7 0)
			(size 1.1 1.05)
			(layers "F.Cu" "F.Mask" "F.Paste")
			(net "GND")
		)
		(pad "2" smd rect
			(at 0.7 0)
			(size 1.1 1.05)
			(layers "F.Cu" "F.Mask" "F.Paste")
			(net "+5.0V")
		)
	)
	(footprint "Vault:RESC1005X40X25ML05T10"
		(layer "F.Cu")
		(at 203.3261 106.0162)
		(property "Reference" "R63"
			(at -0.1714 -1.173079 0)
			(unlocked yes)
			(layer "F.SilkS")
			(effects
				(font
					(size 0.762 0.762)
					(thickness 0.2286)
				)
			)
		)
		(property "Value" "470_1%_0402"
			(at -2.884671 8.036475 270)
			(unlocked yes)
			(layer "F.SilkS")
			(hide yes)
			(effects
				(font
					(size 0.762 0.762)
					(thickness 0.2286)
				)
			)
		)
		(sheetname "POWER")
		(sheetfile "POWER.kicad_sch")
		(duplicate_pad_numbers_are_jumpers no)
		(pad "1" smd rect
			(at -0.475 0 90)
			(size 0.65 0.7)
			(layers "F.Cu" "F.Mask" "F.Paste")
			(net "GND")
		)
		(pad "2" smd rect
			(at 0.475 0 90)
			(size 0.65 0.7)
			(layers "F.Cu" "F.Mask" "F.Paste")
			(net "P5V_FB")
		)
	)
	(footprint "Vault:M08A_N"
		(layer "F.Cu")
		(at 136.5261 85.9636)
		(property "Reference" "U3"
			(at 2.528605 -3.020469 0)
			(unlocked yes)
			(layer "F.SilkS")
			(effects
				(font
					(size 0.762 0.762)
					(thickness 0.2286)
				)
			)
		)
		(property "Value" "DS90LV027AQMA"
			(at 6.35958 4.332471 0)
			(unlocked yes)
			(layer "F.SilkS")
			(hide yes)
			(effects
				(font
					(size 0.762 0.762)
					(thickness 0.2286)
				)
			)
		)
		(sheetname "MAC")
		(sheetfile "MAC.kicad_sch")
		(duplicate_pad_numbers_are_jumpers no)
		(fp_line
			(start -0.9 -2.5)
			(end 0.9 -2.5)
			(stroke
				(width 0.2)
				(type solid)
			)
			(layer "F.SilkS")
		)
		(fp_line
			(start -0.9 2.5)
			(end -0.9 -2.5)
			(stroke
				(width 0.2)
				(type solid)
			)
			(layer "F.SilkS")
		)
		(fp_line
			(start -0.9 2.5)
			(end 0.9 2.5)
			(stroke
				(width 0.2)
				(type solid)
			)
			(layer "F.SilkS")
		)
		(fp_line
			(start 0.9 2.5)
			(end 0.9 -2.5)
			(stroke
				(width 0.2)
				(type solid)
			)
			(layer "F.SilkS")
		)
		(fp_circle
			(center -2.4 -2.755)
			(end -2.4 -2.88)
			(stroke
				(width 0.25)
				(type solid)
			)
			(fill no)
			(layer "F.SilkS")
		)
		(fp_circle
			(center -0.1 -1.7)
			(end -0.1 -1.9)
			(stroke
				(width 0.4)
				(type solid)
			)
			(fill no)
			(layer "F.SilkS")
		)
		(pad "1" smd oval
			(at -2.4 -1.905 90)
			(size 0.6 2.2)
			(layers "F.Cu" "F.Mask" "F.Paste")
			(net "+3.3V")
		)
		(pad "2" smd oval
			(at -2.4 -0.635 90)
			(size 0.6 2.2)
			(layers "F.Cu" "F.Mask" "F.Paste")
			(net "FPGA_MAC_PPS_IN1-")
		)
		(pad "3" smd oval
			(at -2.4 0.635 90)
			(size 0.6 2.2)
			(layers "F.Cu" "F.Mask" "F.Paste")
			(net "FPGA_MAC_PPS_DIFF_IN0")
		)
		(pad "4" smd oval
			(at -2.4 1.905 90)
			(size 0.6 2.2)
			(layers "F.Cu" "F.Mask" "F.Paste")
			(net "GND")
		)
		(pad "5" smd oval
			(at 2.4 1.905 90)
			(size 0.6 2.2)
			(layers "F.Cu" "F.Mask" "F.Paste")
			(net "MAC_PPS_IN0-")
		)
		(pad "6" smd oval
			(at 2.4 0.635 90)
			(size 0.6 2.2)
			(layers "F.Cu" "F.Mask" "F.Paste")
			(net "MAC_PPS_IN0+")
		)
		(pad "7" smd oval
			(at 2.4 -0.635 90)
			(size 0.6 2.2)
			(layers "F.Cu" "F.Mask" "F.Paste")
			(net "MAC_PPS_IN1+")
		)
		(pad "8" smd oval
			(at 2.4 -1.905 90)
			(size 0.6 2.2)
			(layers "F.Cu" "F.Mask" "F.Paste")
			(net "MAC_PPS_IN1-")
		)
	)
	(footprint "Vault:TECO-1909763-1_V"
		(layer "F.Cu")
		(at 74.3761 108.6162 -90)
		(property "Reference" "J2"
			(at -2.973079 1.271395 0)
			(unlocked yes)
			(layer "F.SilkS")
			(effects
				(font
					(size 0.762 0.762)
					(thickness 0.2286)
				)
			)
		)
		(property "Value" "1909763-1"
			(at 4.582685 3.722871 270)
			(unlocked yes)
			(layer "F.SilkS")
			(hide yes)
			(effects
				(font
					(size 0.762 0.762)
					(thickness 0.2286)
				)
			)
		)
		(sheetname "USER_IO")
		(sheetfile "USER_IO.kicad_sch")
		(duplicate_pad_numbers_are_jumpers no)
		(fp_line
			(start 0.55 -1.3)
			(end -0.55 -1.3)
			(stroke
				(width 0.2)
				(type solid)
			)
			(layer "F.SilkS")
		)
		(fp_circle
			(center -1.778 1.65)
			(end -1.903 1.65)
			(stroke
				(width 0.25)
				(type solid)
			)
			(fill no)
			(layer "F.SilkS")
		)
		(pad "1" smd rect
			(at -1.475 0 270)
			(size 1.05 2.2)
			(layers "F.Cu" "F.Mask" "F.Paste")
			(net "GND")
		)
		(pad "2" smd rect
			(at 0 1.525 270)
			(size 1 1.05)
			(layers "F.Cu" "F.Mask" "F.Paste")
			(net "NetAN2_1")
		)
		(pad "3" smd rect
			(at 1.475 0 270)
			(size 1.05 2.2)
			(layers "F.Cu" "F.Mask" "F.Paste")
			(net "GND")
		)
	)
	(footprint "Vault:CAPC1608X87X45ML20T05"
		(layer "F.Cu")
		(at 91.4261 65.4162 -90)
		(property "Reference" "C43"
			(at -2.9714 0.226931 270)
			(unlocked yes)
			(layer "F.SilkS")
			(effects
				(font
					(size 0.762 0.762)
					(thickness 0.2286)
				)
			)
		)
		(property "Value" "0.1uF"
			(at 2.069035 2.630671 270)
			(unlocked yes)
			(layer "F.SilkS")
			(hide yes)
			(effects
				(font
					(size 0.762 0.762)
					(thickness 0.2286)
				)
			)
		)
		(sheetname "GPS_IMU_SENSORS")
		(sheetfile "GPS_IMU_SENSORS.kicad_sch")
		(duplicate_pad_numbers_are_jumpers no)
		(pad "1" smd rect
			(at -0.7 0)
			(size 1.1 1.05)
			(layers "F.Cu" "F.Mask" "F.Paste")
			(net "GND")
		)
		(pad "2" smd rect
			(at 0.7 0)
			(size 1.1 1.05)
			(layers "F.Cu" "F.Mask" "F.Paste")
			(net "+3.3V")
		)
	)
	(footprint "Vault:RESC1608X55X30NL15T15"
		(layer "F.Cu")
		(at 75.1261 55.6162 90)
		(property "Reference" "R39"
			(at -5.7714 0.026921 90)
			(unlocked yes)
			(layer "F.SilkS")
			(effects
				(font
					(size 0.762 0.762)
					(thickness 0.2286)
				)
			)
		)
		(property "Value" "200 OHM"
			(at -2.935471 4.78626 0)
			(unlocked yes)
			(layer "F.SilkS")
			(hide yes)
			(effects
				(font
					(size 0.762 0.762)
					(thickness 0.2286)
				)
			)
		)
		(sheetname "USER_IO_STATUS")
		(sheetfile "USER_IO_STATUS.kicad_sch")
		(duplicate_pad_numbers_are_jumpers no)
		(pad "1" smd rect
			(at -0.675 0 180)
			(size 0.95 0.8)
			(layers "F.Cu" "F.Mask" "F.Paste")
			(net "LED4")
		)
		(pad "2" smd rect
			(at 0.675 0 180)
			(size 0.95 0.8)
			(layers "F.Cu" "F.Mask" "F.Paste")
			(net "NetD11_1")
		)
	)
	(footprint "Vault:FP-CC0603-DA-MFG"
		(layer "F.Cu")
		(at 208.5261 129.2162 180)
		(property "Reference" "C74"
			(at 0.2286 -1.473079 180)
			(unlocked yes)
			(layer "F.SilkS")
			(effects
				(font
					(size 0.762 0.762)
					(thickness 0.2286)
				)
			)
		)
		(property "Value" "0.1uF_50V_0603"
			(at -3.075151 9.686815 90)
			(unlocked yes)
			(layer "F.SilkS")
			(hide yes)
			(effects
				(font
					(size 0.762 0.762)
					(thickness 0.2286)
				)
			)
		)
		(sheetname "POWER")
		(sheetfile "POWER.kicad_sch")
		(duplicate_pad_numbers_are_jumpers no)
		(fp_line
			(start 0.85 0.85)
			(end -0.85 0.85)
			(stroke
				(width 0.2)
				(type solid)
			)
			(layer "F.SilkS")
		)
		(fp_line
			(start 0.85 -0.85)
			(end -0.85 -0.85)
			(stroke
				(width 0.2)
				(type solid)
			)
			(layer "F.SilkS")
		)
		(fp_line
			(start 1.35 0.75)
			(end -1.35 0.75)
			(stroke
				(width 0.2)
				(type solid)
			)
			(layer "F.CrtYd")
		)
		(fp_line
			(start 1.35 -0.75)
			(end 1.35 0.75)
			(stroke
				(width 0.2)
				(type solid)
			)
			(layer "F.CrtYd")
		)
		(fp_line
			(start 1.35 -0.75)
			(end -1.35 -0.75)
			(stroke
				(width 0.2)
				(type solid)
			)
			(layer "F.CrtYd")
		)
		(fp_line
			(start -1.35 -0.75)
			(end -1.35 0.75)
			(stroke
				(width 0.2)
				(type solid)
			)
			(layer "F.CrtYd")
		)
		(fp_line
			(start 1.35 0.75)
			(end -1.35 0.75)
			(stroke
				(width 0.2)
				(type solid)
			)
			(layer "F.Fab")
		)
		(fp_line
			(start 1.35 -0.75)
			(end 1.35 0.75)
			(stroke
				(width 0.2)
				(type solid)
			)
			(layer "F.Fab")
		)
		(fp_line
			(start 1.35 -0.75)
			(end -1.35 -0.75)
			(stroke
				(width 0.2)
				(type solid)
			)
			(layer "F.Fab")
		)
		(fp_line
			(start 0.5 0)
			(end -0.5 0)
			(stroke
				(width 0.1)
				(type solid)
			)
			(layer "F.Fab")
		)
		(fp_line
			(start 0 -0.5)
			(end 0 0.5)
			(stroke
				(width 0.1)
				(type solid)
			)
			(layer "F.Fab")
		)
		(fp_line
			(start -1.35 -0.75)
			(end -1.35 0.75)
			(stroke
				(width 0.2)
				(type solid)
			)
			(layer "F.Fab")
		)
		(fp_text user "${REFERENCE}"
			(at -0.00001 0.09601 180)
			(unlocked yes)
			(layer "F.Fab")
			(effects
				(font
					(face "Arial")
					(size 0.63 0.63)
					(thickness 0.1)
				)
				(justify left bottom)
			)
		)
		(pad "1" smd rect
			(at -0.75 0 180)
			(size 0.8 0.9)
			(layers "F.Cu" "F.Mask" "F.Paste")
			(net "NetC74_1")
			(solder_mask_margin 0)
			(solder_paste_margin 0)
		)
		(pad "2" smd rect
			(at 0.75 0 180)
			(size 0.8 0.9)
			(layers "F.Cu" "F.Mask" "F.Paste")
			(net "P3V3_FB")
			(solder_mask_margin 0)
			(solder_paste_margin 0)
		)
	)
	(footprint "Vault:RESC1005X40X25ML05T10"
		(layer "F.Cu")
		(at 217.2261 114.1162 180)
		(property "Reference" "R6"
			(at 0.6 -1.593345 0)
			(unlocked yes)
			(layer "F.SilkS")
			(effects
				(font
					(size 0.762 0.762)
					(thickness 0.2286)
				)
				(justify left bottom)
			)
		)
		(property "Value" "2.21_1%_0402"
			(at 10.44471 4.536755 0)
			(unlocked yes)
			(layer "F.SilkS")
			(hide yes)
			(effects
				(font
					(size 0.762 0.762)
					(thickness 0.2286)
				)
				(justify left bottom)
			)
		)
		(sheetname "POWER")
		(sheetfile "POWER.kicad_sch")
		(duplicate_pad_numbers_are_jumpers no)
		(pad "1" smd rect
			(at -0.475 0 270)
			(size 0.65 0.7)
			(layers "F.Cu" "F.Mask" "F.Paste")
			(net "NetC3_2")
		)
		(pad "2" smd rect
			(at 0.475 0 270)
			(size 0.65 0.7)
			(layers "F.Cu" "F.Mask" "F.Paste")
			(net "NetL1_1")
		)
	)
	(footprint "Vault:RESC1005X40X25LL05T10"
		(layer "F.Cu")
		(at 166.8011 83.2162)
		(property "Reference" "R88"
			(at -1.7464 0.026921 0)
			(unlocked yes)
			(layer "F.SilkS")
			(effects
				(font
					(size 0.762 0.762)
					(thickness 0.2286)
				)
			)
		)
		(property "Value" "10K_1%_0402"
			(at -2.579871 8.061915 270)
			(unlocked yes)
			(layer "F.SilkS")
			(hide yes)
			(effects
				(font
					(size 0.762 0.762)
					(thickness 0.2286)
				)
			)
		)
		(sheetname "USBUart_DipSelects")
		(sheetfile "USBUart_DipSelects.kicad_sch")
		(duplicate_pad_numbers_are_jumpers no)
		(pad "1" smd rect
			(at -0.375 0 90)
			(size 0.45 0.5)
			(layers "F.Cu" "F.Mask" "F.Paste")
			(net "+3.3V")
		)
		(pad "2" smd rect
			(at 0.375 0 90)
			(size 0.45 0.5)
			(layers "F.Cu" "F.Mask" "F.Paste")
			(net "DIP_SW_UART_SEL")
		)
	)
	(footprint "Vault:FP-LTST-C191TBKT-MFG"
		(layer "F.Cu")
		(at 71.6261 52.1162 90)
		(property "Reference" "D9"
			(at -6.771395 -0.223079 90)
			(unlocked yes)
			(layer "F.SilkS")
			(effects
				(font
					(size 0.762 0.762)
					(thickness 0.2286)
				)
			)
		)
		(property "Value" "BLUE"
			(at 1.2818 2.452871 90)
			(unlocked yes)
			(layer "F.SilkS")
			(hide yes)
			(effects
				(font
					(size 0.762 0.762)
					(thickness 0.2286)
				)
			)
		)
		(sheetname "USER_IO_STATUS")
		(sheetfile "USER_IO_STATUS.kicad_sch")
		(duplicate_pad_numbers_are_jumpers no)
		(fp_line
			(start -0.85 -0.8)
			(end 0.85 -0.8)
			(stroke
				(width 0.2)
				(type solid)
			)
			(layer "F.SilkS")
		)
		(fp_line
			(start -0.85 0.8)
			(end 0.85 0.8)
			(stroke
				(width 0.2)
				(type solid)
			)
			(layer "F.SilkS")
		)
		(fp_circle
			(center -1.75 0)
			(end -1.625 0)
			(stroke
				(width 0.25)
				(type solid)
			)
			(fill no)
			(layer "F.SilkS")
		)
		(fp_line
			(start 1.25 -0.55)
			(end 1.25 0.55)
			(stroke
				(width 0.2)
				(type solid)
			)
			(layer "F.CrtYd")
		)
		(fp_line
			(start -1.25 -0.55)
			(end 1.25 -0.55)
			(stroke
				(width 0.2)
				(type solid)
			)
			(layer "F.CrtYd")
		)
		(fp_line
			(start -1.25 -0.55)
			(end -1.25 0.55)
			(stroke
				(width 0.2)
				(type solid)
			)
			(layer "F.CrtYd")
		)
		(fp_line
			(start -1.25 0.55)
			(end 1.25 0.55)
			(stroke
				(width 0.2)
				(type solid)
			)
			(layer "F.CrtYd")
		)
		(fp_line
			(start 1.25 -0.55)
			(end 1.25 0.55)
			(stroke
				(width 0.2)
				(type solid)
			)
			(layer "F.Fab")
		)
		(fp_line
			(start -1.25 -0.55)
			(end 1.25 -0.55)
			(stroke
				(width 0.2)
				(type solid)
			)
			(layer "F.Fab")
		)
		(fp_line
			(start -1.25 -0.55)
			(end -1.25 0.55)
			(stroke
				(width 0.2)
				(type solid)
			)
			(layer "F.Fab")
		)
		(fp_line
			(start 0 -0.5)
			(end 0 0.5)
			(stroke
				(width 0.1)
				(type solid)
			)
			(layer "F.Fab")
		)
		(fp_line
			(start -0.5 0)
			(end 0.5 0)
			(stroke
				(width 0.1)
				(type solid)
			)
			(layer "F.Fab")
		)
		(fp_line
			(start -1.25 0.55)
			(end 1.25 0.55)
			(stroke
				(width 0.2)
				(type solid)
			)
			(layer "F.Fab")
		)
		(fp_text user "${REFERENCE}"
			(at 0 0.28425 90)
			(unlocked yes)
			(layer "F.Fab")
			(effects
				(font
					(face "Arial")
					(size 0.63 0.63)
					(thickness 0.1)
				)
				(justify left bottom)
			)
		)
		(pad "1" smd rect
			(at -0.75 0 90)
			(size 0.8 0.8)
			(layers "F.Cu" "F.Mask" "F.Paste")
			(net "NetD9_1")
			(solder_mask_margin 0)
			(solder_paste_margin 0)
		)
		(pad "2" smd rect
			(at 0.75 0 90)
			(size 0.8 0.8)
			(layers "F.Cu" "F.Mask" "F.Paste")
			(net "+3.3V")
			(solder_mask_margin 0)
			(solder_paste_margin 0)
		)
	)
	(footprint "Vault:RESC1005X40X25LL05T05"
		(layer "F.Cu")
		(at 80.3261 85.0162 180)
		(property "Reference" "R110"
			(at 2.9714 -0.426931 0)
			(unlocked yes)
			(layer "F.SilkS")
			(effects
				(font
					(size 0.762 0.762)
					(thickness 0.2286)
				)
			)
		)
		(property "Value" "DNI_4.7K_0402"
			(at -2.352802 9.48386 90)
			(unlocked yes)
			(layer "F.SilkS")
			(hide yes)
			(effects
				(font
					(size 1.524 1.524)
					(thickness 0.254)
				)
			)
		)
		(sheetname "USER_IO_STATUS")
		(sheetfile "USER_IO_STATUS.kicad_sch")
		(duplicate_pad_numbers_are_jumpers no)
		(pad "1" smd rect
			(at -0.4 0 270)
			(size 0.45 0.45)
			(layers "F.Cu" "F.Mask" "F.Paste")
			(net "NetR108_2")
		)
		(pad "2" smd rect
			(at 0.4 0 270)
			(size 0.45 0.45)
			(layers "F.Cu" "F.Mask" "F.Paste")
			(net "GND")
		)
	)
	(footprint "Vault:RESC1005X40X25NL05T05"
		(layer "F.Cu")
		(at 209.3761 82.1162)
		(property "Reference" "R103"
			(at 3.03687 0.059321 0)
			(unlocked yes)
			(layer "F.SilkS")
			(effects
				(font
					(size 0.762 0.762)
					(thickness 0.2286)
				)
			)
		)
		(property "Value" "DNI_27_1%_0402"
			(at -2.732281 10.296375 270)
			(unlocked yes)
			(layer "F.SilkS")
			(hide yes)
			(effects
				(font
					(size 0.762 0.762)
					(thickness 0.2286)
				)
			)
		)
		(sheetname "USBUart_DipSelects")
		(sheetfile "USBUart_DipSelects.kicad_sch")
		(duplicate_pad_numbers_are_jumpers no)
		(pad "1" smd rect
			(at -0.45 0 90)
			(size 0.55 0.55)
			(layers "F.Cu" "F.Mask" "F.Paste")
			(net "GPS2_RX_FPGA")
		)
		(pad "2" smd rect
			(at 0.45 0 90)
			(size 0.55 0.55)
			(layers "F.Cu" "F.Mask" "F.Paste")
			(net "GPS2_RX")
		)
	)
	(footprint "Vault:RESC1608X55X25LL10T15"
		(layer "F.Cu")
		(at 131.4761 85.3162)
		(property "Reference" "R10"
			(at 0.4786 1.426931 0)
			(unlocked yes)
			(layer "F.SilkS")
			(effects
				(font
					(size 0.762 0.762)
					(thickness 0.2286)
				)
			)
		)
		(property "Value" "4.7K"
			(at -2.630671 2.57724 270)
			(unlocked yes)
			(layer "F.SilkS")
			(hide yes)
			(effects
				(font
					(size 0.762 0.762)
					(thickness 0.2286)
				)
			)
		)
		(sheetname "MAC")
		(sheetfile "MAC.kicad_sch")
		(duplicate_pad_numbers_are_jumpers no)
		(pad "1" smd rect
			(at -0.65 0 90)
			(size 0.8 0.6)
			(layers "F.Cu" "F.Mask" "F.Paste")
			(net "GND")
		)
		(pad "2" smd rect
			(at 0.65 0 90)
			(size 0.8 0.6)
			(layers "F.Cu" "F.Mask" "F.Paste")
			(net "FPGA_MAC_PPS_IN1-")
		)
	)
	(footprint "Vault:CAPC1608X87X45ML20T05"
		(layer "F.Cu")
		(at 197.3761 84.2786 -90)
		(property "Reference" "C31"
			(at 2.721395 -0.026921 90)
			(unlocked yes)
			(layer "F.SilkS")
			(effects
				(font
					(size 0.762 0.762)
					(thickness 0.2286)
				)
			)
		)
		(property "Value" "0.1uF"
			(at 2.069035 2.630671 270)
			(unlocked yes)
			(layer "F.SilkS")
			(hide yes)
			(effects
				(font
					(size 0.762 0.762)
					(thickness 0.2286)
				)
			)
		)
		(sheetname "GPS_IMU_SENSORS")
		(sheetfile "GPS_IMU_SENSORS.kicad_sch")
		(duplicate_pad_numbers_are_jumpers no)
		(pad "1" smd rect
			(at -0.7 0)
			(size 1.1 1.05)
			(layers "F.Cu" "F.Mask" "F.Paste")
			(net "GND")
		)
		(pad "2" smd rect
			(at 0.7 0)
			(size 1.1 1.05)
			(layers "F.Cu" "F.Mask" "F.Paste")
			(net "+3.3V")
		)
	)
	(footprint "Vault:FP-IHLP-2525EZ-FP_2_413x3-MFG"
		(layer "F.Cu")
		(at 218.8261 125.2162)
		(property "Reference" "L2"
			(at 3.706655 2.6 270)
			(unlocked yes)
			(layer "F.SilkS")
			(effects
				(font
					(size 0.762 0.762)
					(thickness 0.2286)
				)
				(justify left bottom)
			)
		)
		(property "Value" "2.2uH_10A"
			(at -11.1787 10.976845 0)
			(unlocked yes)
			(layer "F.SilkS")
			(hide yes)
			(effects
				(font
					(size 0.762 0.762)
					(thickness 0.2286)
				)
				(justify left bottom)
			)
		)
		(sheetname "POWER")
		(sheetfile "POWER.kicad_sch")
		(duplicate_pad_numbers_are_jumpers no)
		(fp_line
			(start -3.362 -3.362)
			(end 3.362 -3.362)
			(stroke
				(width 0.2)
				(type solid)
			)
			(layer "F.SilkS")
		)
		(fp_line
			(start -3.362 -2.0895)
			(end -3.362 -3.362)
			(stroke
				(width 0.2)
				(type solid)
			)
			(layer "F.SilkS")
		)
		(fp_line
			(start -3.362 3.362)
			(end -3.362 2.0895)
			(stroke
				(width 0.2)
				(type solid)
			)
			(layer "F.SilkS")
		)
		(fp_line
			(start -3.362 3.362)
			(end 3.362 3.362)
			(stroke
				(width 0.2)
				(type solid)
			)
			(layer "F.SilkS")
		)
		(fp_line
			(start 3.362 -2.0895)
			(end 3.362 -3.362)
			(stroke
				(width 0.2)
				(type solid)
			)
			(layer "F.SilkS")
		)
		(fp_line
			(start 3.362 3.362)
			(end 3.362 2.0895)
			(stroke
				(width 0.2)
				(type solid)
			)
			(layer "F.SilkS")
		)
		(fp_line
			(start -4.2275 -3.462)
			(end 4.2275 -3.462)
			(stroke
				(width 0.2)
				(type solid)
			)
			(layer "F.CrtYd")
		)
		(fp_line
			(start -4.2275 3.462)
			(end -4.2275 -3.462)
			(stroke
				(width 0.2)
				(type solid)
			)
			(layer "F.CrtYd")
		)
		(fp_line
			(start -4.2275 3.462)
			(end 4.2275 3.462)
			(stroke
				(width 0.2)
				(type solid)
			)
			(layer "F.CrtYd")
		)
		(fp_line
			(start 4.2275 3.462)
			(end 4.2275 -3.462)
			(stroke
				(width 0.2)
				(type solid)
			)
			(layer "F.CrtYd")
		)
		(fp_line
			(start -4.2275 -3.462)
			(end 4.2275 -3.462)
			(stroke
				(width 0.2)
				(type solid)
			)
			(layer "F.Fab")
		)
		(fp_line
			(start -4.2275 3.462)
			(end -4.2275 -3.462)
			(stroke
				(width 0.2)
				(type solid)
			)
			(layer "F.Fab")
		)
		(fp_line
			(start -4.2275 3.462)
			(end 4.2275 3.462)
			(stroke
				(width 0.2)
				(type solid)
			)
			(layer "F.Fab")
		)
		(fp_line
			(start -0.5 0)
			(end 0.5 0)
			(stroke
				(width 0.1)
				(type solid)
			)
			(layer "F.Fab")
		)
		(fp_line
			(start 0 0.5)
			(end 0 -0.5)
			(stroke
				(width 0.1)
				(type solid)
			)
			(layer "F.Fab")
		)
		(fp_line
			(start 4.2275 3.462)
			(end 4.2275 -3.462)
			(stroke
				(width 0.2)
				(type solid)
			)
			(layer "F.Fab")
		)
		(fp_text user "${REFERENCE}"
			(at -0.00001 0.10711 360)
			(unlocked yes)
			(layer "F.Fab")
			(effects
				(font
					(face "Arial")
					(size 0.63 0.63)
					(thickness 0.1)
				)
				(justify left bottom)
			)
		)
		(pad "1" smd rect
			(at -2.921 0)
			(size 2.413 3.429)
			(layers "F.Cu" "F.Mask" "F.Paste")
			(net "NetL2_1")
			(solder_mask_margin 0)
			(solder_paste_margin 0)
		)
		(pad "2" smd rect
			(at 2.921 0)
			(size 2.413 3.429)
			(layers "F.Cu" "F.Mask" "F.Paste")
			(net "P3V3_SENSE")
			(solder_mask_margin 0)
			(solder_paste_margin 0)
		)
	)
	(footprint "Vault:FP-SML-LX0603IW-TR-MFG"
		(layer "F.Cu")
		(at 167.2261 88.1162 -90)
		(property "Reference" "D25"
			(at -0.1286 1.673069 90)
			(unlocked yes)
			(layer "F.SilkS")
			(effects
				(font
					(size 0.762 0.762)
					(thickness 0.2286)
				)
			)
		)
		(property "Value" "SML-LX0603IW-TR"
			(at -3.519671 10.677135 180)
			(unlocked yes)
			(layer "F.SilkS")
			(hide yes)
			(effects
				(font
					(size 0.762 0.762)
					(thickness 0.2286)
				)
			)
		)
		(sheetname "USBUart_DipSelects")
		(sheetfile "USBUart_DipSelects.kicad_sch")
		(duplicate_pad_numbers_are_jumpers no)
		(fp_line
			(start 0.77933 0.73)
			(end -0.82067 0.73)
			(stroke
				(width 0.2)
				(type solid)
			)
			(layer "F.SilkS")
		)
		(fp_line
			(start 0.8 -0.75)
			(end -0.8 -0.75)
			(stroke
				(width 0.2)
				(type solid)
			)
			(layer "F.SilkS")
		)
		(fp_circle
			(center -1.725 0)
			(end -1.85 0)
			(stroke
				(width 0.25)
				(type solid)
			)
			(fill no)
			(layer "F.SilkS")
		)
		(fp_line
			(start -1.25 0.625)
			(end -1.25 -0.625)
			(stroke
				(width 0.2)
				(type solid)
			)
			(layer "F.CrtYd")
		)
		(fp_line
			(start 1.25 0.625)
			(end -1.25 0.625)
			(stroke
				(width 0.2)
				(type solid)
			)
			(layer "F.CrtYd")
		)
		(fp_line
			(start 1.25 0.625)
			(end 1.25 -0.625)
			(stroke
				(width 0.2)
				(type solid)
			)
			(layer "F.CrtYd")
		)
		(fp_line
			(start 1.25 -0.625)
			(end -1.25 -0.625)
			(stroke
				(width 0.2)
				(type solid)
			)
			(layer "F.CrtYd")
		)
		(fp_line
			(start -1.25 0.625)
			(end -1.25 -0.625)
			(stroke
				(width 0.2)
				(type solid)
			)
			(layer "F.Fab")
		)
		(fp_line
			(start 1.25 0.625)
			(end -1.25 0.625)
			(stroke
				(width 0.2)
				(type solid)
			)
			(layer "F.Fab")
		)
		(fp_line
			(start 1.25 0.625)
			(end 1.25 -0.625)
			(stroke
				(width 0.2)
				(type solid)
			)
			(layer "F.Fab")
		)
		(fp_line
			(start 0 0.5)
			(end 0 -0.5)
			(stroke
				(width 0.1)
				(type solid)
			)
			(layer "F.Fab")
		)
		(fp_line
			(start 0.5 0)
			(end -0.5 0)
			(stroke
				(width 0.1)
				(type solid)
			)
			(layer "F.Fab")
		)
		(fp_line
			(start 1.25 -0.625)
			(end -1.25 -0.625)
			(stroke
				(width 0.2)
				(type solid)
			)
			(layer "F.Fab")
		)
		(fp_text user "${REFERENCE}"
			(at 0 0.28425 270)
			(unlocked yes)
			(layer "F.Fab")
			(effects
				(font
					(face "Arial")
					(size 0.63 0.63)
					(thickness 0.1)
				)
				(justify left bottom)
			)
		)
		(pad "1" smd rect
			(at -0.75 0 270)
			(size 0.8 0.8)
			(layers "F.Cu" "F.Mask" "F.Paste")
			(net "NetD25_1")
			(solder_mask_margin 0)
			(solder_paste_margin 0)
		)
		(pad "2" smd rect
			(at 0.75 0 270)
			(size 0.8 0.8)
			(layers "F.Cu" "F.Mask" "F.Paste")
			(net "+3.3V")
			(solder_mask_margin 0)
			(solder_paste_margin 0)
		)
	)
	(footprint "Vault:CAPC1608X87X45ML20T05"
		(layer "F.Cu")
		(at 151.54502 80.89267 -90)
		(property "Reference" "C63"
			(at -0.27647 1.125575 90)
			(unlocked yes)
			(layer "F.SilkS")
			(effects
				(font
					(size 0.762 0.762)
					(thickness 0.2286)
				)
				(justify left bottom)
			)
		)
		(property "Value" "0.1uF"
			(at 1.829705 -4.27006 0)
			(unlocked yes)
			(layer "F.SilkS")
			(hide yes)
			(effects
				(font
					(size 0.762 0.762)
					(thickness 0.2286)
				)
				(justify left bottom)
			)
		)
		(sheetname "MAC")
		(sheetfile "MAC.kicad_sch")
		(duplicate_pad_numbers_are_jumpers no)
		(pad "1" smd rect
			(at -0.7 0)
			(size 1.1 1.05)
			(layers "F.Cu" "F.Mask" "F.Paste")
			(net "GND")
		)
		(pad "2" smd rect
			(at 0.7 0)
			(size 1.1 1.05)
			(layers "F.Cu" "F.Mask" "F.Paste")
			(net "MAC_VCC")
		)
	)
	(footprint "Vault:CAPC1608X87X45ML20T05"
		(layer "F.Cu")
		(at 84.1261 87.1162 90)
		(property "Reference" "C40"
			(at 0.4786 -3.473069 90)
			(unlocked yes)
			(layer "F.SilkS")
			(effects
				(font
					(size 0.762 0.762)
					(thickness 0.2286)
				)
			)
		)
		(property "Value" "0.1uF"
			(at 2.069035 2.630671 90)
			(unlocked yes)
			(layer "F.SilkS")
			(hide yes)
			(effects
				(font
					(size 0.762 0.762)
					(thickness 0.2286)
				)
			)
		)
		(sheetname "USER_IO_STATUS")
		(sheetfile "USER_IO_STATUS.kicad_sch")
		(duplicate_pad_numbers_are_jumpers no)
		(pad "1" smd rect
			(at -0.7 0 180)
			(size 1.1 1.05)
			(layers "F.Cu" "F.Mask" "F.Paste")
			(net "GND")
		)
		(pad "2" smd rect
			(at 0.7 0 180)
			(size 1.1 1.05)
			(layers "F.Cu" "F.Mask" "F.Paste")
			(net "+3.3V")
		)
	)
	(footprint "Vault:RESC1005X40X25LL05T05"
		(layer "F.Cu")
		(at 184.6261 82.8162)
		(property "Reference" "R54"
			(at -2.1714 -1.673079 0)
			(unlocked yes)
			(layer "F.SilkS")
			(effects
				(font
					(size 0.762 0.762)
					(thickness 0.2286)
				)
			)
		)
		(property "Value" "0_1%_0402"
			(at -2.579871 6.66536 270)
			(unlocked yes)
			(layer "F.SilkS")
			(hide yes)
			(effects
				(font
					(size 0.762 0.762)
					(thickness 0.2286)
				)
			)
		)
		(sheetname "GPS_IMU_SENSORS")
		(sheetfile "GPS_IMU_SENSORS.kicad_sch")
		(duplicate_pad_numbers_are_jumpers no)
		(pad "1" smd rect
			(at -0.4 0 90)
			(size 0.45 0.45)
			(layers "F.Cu" "F.Mask" "F.Paste")
			(net "PCIE_PERST")
		)
		(pad "2" smd rect
			(at 0.4 0 90)
			(size 0.45 0.45)
			(layers "F.Cu" "F.Mask" "F.Paste")
			(net "NetR52_1")
		)
	)
	(footprint "Vault:CAPC1608X87X45ML20T05"
		(layer "F.Cu")
		(at 232.8261 67.1162 180)
		(property "Reference" "C64"
			(at -0.4286 1.473079 0)
			(unlocked yes)
			(layer "F.SilkS")
			(effects
				(font
					(size 0.762 0.762)
					(thickness 0.2286)
				)
			)
		)
		(property "Value" "0.1uF"
			(at 2.069035 2.630671 180)
			(unlocked yes)
			(layer "F.SilkS")
			(hide yes)
			(effects
				(font
					(size 0.762 0.762)
					(thickness 0.2286)
				)
			)
		)
		(sheetname "GPS_IMU_SENSORS")
		(sheetfile "GPS_IMU_SENSORS.kicad_sch")
		(duplicate_pad_numbers_are_jumpers no)
		(pad "1" smd rect
			(at -0.7 0 270)
			(size 1.1 1.05)
			(layers "F.Cu" "F.Mask" "F.Paste")
			(net "GND")
		)
		(pad "2" smd rect
			(at 0.7 0 270)
			(size 1.1 1.05)
			(layers "F.Cu" "F.Mask" "F.Paste")
			(net "+5.0V")
		)
	)
	(footprint "Vault:FP-CL829-IPC_C"
		(layer "F.Cu")
		(at 231.8261 83.2162 180)
		(property "Reference" "C90"
			(at 1.8714 -0.026921 0)
			(unlocked yes)
			(layer "F.SilkS")
			(effects
				(font
					(size 0.762 0.762)
					(thickness 0.2286)
				)
			)
		)
		(property "Value" "4.7uF_16V_0402"
			(at -2.440151 9.864615 90)
			(unlocked yes)
			(layer "F.SilkS")
			(hide yes)
			(effects
				(font
					(size 0.762 0.762)
					(thickness 0.2286)
				)
			)
		)
		(sheetname "USBUart_DipSelects")
		(sheetfile "USBUart_DipSelects.kicad_sch")
		(duplicate_pad_numbers_are_jumpers no)
		(fp_line
			(start 0.63624 0.675)
			(end -0.63624 0.675)
			(stroke
				(width 0.2)
				(type solid)
			)
			(layer "F.SilkS")
		)
		(fp_line
			(start 0.63624 -0.675)
			(end -0.63624 -0.675)
			(stroke
				(width 0.2)
				(type solid)
			)
			(layer "F.SilkS")
		)
		(fp_line
			(start 0.73624 0.375)
			(end -0.73624 0.375)
			(stroke
				(width 0.2)
				(type solid)
			)
			(layer "F.CrtYd")
		)
		(fp_line
			(start 0.73624 -0.375)
			(end 0.73624 0.375)
			(stroke
				(width 0.2)
				(type solid)
			)
			(layer "F.CrtYd")
		)
		(fp_line
			(start 0.73624 -0.375)
			(end -0.73624 -0.375)
			(stroke
				(width 0.2)
				(type solid)
			)
			(layer "F.CrtYd")
		)
		(fp_line
			(start -0.73624 -0.375)
			(end -0.73624 0.375)
			(stroke
				(width 0.2)
				(type solid)
			)
			(layer "F.CrtYd")
		)
		(fp_line
			(start 0.73624 0.375)
			(end -0.73624 0.375)
			(stroke
				(width 0.2)
				(type solid)
			)
			(layer "F.Fab")
		)
		(fp_line
			(start 0.73624 -0.375)
			(end 0.73624 0.375)
			(stroke
				(width 0.2)
				(type solid)
			)
			(layer "F.Fab")
		)
		(fp_line
			(start 0.73624 -0.375)
			(end -0.73624 -0.375)
			(stroke
				(width 0.2)
				(type solid)
			)
			(layer "F.Fab")
		)
		(fp_line
			(start 0.5 0)
			(end -0.5 0)
			(stroke
				(width 0.1)
				(type solid)
			)
			(layer "F.Fab")
		)
		(fp_line
			(start 0.5 0)
			(end -0.5 0)
			(stroke
				(width 0.1)
				(type solid)
			)
			(layer "F.Fab")
		)
		(fp_line
			(start 0 -0.5)
			(end 0 0.5)
			(stroke
				(width 0.1)
				(type solid)
			)
			(layer "F.Fab")
		)
		(fp_line
			(start 0 -0.5)
			(end 0 0.5)
			(stroke
				(width 0.1)
				(type solid)
			)
			(layer "F.Fab")
		)
		(fp_line
			(start -0.73624 -0.375)
			(end -0.73624 0.375)
			(stroke
				(width 0.2)
				(type solid)
			)
			(layer "F.Fab")
		)
		(fp_text user "${REFERENCE}"
			(at 0 0.28425 180)
			(unlocked yes)
			(layer "F.Fab")
			(effects
				(font
					(face "Arial")
					(size 0.63 0.63)
					(thickness 0.1)
				)
				(justify left bottom)
			)
		)
		(pad "1" smd rect
			(at -0.37856 0 180)
			(size 0.51535 0.47247)
			(layers "F.Cu" "F.Mask" "F.Paste")
			(net "FTDI_VBUS")
			(solder_mask_margin 0)
			(solder_paste_margin 0)
		)
		(pad "2" smd rect
			(at 0.37856 0 180)
			(size 0.51535 0.47247)
			(layers "F.Cu" "F.Mask" "F.Paste")
			(net "GND")
			(solder_mask_margin 0)
			(solder_paste_margin 0)
		)
	)
	(footprint "Vault:FP-0603-L_1_6_0_2-W_0_8_0-MFG"
		(layer "F.Cu")
		(at 198.9261 89.1162 180)
		(property "Reference" "C20"
			(at -1.336 -0.346345 0)
			(unlocked yes)
			(layer "F.SilkS")
			(effects
				(font
					(size 0.762 0.762)
					(thickness 0.2286)
				)
				(justify left bottom)
			)
		)
		(property "Value" "10uF_16V_0603"
			(at -6.5525 -3.826045 0)
			(unlocked yes)
			(layer "F.SilkS")
			(hide yes)
			(effects
				(font
					(size 0.762 0.762)
					(thickness 0.2286)
				)
				(justify left bottom)
			)
		)
		(sheetname "POWER")
		(sheetfile "POWER.kicad_sch")
		(duplicate_pad_numbers_are_jumpers no)
		(fp_line
			(start 0.9 0.825)
			(end -0.9 0.825)
			(stroke
				(width 0.2)
				(type solid)
			)
			(layer "F.SilkS")
		)
		(fp_line
			(start 0.9 -0.825)
			(end -0.9 -0.825)
			(stroke
				(width 0.2)
				(type solid)
			)
			(layer "F.SilkS")
		)
		(fp_line
			(start 1.15 0.6)
			(end -1.15 0.6)
			(stroke
				(width 0.2)
				(type solid)
			)
			(layer "F.CrtYd")
		)
		(fp_line
			(start 1.15 -0.6)
			(end 1.15 0.6)
			(stroke
				(width 0.2)
				(type solid)
			)
			(layer "F.CrtYd")
		)
		(fp_line
			(start 1.15 -0.6)
			(end -1.15 -0.6)
			(stroke
				(width 0.2)
				(type solid)
			)
			(layer "F.CrtYd")
		)
		(fp_line
			(start -1.15 -0.6)
			(end -1.15 0.6)
			(stroke
				(width 0.2)
				(type solid)
			)
			(layer "F.CrtYd")
		)
		(fp_line
			(start 1.15 0.6)
			(end -1.15 0.6)
			(stroke
				(width 0.2)
				(type solid)
			)
			(layer "F.Fab")
		)
		(fp_line
			(start 1.15 -0.6)
			(end 1.15 0.6)
			(stroke
				(width 0.2)
				(type solid)
			)
			(layer "F.Fab")
		)
		(fp_line
			(start 1.15 -0.6)
			(end -1.15 -0.6)
			(stroke
				(width 0.2)
				(type solid)
			)
			(layer "F.Fab")
		)
		(fp_line
			(start 0.5 0)
			(end -0.5 0)
			(stroke
				(width 0.1)
				(type solid)
			)
			(layer "F.Fab")
		)
		(fp_line
			(start 0 -0.5)
			(end 0 0.5)
			(stroke
				(width 0.1)
				(type solid)
			)
			(layer "F.Fab")
		)
		(fp_line
			(start -1.15 -0.6)
			(end -1.15 0.6)
			(stroke
				(width 0.2)
				(type solid)
			)
			(layer "F.Fab")
		)
		(fp_text user "${REFERENCE}"
			(at -0.00001 0.09602 180)
			(unlocked yes)
			(layer "F.Fab")
			(effects
				(font
					(face "Arial")
					(size 0.63 0.63)
					(thickness 0.1)
				)
				(justify left bottom)
			)
		)
		(pad "1" smd rect
			(at -0.7 0 180)
			(size 0.7 0.7)
			(layers "F.Cu" "F.Mask" "F.Paste")
			(net "+3.3V")
			(solder_mask_margin 0)
			(solder_paste_margin 0)
		)
		(pad "2" smd rect
			(at 0.7 0 180)
			(size 0.7 0.7)
			(layers "F.Cu" "F.Mask" "F.Paste")
			(net "GND")
			(solder_mask_margin 0)
			(solder_paste_margin 0)
		)
	)
	(footprint "Vault:SOT143-4L"
		(layer "F.Cu")
		(at 71.8761 128.1162 90)
		(property "Reference" "D2"
			(at -2.926921 1.178595 0)
			(unlocked yes)
			(layer "F.SilkS")
			(effects
				(font
					(size 0.762 0.762)
					(thickness 0.2286)
				)
			)
		)
		(property "Value" "8240136"
			(at 2.6781 3.341871 90)
			(unlocked yes)
			(layer "F.SilkS")
			(hide yes)
			(effects
				(font
					(size 0.762 0.762)
					(thickness 0.2286)
				)
			)
		)
		(sheetname "USER_IO")
		(sheetfile "USER_IO.kicad_sch")
		(duplicate_pad_numbers_are_jumpers no)
		(fp_line
			(start 2.05 -1.7)
			(end 2.05 1.7)
			(stroke
				(width 0.2)
				(type solid)
			)
			(layer "F.SilkS")
		)
		(fp_line
			(start -2.05 -1.7)
			(end 2.05 -1.7)
			(stroke
				(width 0.2)
				(type solid)
			)
			(layer "F.SilkS")
		)
		(fp_line
			(start -2.05 -1.7)
			(end -2.05 1.675)
			(stroke
				(width 0.2)
				(type solid)
			)
			(layer "F.SilkS")
		)
		(fp_line
			(start -2.05 1.7)
			(end 2.05 1.7)
			(stroke
				(width 0.2)
				(type solid)
			)
			(layer "F.SilkS")
		)
		(fp_circle
			(center -2.404 -1.075)
			(end -2.15 -1.075)
			(stroke
				(width 0.2)
				(type solid)
			)
			(fill no)
			(layer "F.SilkS")
		)
		(pad "1" smd rect
			(at -1.1 -0.75 180)
			(size 1.4 1.4)
			(layers "F.Cu" "F.Mask" "F.Paste")
			(net "GND")
		)
		(pad "2" smd rect
			(at -1.1 0.95 180)
			(size 1 1.4)
			(layers "F.Cu" "F.Mask" "F.Paste")
			(net "NetAN4_1")
		)
		(pad "3" smd rect
			(at 1.1 0.95 180)
			(size 1 1.4)
			(layers "F.Cu" "F.Mask" "F.Paste")
			(net "NetAN3_1")
		)
		(pad "4" smd rect
			(at 1.1 -0.95 180)
			(size 1 1.4)
			(layers "F.Cu" "F.Mask" "F.Paste")
			(net "+3.3V")
		)
	)
	(footprint "Vault:CAPC1005X56X25NL10T15"
		(layer "F.Cu")
		(at 198.8261 91.0162)
		(property "Reference" "C19"
			(at 1.046 1.141655 180)
			(unlocked yes)
			(layer "F.SilkS")
			(effects
				(font
					(size 0.762 0.762)
					(thickness 0.2286)
				)
				(justify left bottom)
			)
		)
		(property "Value" "0.1uF_0402"
			(at 9.4735 -2.041355 0)
			(unlocked yes)
			(layer "F.SilkS")
			(hide yes)
			(effects
				(font
					(size 0.762 0.762)
					(thickness 0.2286)
				)
				(justify left bottom)
			)
		)
		(sheetname "POWER")
		(sheetfile "POWER.kicad_sch")
		(duplicate_pad_numbers_are_jumpers no)
		(pad "1" smd rect
			(at -0.44 0 90)
			(size 0.64 0.68)
			(layers "F.Cu" "F.Mask" "F.Paste")
			(net "GND")
		)
		(pad "2" smd rect
			(at 0.44 0 90)
			(size 0.64 0.68)
			(layers "F.Cu" "F.Mask" "F.Paste")
			(net "+3.3V")
		)
	)
	(footprint "Vault:RESC1005X40X25LL05T05"
		(layer "F.Cu")
		(at 234.2261 116.6162 180)
		(property "Reference" "R66"
			(at -0.7286 -1.026921 0)
			(unlocked yes)
			(layer "F.SilkS")
			(effects
				(font
					(size 0.762 0.762)
					(thickness 0.2286)
				)
			)
		)
		(property "Value" "0_1%_0402"
			(at -2.579871 6.66536 90)
			(unlocked yes)
			(layer "F.SilkS")
			(hide yes)
			(effects
				(font
					(size 0.762 0.762)
					(thickness 0.2286)
				)
			)
		)
		(sheetname "POWER")
		(sheetfile "POWER.kicad_sch")
		(duplicate_pad_numbers_are_jumpers no)
		(pad "1" smd rect
			(at -0.4 0 270)
			(size 0.45 0.45)
			(layers "F.Cu" "F.Mask" "F.Paste")
			(net "NetR66_1")
		)
		(pad "2" smd rect
			(at 0.4 0 270)
			(size 0.45 0.45)
			(layers "F.Cu" "F.Mask" "F.Paste")
			(net "GND")
		)
	)
	(footprint "Vault:FP-0402-L_1_0_1-W_0_5_0_1-IPC_C"
		(layer "F.Cu")
		(at 237.5261 64.7162 90)
		(property "Reference" "C93"
			(at 2.1714 1.073069 270)
			(unlocked yes)
			(layer "F.SilkS")
			(effects
				(font
					(size 0.762 0.762)
					(thickness 0.2286)
				)
			)
		)
		(property "Value" "0.1uF_25V_0402"
			(at -2.465551 9.839215 0)
			(unlocked yes)
			(layer "F.SilkS")
			(hide yes)
			(effects
				(font
					(size 0.762 0.762)
					(thickness 0.2286)
				)
			)
		)
		(sheetname "USBUart_DipSelects")
		(sheetfile "USBUart_DipSelects.kicad_sch")
		(duplicate_pad_numbers_are_jumpers no)
		(fp_line
			(start -0.65607 -0.7)
			(end 0.65607 -0.7)
			(stroke
				(width 0.2)
				(type solid)
			)
			(layer "F.SilkS")
		)
		(fp_line
			(start -0.65607 0.7)
			(end 0.65607 0.7)
			(stroke
				(width 0.2)
				(type solid)
			)
			(layer "F.SilkS")
		)
		(fp_line
			(start 0.75607 -0.4)
			(end 0.75607 0.4)
			(stroke
				(width 0.2)
				(type solid)
			)
			(layer "F.CrtYd")
		)
		(fp_line
			(start -0.75607 -0.4)
			(end 0.75607 -0.4)
			(stroke
				(width 0.2)
				(type solid)
			)
			(layer "F.CrtYd")
		)
		(fp_line
			(start -0.75607 -0.4)
			(end -0.75607 0.4)
			(stroke
				(width 0.2)
				(type solid)
			)
			(layer "F.CrtYd")
		)
		(fp_line
			(start -0.75607 0.4)
			(end 0.75607 0.4)
			(stroke
				(width 0.2)
				(type solid)
			)
			(layer "F.CrtYd")
		)
		(fp_line
			(start 0 -0.5)
			(end 0 0.5)
			(stroke
				(width 0.1)
				(type solid)
			)
			(layer "F.Fab")
		)
		(fp_line
			(start 0.75607 -0.4)
			(end 0.75607 0.4)
			(stroke
				(width 0.2)
				(type solid)
			)
			(layer "F.Fab")
		)
		(fp_line
			(start -0.75607 -0.4)
			(end 0.75607 -0.4)
			(stroke
				(width 0.2)
				(type solid)
			)
			(layer "F.Fab")
		)
		(fp_line
			(start -0.75607 -0.4)
			(end -0.75607 0.4)
			(stroke
				(width 0.2)
				(type solid)
			)
			(layer "F.Fab")
		)
		(fp_line
			(start -0.5 0)
			(end 0.5 0)
			(stroke
				(width 0.1)
				(type solid)
			)
			(layer "F.Fab")
		)
		(fp_line
			(start -0.75607 0.4)
			(end 0.75607 0.4)
			(stroke
				(width 0.2)
				(type solid)
			)
			(layer "F.Fab")
		)
		(fp_text user "${REFERENCE}"
			(at -0.00001 0.09601 90)
			(unlocked yes)
			(layer "F.Fab")
			(effects
				(font
					(face "Arial")
					(size 0.63 0.63)
					(thickness 0.1)
				)
				(justify left bottom)
			)
		)
		(pad "1" smd rect
			(at -0.36554 0 90)
			(size 0.58106 0.51213)
			(layers "F.Cu" "F.Mask" "F.Paste")
			(net "NetC92_1")
			(solder_mask_margin 0)
			(solder_paste_margin 0)
		)
		(pad "2" smd rect
			(at 0.36554 0 90)
			(size 0.58106 0.51213)
			(layers "F.Cu" "F.Mask" "F.Paste")
			(net "GND")
			(solder_mask_margin 0)
			(solder_paste_margin 0)
		)
	)
	(footprint "Vault:CAPC1005X55X25LL05T10"
		(layer "F.Cu")
		(at 231.4261 75.7162 -90)
		(property "Reference" "C88"
			(at -0.1714 4.826931 270)
			(unlocked yes)
			(layer "F.SilkS")
			(effects
				(font
					(size 0.762 0.762)
					(thickness 0.2286)
				)
			)
		)
		(property "Value" "47pF_50V_0402"
			(at -2.656031 9.61078 180)
			(unlocked yes)
			(layer "F.SilkS")
			(hide yes)
			(effects
				(font
					(size 0.762 0.762)
					(thickness 0.2286)
				)
			)
		)
		(sheetname "USBUart_DipSelects")
		(sheetfile "USBUart_DipSelects.kicad_sch")
		(duplicate_pad_numbers_are_jumpers no)
		(pad "1" smd rect
			(at -0.39 0)
			(size 0.52 0.56)
			(layers "F.Cu" "F.Mask" "F.Paste")
			(net "GND")
		)
		(pad "2" smd rect
			(at 0.39 0)
			(size 0.52 0.56)
			(layers "F.Cu" "F.Mask" "F.Paste")
			(net "FTDI_USB_R_N")
		)
	)
	(footprint "Vault:RESC1005X40X25LL05T05"
		(layer "F.Cu")
		(at 98.7261 88.0162 -90)
		(property "Reference" "R48"
			(at 0.5286 1.126931 270)
			(unlocked yes)
			(layer "F.SilkS")
			(effects
				(font
					(size 0.762 0.762)
					(thickness 0.2286)
				)
			)
		)
		(property "Value" "0_1%_0402"
			(at -2.579871 6.66536 180)
			(unlocked yes)
			(layer "F.SilkS")
			(hide yes)
			(effects
				(font
					(size 0.762 0.762)
					(thickness 0.2286)
				)
			)
		)
		(sheetname "GPS_IMU_SENSORS")
		(sheetfile "GPS_IMU_SENSORS.kicad_sch")
		(duplicate_pad_numbers_are_jumpers no)
		(pad "1" smd rect
			(at -0.4 0)
			(size 0.45 0.45)
			(layers "F.Cu" "F.Mask" "F.Paste")
			(net "NetP1_5")
		)
		(pad "2" smd rect
			(at 0.4 0)
			(size 0.45 0.45)
			(layers "F.Cu" "F.Mask" "F.Paste")
			(net "MAC_FREQ_CTRL")
		)
	)
	(footprint "Vault:FP-SML-LX0603IW-TR-MFG"
		(layer "F.Cu")
		(at 234.0261 135.3162 180)
		(property "Reference" "D20"
			(at -0.2286 1.273079 0)
			(unlocked yes)
			(layer "F.SilkS")
			(effects
				(font
					(size 0.762 0.762)
					(thickness 0.2286)
				)
			)
		)
		(property "Value" "SML-LX0603IW-TR"
			(at -3.519671 10.677135 90)
			(unlocked yes)
			(layer "F.SilkS")
			(hide yes)
			(effects
				(font
					(size 0.762 0.762)
					(thickness 0.2286)
				)
			)
		)
		(sheetname "POWER")
		(sheetfile "POWER.kicad_sch")
		(duplicate_pad_numbers_are_jumpers no)
		(fp_line
			(start 0.8 -0.75)
			(end -0.8 -0.75)
			(stroke
				(width 0.2)
				(type solid)
			)
			(layer "F.SilkS")
		)
		(fp_line
			(start 0.77934 0.73)
			(end -0.82066 0.73)
			(stroke
				(width 0.2)
				(type solid)
			)
			(layer "F.SilkS")
		)
		(fp_circle
			(center -1.725 0)
			(end -1.725 0.125)
			(stroke
				(width 0.25)
				(type solid)
			)
			(fill no)
			(layer "F.SilkS")
		)
		(fp_line
			(start 1.25 0.625)
			(end -1.25 0.625)
			(stroke
				(width 0.2)
				(type solid)
			)
			(layer "F.CrtYd")
		)
		(fp_line
			(start 1.25 -0.625)
			(end 1.25 0.625)
			(stroke
				(width 0.2)
				(type solid)
			)
			(layer "F.CrtYd")
		)
		(fp_line
			(start 1.25 -0.625)
			(end -1.25 -0.625)
			(stroke
				(width 0.2)
				(type solid)
			)
			(layer "F.CrtYd")
		)
		(fp_line
			(start -1.25 -0.625)
			(end -1.25 0.625)
			(stroke
				(width 0.2)
				(type solid)
			)
			(layer "F.CrtYd")
		)
		(fp_line
			(start 1.25 0.625)
			(end -1.25 0.625)
			(stroke
				(width 0.2)
				(type solid)
			)
			(layer "F.Fab")
		)
		(fp_line
			(start 1.25 -0.625)
			(end 1.25 0.625)
			(stroke
				(width 0.2)
				(type solid)
			)
			(layer "F.Fab")
		)
		(fp_line
			(start 1.25 -0.625)
			(end -1.25 -0.625)
			(stroke
				(width 0.2)
				(type solid)
			)
			(layer "F.Fab")
		)
		(fp_line
			(start 0.5 0)
			(end -0.5 0)
			(stroke
				(width 0.1)
				(type solid)
			)
			(layer "F.Fab")
		)
		(fp_line
			(start 0 -0.5)
			(end 0 0.5)
			(stroke
				(width 0.1)
				(type solid)
			)
			(layer "F.Fab")
		)
		(fp_line
			(start -1.25 -0.625)
			(end -1.25 0.625)
			(stroke
				(width 0.2)
				(type solid)
			)
			(layer "F.Fab")
		)
		(fp_text user "${REFERENCE}"
			(at 0.00001 0.28425 180)
			(unlocked yes)
			(layer "F.Fab")
			(effects
				(font
					(face "Arial")
					(size 0.63 0.63)
					(thickness 0.1)
				)
				(justify left bottom)
			)
		)
		(pad "1" smd rect
			(at -0.75 0 180)
			(size 0.8 0.8)
			(layers "F.Cu" "F.Mask" "F.Paste")
			(net "NetD20_1")
			(solder_mask_margin 0)
			(solder_paste_margin 0)
		)
		(pad "2" smd rect
			(at 0.75 0 180)
			(size 0.8 0.8)
			(layers "F.Cu" "F.Mask" "F.Paste")
			(net "+3.3V")
			(solder_mask_margin 0)
			(solder_paste_margin 0)
		)
	)
	(footprint "Vault:FP-D0008A-MFG"
		(layer "F.Cu")
		(at 203.1261 87.2162 -90)
		(property "Reference" "U2"
			(at 6.13379 -2.264855 90)
			(unlocked yes)
			(layer "F.SilkS")
			(effects
				(font
					(size 0.762 0.762)
					(thickness 0.2286)
				)
				(justify left bottom)
			)
		)
		(property "Value" "INA219BIDR"
			(at 9.427445 -10.9955 0)
			(unlocked yes)
			(layer "F.SilkS")
			(hide yes)
			(effects
				(font
					(size 0.762 0.762)
					(thickness 0.2286)
				)
				(justify left bottom)
			)
		)
		(sheetname "POWER")
		(sheetfile "POWER.kicad_sch")
		(duplicate_pad_numbers_are_jumpers no)
		(fp_line
			(start -1.5 2.5)
			(end -1.5 -2.5)
			(stroke
				(width 0.2)
				(type solid)
			)
			(layer "F.SilkS")
		)
		(fp_line
			(start 1.5 2.5)
			(end -1.5 2.5)
			(stroke
				(width 0.2)
				(type solid)
			)
			(layer "F.SilkS")
		)
		(fp_line
			(start 1.5 2.5)
			(end 1.5 -2.5)
			(stroke
				(width 0.2)
				(type solid)
			)
			(layer "F.SilkS")
		)
		(fp_line
			(start 1.5 -2.5)
			(end -1.5 -2.5)
			(stroke
				(width 0.2)
				(type solid)
			)
			(layer "F.SilkS")
		)
		(fp_circle
			(center -0.725 -1.725)
			(end -0.975 -1.725)
			(stroke
				(width 0.5)
				(type solid)
			)
			(fill no)
			(layer "F.SilkS")
		)
		(fp_circle
			(center -4.05 -1.905)
			(end -4.175 -1.905)
			(stroke
				(width 0.25)
				(type solid)
			)
			(fill no)
			(layer "F.SilkS")
		)
		(fp_line
			(start -3.575 2.75)
			(end -3.575 -2.75)
			(stroke
				(width 0.2)
				(type solid)
			)
			(layer "F.CrtYd")
		)
		(fp_line
			(start 3.575 2.75)
			(end -3.575 2.75)
			(stroke
				(width 0.2)
				(type solid)
			)
			(layer "F.CrtYd")
		)
		(fp_line
			(start 3.575 2.75)
			(end 3.575 -2.75)
			(stroke
				(width 0.2)
				(type solid)
			)
			(layer "F.CrtYd")
		)
		(fp_line
			(start 3.575 -2.75)
			(end -3.575 -2.75)
			(stroke
				(width 0.2)
				(type solid)
			)
			(layer "F.CrtYd")
		)
		(fp_line
			(start -3.575 2.75)
			(end -3.575 -2.75)
			(stroke
				(width 0.2)
				(type solid)
			)
			(layer "F.Fab")
		)
		(fp_line
			(start 3.575 2.75)
			(end -3.575 2.75)
			(stroke
				(width 0.2)
				(type solid)
			)
			(layer "F.Fab")
		)
		(fp_line
			(start 3.575 2.75)
			(end 3.575 -2.75)
			(stroke
				(width 0.2)
				(type solid)
			)
			(layer "F.Fab")
		)
		(fp_line
			(start 0 0.5)
			(end 0 -0.5)
			(stroke
				(width 0.1)
				(type solid)
			)
			(layer "F.Fab")
		)
		(fp_line
			(start 0.5 0)
			(end -0.5 0)
			(stroke
				(width 0.1)
				(type solid)
			)
			(layer "F.Fab")
		)
		(fp_line
			(start 3.575 -2.75)
			(end -3.575 -2.75)
			(stroke
				(width 0.2)
				(type solid)
			)
			(layer "F.Fab")
		)
		(fp_text user "${REFERENCE}"
			(at -0.00001 0.09602 270)
			(unlocked yes)
			(layer "F.Fab")
			(effects
				(font
					(face "Arial")
					(size 0.63 0.63)
					(thickness 0.1)
				)
				(justify left bottom)
			)
		)
		(pad "1" smd roundrect
			(at -2.7 -1.905 270)
			(size 1.55 0.6)
			(layers "F.Cu" "F.Mask" "F.Paste")
			(roundrect_rratio 0.085)
			(net "NetR64_1")
			(solder_mask_margin 0)
			(solder_paste_margin 0)
		)
		(pad "2" smd roundrect
			(at -2.7 -0.635 270)
			(size 1.55 0.6)
			(layers "F.Cu" "F.Mask" "F.Paste")
			(roundrect_rratio 0.085)
			(net "NetR62_1")
			(solder_mask_margin 0)
			(solder_paste_margin 0)
		)
		(pad "3" smd roundrect
			(at -2.7 0.635 270)
			(size 1.55 0.6)
			(layers "F.Cu" "F.Mask" "F.Paste")
			(roundrect_rratio 0.085)
			(net "SDA")
			(solder_mask_margin 0)
			(solder_paste_margin 0)
		)
		(pad "4" smd roundrect
			(at -2.7 1.905 270)
			(size 1.55 0.6)
			(layers "F.Cu" "F.Mask" "F.Paste")
			(roundrect_rratio 0.085)
			(net "SCL")
			(solder_mask_margin 0)
			(solder_paste_margin 0)
		)
		(pad "5" smd roundrect
			(at 2.7 1.905 270)
			(size 1.55 0.6)
			(layers "F.Cu" "F.Mask" "F.Paste")
			(roundrect_rratio 0.085)
			(net "+3.3V")
			(solder_mask_margin 0)
			(solder_paste_margin 0)
		)
		(pad "6" smd roundrect
			(at 2.7 0.635 270)
			(size 1.55 0.6)
			(layers "F.Cu" "F.Mask" "F.Paste")
			(roundrect_rratio 0.085)
			(net "GND")
			(solder_mask_margin 0)
			(solder_paste_margin 0)
		)
		(pad "7" smd roundrect
			(at 2.7 -0.635 270)
			(size 1.55 0.6)
			(layers "F.Cu" "F.Mask" "F.Paste")
			(roundrect_rratio 0.085)
			(net "+12V")
			(solder_mask_margin 0)
			(solder_paste_margin 0)
		)
		(pad "8" smd roundrect
			(at 2.7 -1.905 270)
			(size 1.55 0.6)
			(layers "F.Cu" "F.Mask" "F.Paste")
			(roundrect_rratio 0.085)
			(net "+12V_SENS")
			(solder_mask_margin 0)
			(solder_paste_margin 0)
		)
	)
	(footprint "Vault:FP-RUT0012A-MFG"
		(layer "F.Cu")
		(at 219.8761 78.8162)
		(property "Reference" "U21"
			(at 0.078605 -2.173069 0)
			(unlocked yes)
			(layer "F.SilkS")
			(effects
				(font
					(size 0.762 0.762)
					(thickness 0.2286)
				)
			)
		)
		(property "Value" "TMUX1072RUTR"
			(at 7.426665 3.164071 0)
			(unlocked yes)
			(layer "F.SilkS")
			(hide yes)
			(effects
				(font
					(size 0.762 0.762)
					(thickness 0.2286)
				)
			)
		)
		(sheetname "USBUart_DipSelects")
		(sheetfile "USBUart_DipSelects.kicad_sch")
		(duplicate_pad_numbers_are_jumpers no)
		(fp_line
			(start -0.9 -1.525)
			(end 0.9 -1.525)
			(stroke
				(width 0.2)
				(type solid)
			)
			(layer "F.SilkS")
		)
		(fp_line
			(start -0.9 1.525)
			(end 0.9 1.525)
			(stroke
				(width 0.2)
				(type solid)
			)
			(layer "F.SilkS")
		)
		(fp_circle
			(center -1.575 -0.8)
			(end -1.575 -0.925)
			(stroke
				(width 0.25)
				(type solid)
			)
			(fill no)
			(layer "F.SilkS")
		)
		(fp_rect
			(start -0.85 -0.3)
			(end -0.35 -0.5)
			(stroke
				(width 0)
				(type default)
			)
			(fill yes)
			(layer "F.Paste")
		)
		(fp_rect
			(start -0.85 0.1)
			(end -0.35 -0.1)
			(stroke
				(width 0)
				(type default)
			)
			(fill yes)
			(layer "F.Paste")
		)
		(fp_rect
			(start -0.85 0.5)
			(end -0.35 0.3)
			(stroke
				(width 0)
				(type default)
			)
			(fill yes)
			(layer "F.Paste")
		)
		(fp_rect
			(start -0.85 0.9)
			(end -0.35 0.7)
			(stroke
				(width 0)
				(type default)
			)
			(fill yes)
			(layer "F.Paste")
		)
		(fp_rect
			(start -0.1 -0.5)
			(end 0.1 -1)
			(stroke
				(width 0)
				(type default)
			)
			(fill yes)
			(layer "F.Paste")
		)
		(fp_rect
			(start -0.1 1)
			(end 0.1 0.5)
			(stroke
				(width 0)
				(type default)
			)
			(fill yes)
			(layer "F.Paste")
		)
		(fp_rect
			(start 0.35 -0.7)
			(end 0.85 -0.9)
			(stroke
				(width 0)
				(type default)
			)
			(fill yes)
			(layer "F.Paste")
		)
		(fp_rect
			(start 0.35 -0.3)
			(end 0.85 -0.5)
			(stroke
				(width 0)
				(type default)
			)
			(fill yes)
			(layer "F.Paste")
		)
		(fp_rect
			(start 0.35 0.1)
			(end 0.85 -0.1)
			(stroke
				(width 0)
				(type default)
			)
			(fill yes)
			(layer "F.Paste")
		)
		(fp_rect
			(start 0.35 0.5)
			(end 0.85 0.3)
			(stroke
				(width 0)
				(type default)
			)
			(fill yes)
			(layer "F.Paste")
		)
		(fp_rect
			(start 0.35 0.9)
			(end 0.85 0.7)
			(stroke
				(width 0)
				(type default)
			)
			(fill yes)
			(layer "F.Paste")
		)
		(fp_poly
			(pts
				(xy -0.5 -1) (xy -0.35 -1) (xy -0.35 -0.7) (xy -0.85 -0.7) (xy -0.85 -0.9) (xy -0.5 -0.9)
			)
			(stroke
				(width 0)
				(type default)
			)
			(fill yes)
			(layer "F.Paste")
		)
		(fp_line
			(start -1.05 -1.2)
			(end 1.05 -1.2)
			(stroke
				(width 0.2)
				(type solid)
			)
			(layer "F.CrtYd")
		)
		(fp_line
			(start -1.05 1.2)
			(end -1.05 -1.2)
			(stroke
				(width 0.2)
				(type solid)
			)
			(layer "F.CrtYd")
		)
		(fp_line
			(start -1.05 1.2)
			(end 1.05 1.2)
			(stroke
				(width 0.2)
				(type solid)
			)
			(layer "F.CrtYd")
		)
		(fp_line
			(start 1.05 1.2)
			(end 1.05 -1.2)
			(stroke
				(width 0.2)
				(type solid)
			)
			(layer "F.CrtYd")
		)
		(fp_line
			(start -1.05 -1.2)
			(end 1.05 -1.2)
			(stroke
				(width 0.2)
				(type solid)
			)
			(layer "F.Fab")
		)
		(fp_line
			(start -1.05 1.2)
			(end -1.05 -1.2)
			(stroke
				(width 0.2)
				(type solid)
			)
			(layer "F.Fab")
		)
		(fp_line
			(start -1.05 1.2)
			(end 1.05 1.2)
			(stroke
				(width 0.2)
				(type solid)
			)
			(layer "F.Fab")
		)
		(fp_line
			(start -0.5 0)
			(end 0.5 0)
			(stroke
				(width 0.1)
				(type solid)
			)
			(layer "F.Fab")
		)
		(fp_line
			(start 0 0.5)
			(end 0 -0.5)
			(stroke
				(width 0.1)
				(type solid)
			)
			(layer "F.Fab")
		)
		(fp_line
			(start 1.05 1.2)
			(end 1.05 -1.2)
			(stroke
				(width 0.2)
				(type solid)
			)
			(layer "F.Fab")
		)
		(fp_text user "${REFERENCE}"
			(at -0.00001 0.09602 0)
			(unlocked yes)
			(layer "F.Fab")
			(effects
				(font
					(face "Arial")
					(size 0.63 0.63)
					(thickness 0.1)
				)
				(justify left bottom)
			)
		)
		(pad "" smd custom
			(at -0.5 -1.1)
			(size 0.000001 0.000001)
			(layers "F.Cu" "F.Mask")
			(solder_mask_margin 0)
			(thermal_bridge_angle 90)
			(options
				(clearance outline)
				(anchor circle)
			)
			(primitives
				(gr_poly
					(pts
						(xy 0 0) (xy 0.15 0) (xy 0.15 0.4) (xy -0.45 0.4) (xy -0.45 0.2) (xy 0 0.2)
					)
					(width 0)
					(fill yes)
				)
			)
		)
		(pad "1" smd circle
			(at -0.45 -0.8)
			(size 0.18 0.18)
			(layers "F.Cu" "F.Mask" "F.Paste")
			(net "DIP_SW_UART_SEL")
			(solder_mask_margin 0)
			(solder_paste_margin -1000)
			(thermal_bridge_angle 90)
		)
		(pad "2" smd rect
			(at -0.65 -0.4)
			(size 0.6 0.2)
			(layers "F.Cu" "F.Mask" "F.Paste")
			(net "NetR85_2")
			(solder_mask_margin 0)
			(solder_paste_margin -1000)
		)
		(pad "3" smd rect
			(at -0.65 0)
			(size 0.6 0.2)
			(layers "F.Cu" "F.Mask" "F.Paste")
			(net "GND")
			(solder_mask_margin 0)
			(solder_paste_margin -1000)
		)
		(pad "4" smd rect
			(at -0.65 0.4)
			(size 0.6 0.2)
			(layers "F.Cu" "F.Mask" "F.Paste")
			(net "NetR87_2")
			(solder_mask_margin 0)
			(solder_paste_margin -1000)
		)
		(pad "5" smd rect
			(at -0.65 0.8)
			(size 0.6 0.2)
			(layers "F.Cu" "F.Mask" "F.Paste")
			(net "DIP_SW_UART_SEL")
			(solder_mask_margin 0)
			(solder_paste_margin -1000)
		)
		(pad "6" smd rect
			(at 0 0.8)
			(size 0.2 0.6)
			(layers "F.Cu" "F.Mask" "F.Paste")
			(net "GND")
			(solder_mask_margin 0)
			(solder_paste_margin -1000)
		)
		(pad "7" smd rect
			(at 0.65 0.8)
			(size 0.6 0.2)
			(layers "F.Cu" "F.Mask" "F.Paste")
			(net "UART1_RXD")
			(solder_mask_margin 0)
			(solder_paste_margin -1000)
		)
		(pad "8" smd rect
			(at 0.65 0.4)
			(size 0.6 0.2)
			(layers "F.Cu" "F.Mask" "F.Paste")
			(net "NetR86_2")
			(solder_mask_margin 0)
			(solder_paste_margin -1000)
		)
		(pad "9" smd rect
			(at 0.65 0)
			(size 0.6 0.2)
			(layers "F.Cu" "F.Mask" "F.Paste")
			(net "+3.3V")
			(solder_mask_margin 0)
			(solder_paste_margin -1000)
		)
		(pad "10" smd rect
			(at 0.65 -0.4)
			(size 0.6 0.2)
			(layers "F.Cu" "F.Mask" "F.Paste")
			(net "NetR84_2")
			(solder_mask_margin 0)
			(solder_paste_margin -1000)
		)
		(pad "11" smd rect
			(at 0.65 -0.8)
			(size 0.6 0.2)
			(layers "F.Cu" "F.Mask" "F.Paste")
			(net "UART1_TXD")
			(solder_mask_margin 0)
			(solder_paste_margin -1000)
		)
		(pad "12" smd rect
			(at 0 -0.8)
			(size 0.2 0.6)
			(layers "F.Cu" "F.Mask" "F.Paste")
			(net "GND")
			(solder_mask_margin 0)
			(solder_paste_margin -1000)
		)
	)
	(footprint "Vault:FP-ERJ2R-MFG"
		(layer "F.Cu")
		(at 237.3261 62.1162 -90)
		(property "Reference" "R83"
			(at -2.0714 -0.273069 270)
			(unlocked yes)
			(layer "F.SilkS")
			(effects
				(font
					(size 0.762 0.762)
					(thickness 0.2286)
				)
			)
		)
		(property "Value" "15K_1%_0402"
			(at -2.732271 8.011115 180)
			(unlocked yes)
			(layer "F.SilkS")
			(hide yes)
			(effects
				(font
					(size 0.762 0.762)
					(thickness 0.2286)
				)
			)
		)
		(sheetname "USBUart_DipSelects")
		(sheetfile "USBUart_DipSelects.kicad_sch")
		(duplicate_pad_numbers_are_jumpers no)
		(fp_line
			(start 0.521 0.636)
			(end -0.529 0.636)
			(stroke
				(width 0.2)
				(type solid)
			)
			(layer "F.SilkS")
		)
		(fp_line
			(start 0.525 -0.65)
			(end -0.525 -0.65)
			(stroke
				(width 0.2)
				(type solid)
			)
			(layer "F.SilkS")
		)
		(fp_line
			(start -0.85 0.375)
			(end -0.85 -0.375)
			(stroke
				(width 0.2)
				(type solid)
			)
			(layer "F.CrtYd")
		)
		(fp_line
			(start 0.85 0.375)
			(end -0.85 0.375)
			(stroke
				(width 0.2)
				(type solid)
			)
			(layer "F.CrtYd")
		)
		(fp_line
			(start 0.85 0.375)
			(end 0.85 -0.375)
			(stroke
				(width 0.2)
				(type solid)
			)
			(layer "F.CrtYd")
		)
		(fp_line
			(start 0.85 -0.375)
			(end -0.85 -0.375)
			(stroke
				(width 0.2)
				(type solid)
			)
			(layer "F.CrtYd")
		)
		(fp_line
			(start 0 0.5)
			(end 0 -0.5)
			(stroke
				(width 0.1)
				(type solid)
			)
			(layer "F.Fab")
		)
		(fp_line
			(start -0.85 0.375)
			(end -0.85 -0.375)
			(stroke
				(width 0.2)
				(type solid)
			)
			(layer "F.Fab")
		)
		(fp_line
			(start 0.85 0.375)
			(end -0.85 0.375)
			(stroke
				(width 0.2)
				(type solid)
			)
			(layer "F.Fab")
		)
		(fp_line
			(start 0.85 0.375)
			(end 0.85 -0.375)
			(stroke
				(width 0.2)
				(type solid)
			)
			(layer "F.Fab")
		)
		(fp_line
			(start 0.5 0)
			(end -0.5 0)
			(stroke
				(width 0.1)
				(type solid)
			)
			(layer "F.Fab")
		)
		(fp_line
			(start 0.85 -0.375)
			(end -0.85 -0.375)
			(stroke
				(width 0.2)
				(type solid)
			)
			(layer "F.Fab")
		)
		(fp_text user "${REFERENCE}"
			(at -0.00001 0.09602 270)
			(unlocked yes)
			(layer "F.Fab")
			(effects
				(font
					(face "Arial")
					(size 0.63 0.63)
					(thickness 0.1)
				)
				(justify left bottom)
			)
		)
		(pad "1" smd rect
			(at -0.5125 0 270)
			(size 0.475 0.5)
			(layers "F.Cu" "F.Mask" "F.Paste")
			(net "GND")
			(solder_mask_margin 0)
			(solder_paste_margin 0)
		)
		(pad "2" smd rect
			(at 0.5125 0 270)
			(size 0.475 0.5)
			(layers "F.Cu" "F.Mask" "F.Paste")
			(net "NetC91_1")
			(solder_mask_margin 0)
			(solder_paste_margin 0)
		)
	)
	(footprint "Vault:RESC1608X55X25NL10T15"
		(layer "F.Cu")
		(at 77.8761 121.8662 180)
		(property "Reference" "R28"
			(at 0.81672 1.068825 0)
			(unlocked yes)
			(layer "F.SilkS")
			(effects
				(font
					(size 0.762 0.762)
					(thickness 0.2286)
				)
				(justify left bottom)
			)
		)
		(property "Value" "49.9R"
			(at 1.1445 -4.336645 0)
			(unlocked yes)
			(layer "F.SilkS")
			(hide yes)
			(effects
				(font
					(size 0.762 0.762)
					(thickness 0.2286)
				)
				(justify left bottom)
			)
		)
		(sheetname "USER_IO")
		(sheetfile "USER_IO.kicad_sch")
		(duplicate_pad_numbers_are_jumpers no)
		(pad "1" smd rect
			(at -0.7 0 270)
			(size 0.9 0.7)
			(layers "F.Cu" "F.Mask" "F.Paste")
			(net "NetR28_1")
		)
		(pad "2" smd rect
			(at 0.7 0 270)
			(size 0.9 0.7)
			(layers "F.Cu" "F.Mask" "F.Paste")
			(net "NetAN3_1")
		)
	)
	(footprint "Vault:FP-RUT0012A-MFG"
		(layer "F.Cu")
		(at 211.5261 78.8162)
		(property "Reference" "U22"
			(at 0.1286 -2.273069 0)
			(unlocked yes)
			(layer "F.SilkS")
			(effects
				(font
					(size 0.762 0.762)
					(thickness 0.2286)
				)
			)
		)
		(property "Value" "TMUX1072RUTR"
			(at 7.426665 3.164071 0)
			(unlocked yes)
			(layer "F.SilkS")
			(hide yes)
			(effects
				(font
					(size 0.762 0.762)
					(thickness 0.2286)
				)
			)
		)
		(sheetname "USBUart_DipSelects")
		(sheetfile "USBUart_DipSelects.kicad_sch")
		(duplicate_pad_numbers_are_jumpers no)
		(fp_line
			(start -0.9 -1.525)
			(end 0.9 -1.525)
			(stroke
				(width 0.2)
				(type solid)
			)
			(layer "F.SilkS")
		)
		(fp_line
			(start -0.9 1.525)
			(end 0.9 1.525)
			(stroke
				(width 0.2)
				(type solid)
			)
			(layer "F.SilkS")
		)
		(fp_circle
			(center -1.575 -0.8)
			(end -1.575 -0.925)
			(stroke
				(width 0.25)
				(type solid)
			)
			(fill no)
			(layer "F.SilkS")
		)
		(fp_rect
			(start -0.85 -0.3)
			(end -0.35 -0.5)
			(stroke
				(width 0)
				(type default)
			)
			(fill yes)
			(layer "F.Paste")
		)
		(fp_rect
			(start -0.85 0.1)
			(end -0.35 -0.1)
			(stroke
				(width 0)
				(type default)
			)
			(fill yes)
			(layer "F.Paste")
		)
		(fp_rect
			(start -0.85 0.5)
			(end -0.35 0.3)
			(stroke
				(width 0)
				(type default)
			)
			(fill yes)
			(layer "F.Paste")
		)
		(fp_rect
			(start -0.85 0.9)
			(end -0.35 0.7)
			(stroke
				(width 0)
				(type default)
			)
			(fill yes)
			(layer "F.Paste")
		)
		(fp_rect
			(start -0.1 -0.5)
			(end 0.1 -1)
			(stroke
				(width 0)
				(type default)
			)
			(fill yes)
			(layer "F.Paste")
		)
		(fp_rect
			(start -0.1 1)
			(end 0.1 0.5)
			(stroke
				(width 0)
				(type default)
			)
			(fill yes)
			(layer "F.Paste")
		)
		(fp_rect
			(start 0.35 -0.7)
			(end 0.85 -0.9)
			(stroke
				(width 0)
				(type default)
			)
			(fill yes)
			(layer "F.Paste")
		)
		(fp_rect
			(start 0.35 -0.3)
			(end 0.85 -0.5)
			(stroke
				(width 0)
				(type default)
			)
			(fill yes)
			(layer "F.Paste")
		)
		(fp_rect
			(start 0.35 0.1)
			(end 0.85 -0.1)
			(stroke
				(width 0)
				(type default)
			)
			(fill yes)
			(layer "F.Paste")
		)
		(fp_rect
			(start 0.35 0.5)
			(end 0.85 0.3)
			(stroke
				(width 0)
				(type default)
			)
			(fill yes)
			(layer "F.Paste")
		)
		(fp_rect
			(start 0.35 0.9)
			(end 0.85 0.7)
			(stroke
				(width 0)
				(type default)
			)
			(fill yes)
			(layer "F.Paste")
		)
		(fp_poly
			(pts
				(xy -0.5 -1) (xy -0.35 -1) (xy -0.35 -0.7) (xy -0.85 -0.7) (xy -0.85 -0.9) (xy -0.5 -0.9)
			)
			(stroke
				(width 0)
				(type default)
			)
			(fill yes)
			(layer "F.Paste")
		)
		(fp_line
			(start -1.05 -1.2)
			(end 1.05 -1.2)
			(stroke
				(width 0.2)
				(type solid)
			)
			(layer "F.CrtYd")
		)
		(fp_line
			(start -1.05 1.2)
			(end -1.05 -1.2)
			(stroke
				(width 0.2)
				(type solid)
			)
			(layer "F.CrtYd")
		)
		(fp_line
			(start -1.05 1.2)
			(end 1.05 1.2)
			(stroke
				(width 0.2)
				(type solid)
			)
			(layer "F.CrtYd")
		)
		(fp_line
			(start 1.05 1.2)
			(end 1.05 -1.2)
			(stroke
				(width 0.2)
				(type solid)
			)
			(layer "F.CrtYd")
		)
		(fp_line
			(start -1.05 -1.2)
			(end 1.05 -1.2)
			(stroke
				(width 0.2)
				(type solid)
			)
			(layer "F.Fab")
		)
		(fp_line
			(start -1.05 1.2)
			(end -1.05 -1.2)
			(stroke
				(width 0.2)
				(type solid)
			)
			(layer "F.Fab")
		)
		(fp_line
			(start -1.05 1.2)
			(end 1.05 1.2)
			(stroke
				(width 0.2)
				(type solid)
			)
			(layer "F.Fab")
		)
		(fp_line
			(start -0.5 0)
			(end 0.5 0)
			(stroke
				(width 0.1)
				(type solid)
			)
			(layer "F.Fab")
		)
		(fp_line
			(start 0 0.5)
			(end 0 -0.5)
			(stroke
				(width 0.1)
				(type solid)
			)
			(layer "F.Fab")
		)
		(fp_line
			(start 1.05 1.2)
			(end 1.05 -1.2)
			(stroke
				(width 0.2)
				(type solid)
			)
			(layer "F.Fab")
		)
		(fp_text user "${REFERENCE}"
			(at -0.00001 0.09602 0)
			(unlocked yes)
			(layer "F.Fab")
			(effects
				(font
					(face "Arial")
					(size 0.63 0.63)
					(thickness 0.1)
				)
				(justify left bottom)
			)
		)
		(pad "" smd custom
			(at -0.5 -1.1)
			(size 0.000001 0.000001)
			(layers "F.Cu" "F.Mask")
			(solder_mask_margin 0)
			(thermal_bridge_angle 90)
			(options
				(clearance outline)
				(anchor circle)
			)
			(primitives
				(gr_poly
					(pts
						(xy 0 0) (xy 0.15 0) (xy 0.15 0.4) (xy -0.45 0.4) (xy -0.45 0.2) (xy 0 0.2)
					)
					(width 0)
					(fill yes)
				)
			)
		)
		(pad "1" smd circle
			(at -0.45 -0.8)
			(size 0.18 0.18)
			(layers "F.Cu" "F.Mask" "F.Paste")
			(net "DIP_SW_UART_SEL")
			(solder_mask_margin 0)
			(solder_paste_margin -1000)
			(thermal_bridge_angle 90)
		)
		(pad "2" smd rect
			(at -0.65 -0.4)
			(size 0.6 0.2)
			(layers "F.Cu" "F.Mask" "F.Paste")
			(net "NetR91_2")
			(solder_mask_margin 0)
			(solder_paste_margin -1000)
		)
		(pad "3" smd rect
			(at -0.65 0)
			(size 0.6 0.2)
			(layers "F.Cu" "F.Mask" "F.Paste")
			(net "GND")
			(solder_mask_margin 0)
			(solder_paste_margin -1000)
		)
		(pad "4" smd rect
			(at -0.65 0.4)
			(size 0.6 0.2)
			(layers "F.Cu" "F.Mask" "F.Paste")
			(net "NetR93_2")
			(solder_mask_margin 0)
			(solder_paste_margin -1000)
		)
		(pad "5" smd rect
			(at -0.65 0.8)
			(size 0.6 0.2)
			(layers "F.Cu" "F.Mask" "F.Paste")
			(net "DIP_SW_UART_SEL")
			(solder_mask_margin 0)
			(solder_paste_margin -1000)
		)
		(pad "6" smd rect
			(at 0 0.8)
			(size 0.2 0.6)
			(layers "F.Cu" "F.Mask" "F.Paste")
			(net "GND")
			(solder_mask_margin 0)
			(solder_paste_margin -1000)
		)
		(pad "7" smd rect
			(at 0.65 0.8)
			(size 0.6 0.2)
			(layers "F.Cu" "F.Mask" "F.Paste")
			(net "GPS2_RX")
			(solder_mask_margin 0)
			(solder_paste_margin -1000)
		)
		(pad "8" smd rect
			(at 0.65 0.4)
			(size 0.6 0.2)
			(layers "F.Cu" "F.Mask" "F.Paste")
			(net "NetR92_2")
			(solder_mask_margin 0)
			(solder_paste_margin -1000)
		)
		(pad "9" smd rect
			(at 0.65 0)
			(size 0.6 0.2)
			(layers "F.Cu" "F.Mask" "F.Paste")
			(net "+3.3V")
			(solder_mask_margin 0)
			(solder_paste_margin -1000)
		)
		(pad "10" smd rect
			(at 0.65 -0.4)
			(size 0.6 0.2)
			(layers "F.Cu" "F.Mask" "F.Paste")
			(net "NetR90_2")
			(solder_mask_margin 0)
			(solder_paste_margin -1000)
		)
		(pad "11" smd rect
			(at 0.65 -0.8)
			(size 0.6 0.2)
			(layers "F.Cu" "F.Mask" "F.Paste")
			(net "GPS2_TX")
			(solder_mask_margin 0)
			(solder_paste_margin -1000)
		)
		(pad "12" smd rect
			(at 0 -0.8)
			(size 0.2 0.6)
			(layers "F.Cu" "F.Mask" "F.Paste")
			(net "GND")
			(solder_mask_margin 0)
			(solder_paste_margin -1000)
		)
	)
	(footprint "SA53:SolderSocket"
		(layer "F.Cu")
		(at 134.8261 138.2162 90)
		(property "Reference" "SKT3"
			(at -3.426921 2.1286 0)
			(unlocked yes)
			(layer "F.SilkS")
			(effects
				(font
					(size 0.762 0.762)
					(thickness 0.2286)
				)
			)
		)
		(property "Value" "0332-0-43-80-18-27-10-0"
			(at -2.910071 16.1362 0)
			(unlocked yes)
			(layer "F.SilkS")
			(hide yes)
			(effects
				(font
					(size 0.762 0.762)
					(thickness 0.2286)
				)
			)
		)
		(sheetname "MAC")
		(sheetfile "MAC.kicad_sch")
		(duplicate_pad_numbers_are_jumpers no)
		(pad "1" thru_hole circle
			(at 0 0 90)
			(size 2.54 2.54)
			(drill 2.0066)
			(layers "*.Cu" "*.Mask")
			(remove_unused_layers no)
			(net "MAC_RX")
			(thermal_bridge_angle 90)
		)
	)
	(footprint "Vault:RESC1005X40X25LL05T05"
		(layer "F.Cu")
		(at 191.3261 83.4162 -90)
		(property "Reference" "R58"
			(at -2.6714 -0.073069 270)
			(unlocked yes)
			(layer "F.SilkS")
			(effects
				(font
					(size 0.762 0.762)
					(thickness 0.2286)
				)
			)
		)
		(property "Value" "4.7K_0402"
			(at -3.024391 2.374045 180)
			(unlocked yes)
			(layer "F.SilkS")
			(hide yes)
			(effects
				(font
					(size 0.762 0.762)
					(thickness 0.2286)
				)
			)
		)
		(sheetname "GPS_IMU_SENSORS")
		(sheetfile "GPS_IMU_SENSORS.kicad_sch")
		(duplicate_pad_numbers_are_jumpers no)
		(pad "1" smd rect
			(at -0.4 0)
			(size 0.45 0.45)
			(layers "F.Cu" "F.Mask" "F.Paste")
			(net "+3.3V")
		)
		(pad "2" smd rect
			(at 0.4 0)
			(size 0.45 0.45)
			(layers "F.Cu" "F.Mask" "F.Paste")
			(net "NetR58_2")
		)
	)
	(footprint "Vault:CAPC1005X56X25NL10T15"
		(layer "F.Cu")
		(at 189.6261 91.0162 180)
		(property "Reference" "C33"
			(at -2.5286 -0.426931 0)
			(unlocked yes)
			(layer "F.SilkS")
			(effects
				(font
					(size 0.762 0.762)
					(thickness 0.2286)
				)
			)
		)
		(property "Value" "0.1uF_0402"
			(at 2.06903 2.567201 180)
			(unlocked yes)
			(layer "F.SilkS")
			(hide yes)
			(effects
				(font
					(size 0.762 0.762)
					(thickness 0.2286)
				)
			)
		)
		(sheetname "GPS_IMU_SENSORS")
		(sheetfile "GPS_IMU_SENSORS.kicad_sch")
		(duplicate_pad_numbers_are_jumpers no)
		(pad "1" smd rect
			(at -0.44 0 270)
			(size 0.64 0.68)
			(layers "F.Cu" "F.Mask" "F.Paste")
			(net "BNO_XOUT32_C")
		)
		(pad "2" smd rect
			(at 0.44 0 270)
			(size 0.64 0.68)
			(layers "F.Cu" "F.Mask" "F.Paste")
			(net "BNO_XOUT32")
		)
	)
	(footprint "Vault:RESC0402(1005)_N"
		(layer "F.Cu")
		(at 217.5261 130.1162 -90)
		(property "Reference" "R69"
			(at 0.8286 -1.073069 270)
			(unlocked yes)
			(layer "F.SilkS")
			(effects
				(font
					(size 0.762 0.762)
					(thickness 0.2286)
				)
			)
		)
		(property "Value" "1.21_1%_0402"
			(at -2.783071 8.468155 180)
			(unlocked yes)
			(layer "F.SilkS")
			(hide yes)
			(effects
				(font
					(size 0.762 0.762)
					(thickness 0.2286)
				)
			)
		)
		(sheetname "POWER")
		(sheetfile "POWER.kicad_sch")
		(duplicate_pad_numbers_are_jumpers no)
		(pad "1" smd rect
			(at -0.5 0)
			(size 0.65 0.55)
			(layers "F.Cu" "F.Mask" "F.Paste")
			(net "NetR69_1")
		)
		(pad "2" smd rect
			(at 0.5 0)
			(size 0.65 0.55)
			(layers "F.Cu" "F.Mask" "F.Paste")
			(net "NetC68_1")
		)
	)
	(footprint "Vault:RESC1005X40X25ML05T10"
		(layer "F.Cu")
		(at 204.0261 109.3162 -90)
		(property "Reference" "R59"
			(at -0.1286 1.473069 90)
			(unlocked yes)
			(layer "F.SilkS")
			(effects
				(font
					(size 0.762 0.762)
					(thickness 0.2286)
				)
			)
		)
		(property "Value" "2.21_1%_0402"
			(at -2.884671 8.544305 180)
			(unlocked yes)
			(layer "F.SilkS")
			(hide yes)
			(effects
				(font
					(size 0.762 0.762)
					(thickness 0.2286)
				)
			)
		)
		(sheetname "POWER")
		(sheetfile "POWER.kicad_sch")
		(duplicate_pad_numbers_are_jumpers no)
		(pad "1" smd rect
			(at -0.475 0)
			(size 0.65 0.7)
			(layers "F.Cu" "F.Mask" "F.Paste")
			(net "+12V")
		)
		(pad "2" smd rect
			(at 0.475 0)
			(size 0.65 0.7)
			(layers "F.Cu" "F.Mask" "F.Paste")
			(net "NetC6_1")
		)
	)
	(footprint "SamacSys:155124M173200"
		(layer "F.Cu")
		(at 58.4511 101.4162 90)
		(property "Reference" "D15"
			(at -0.4714 1.701931 90)
			(unlocked yes)
			(layer "F.SilkS")
			(effects
				(font
					(size 0.762 0.762)
					(thickness 0.2286)
				)
			)
		)
		(property "Value" "155124M173200"
			(at 7.1471 2.605271 90)
			(unlocked yes)
			(layer "F.SilkS")
			(hide yes)
			(effects
				(font
					(size 0.762 0.762)
					(thickness 0.2286)
				)
			)
		)
		(sheetname "USER_IO_STATUS")
		(sheetfile "USER_IO_STATUS.kicad_sch")
		(duplicate_pad_numbers_are_jumpers no)
		(fp_line
			(start -0.8 0.5)
			(end 0.8 0.5)
			(stroke
				(width 0.1)
				(type solid)
			)
			(layer "F.SilkS")
		)
		(fp_arc
			(start -2 -0.1)
			(mid -1.95 -0.05)
			(end -2 0)
			(stroke
				(width 0.1)
				(type solid)
			)
			(layer "F.SilkS")
		)
		(fp_arc
			(start -2 0)
			(mid -2.05 -0.05)
			(end -2 -0.1)
			(stroke
				(width 0.1)
				(type solid)
			)
			(layer "F.SilkS")
		)
		(pad "1" smd rect
			(at -1.4 0 180)
			(size 0.9 0.6)
			(layers "F.Cu" "F.Mask" "F.Paste")
			(net "+3.3V")
		)
		(pad "2" smd rect
			(at -0.45 -0.325 90)
			(size 0.6 0.55)
			(layers "F.Cu" "F.Mask" "F.Paste")
			(net "NetD15_2")
		)
		(pad "3" smd rect
			(at 0.45 -0.325 90)
			(size 0.6 0.55)
			(layers "F.Cu" "F.Mask" "F.Paste")
			(net "NetD15_3")
		)
		(pad "4" smd rect
			(at 1.4 0 180)
			(size 0.9 0.6)
			(layers "F.Cu" "F.Mask" "F.Paste")
			(net "NetD15_4")
		)
	)
	(footprint "Vault:RESC1005X40X25NL05T05"
		(layer "F.Cu")
		(at 208.8261 80.6162)
		(property "Reference" "R93"
			(at -1.9714 -0.173069 0)
			(unlocked yes)
			(layer "F.SilkS")
			(effects
				(font
					(size 0.762 0.762)
					(thickness 0.2286)
				)
			)
		)
		(property "Value" "27_1%_0402"
			(at -2.732271 7.37632 270)
			(unlocked yes)
			(layer "F.SilkS")
			(hide yes)
			(effects
				(font
					(size 0.762 0.762)
					(thickness 0.2286)
				)
			)
		)
		(sheetname "USBUart_DipSelects")
		(sheetfile "USBUart_DipSelects.kicad_sch")
		(duplicate_pad_numbers_are_jumpers no)
		(pad "1" smd rect
			(at -0.45 0 90)
			(size 0.55 0.55)
			(layers "F.Cu" "F.Mask" "F.Paste")
			(net "GPS2_RX_FPGA")
		)
		(pad "2" smd rect
			(at 0.45 0 90)
			(size 0.55 0.55)
			(layers "F.Cu" "F.Mask" "F.Paste")
			(net "NetR93_2")
		)
	)
	(footprint "Vault:FP-C3216-160-0_2-MFG"
		(layer "F.Cu")
		(at 231.8261 123.3162)
		(property "Reference" "C78"
			(at 4.0286 0.226931 0)
			(unlocked yes)
			(layer "F.SilkS")
			(effects
				(font
					(size 0.762 0.762)
					(thickness 0.2286)
				)
			)
		)
		(property "Value" "47uF_16V_1206"
			(at -4.014951 8.77266 270)
			(unlocked yes)
			(layer "F.SilkS")
			(hide yes)
			(effects
				(font
					(size 0.762 0.762)
					(thickness 0.2286)
				)
			)
		)
		(sheetname "POWER")
		(sheetfile "POWER.kicad_sch")
		(duplicate_pad_numbers_are_jumpers no)
		(fp_line
			(start -0.725 -0.9)
			(end 0.725 -0.9)
			(stroke
				(width 0.2)
				(type solid)
			)
			(layer "F.SilkS")
		)
		(fp_line
			(start -0.725 0.9)
			(end 0.725 0.9)
			(stroke
				(width 0.2)
				(type solid)
			)
			(layer "F.SilkS")
		)
		(fp_line
			(start -2.3 -1)
			(end 2.3 -1)
			(stroke
				(width 0.2)
				(type solid)
			)
			(layer "F.CrtYd")
		)
		(fp_line
			(start -2.3 1)
			(end -2.3 -1)
			(stroke
				(width 0.2)
				(type solid)
			)
			(layer "F.CrtYd")
		)
		(fp_line
			(start -2.3 1)
			(end 2.3 1)
			(stroke
				(width 0.2)
				(type solid)
			)
			(layer "F.CrtYd")
		)
		(fp_line
			(start 2.3 1)
			(end 2.3 -1)
			(stroke
				(width 0.2)
				(type solid)
			)
			(layer "F.CrtYd")
		)
		(fp_line
			(start -2.3 -1)
			(end 2.3 -1)
			(stroke
				(width 0.2)
				(type solid)
			)
			(layer "F.Fab")
		)
		(fp_line
			(start -2.3 1)
			(end -2.3 -1)
			(stroke
				(width 0.2)
				(type solid)
			)
			(layer "F.Fab")
		)
		(fp_line
			(start -2.3 1)
			(end 2.3 1)
			(stroke
				(width 0.2)
				(type solid)
			)
			(layer "F.Fab")
		)
		(fp_line
			(start -0.5 0)
			(end 0.5 0)
			(stroke
				(width 0.1)
				(type solid)
			)
			(layer "F.Fab")
		)
		(fp_line
			(start 0 0.5)
			(end 0 -0.5)
			(stroke
				(width 0.1)
				(type solid)
			)
			(layer "F.Fab")
		)
		(fp_line
			(start 2.3 1)
			(end 2.3 -1)
			(stroke
				(width 0.2)
				(type solid)
			)
			(layer "F.Fab")
		)
		(fp_text user "${REFERENCE}"
			(at -0.00001 0.09602 360)
			(unlocked yes)
			(layer "F.Fab")
			(effects
				(font
					(face "Arial")
					(size 0.63 0.63)
					(thickness 0.1)
				)
				(justify left bottom)
			)
		)
		(pad "1" smd rect
			(at -1.65 0)
			(size 1.1 1.35)
			(layers "F.Cu" "F.Mask" "F.Paste")
			(net "+3.3V")
			(solder_mask_margin 0)
			(solder_paste_margin 0)
		)
		(pad "2" smd rect
			(at 1.65 0)
			(size 1.1 1.35)
			(layers "F.Cu" "F.Mask" "F.Paste")
			(net "GND")
			(solder_mask_margin 0)
			(solder_paste_margin 0)
		)
	)
	(footprint "Vault:RESC1005X40X25NL05T05"
		(layer "F.Cu")
		(at 217.2261 77.9162)
		(property "Reference" "R85"
			(at 0.0286 -0.973079 0)
			(unlocked yes)
			(layer "F.SilkS")
			(effects
				(font
					(size 0.762 0.762)
					(thickness 0.2286)
				)
			)
		)
		(property "Value" "27_1%_0402"
			(at -2.732281 7.37632 270)
			(unlocked yes)
			(layer "F.SilkS")
			(hide yes)
			(effects
				(font
					(size 0.762 0.762)
					(thickness 0.2286)
				)
			)
		)
		(sheetname "USBUart_DipSelects")
		(sheetfile "USBUart_DipSelects.kicad_sch")
		(duplicate_pad_numbers_are_jumpers no)
		(pad "1" smd rect
			(at -0.45 0 90)
			(size 0.55 0.55)
			(layers "F.Cu" "F.Mask" "F.Paste")
			(net "FTDI_RX")
		)
		(pad "2" smd rect
			(at 0.45 0 90)
			(size 0.55 0.55)
			(layers "F.Cu" "F.Mask" "F.Paste")
			(net "NetR85_2")
		)
	)
	(footprint "Vault:RESC1005X40X25LL05T05"
		(layer "F.Cu")
		(at 192.3261 83.4162 -90)
		(property "Reference" "R57"
			(at -2.4714 -0.173069 270)
			(unlocked yes)
			(layer "F.SilkS")
			(effects
				(font
					(size 0.762 0.762)
					(thickness 0.2286)
				)
			)
		)
		(property "Value" "4.7K_0402"
			(at -3.024391 2.374045 180)
			(unlocked yes)
			(layer "F.SilkS")
			(hide yes)
			(effects
				(font
					(size 0.762 0.762)
					(thickness 0.2286)
				)
			)
		)
		(sheetname "GPS_IMU_SENSORS")
		(sheetfile "GPS_IMU_SENSORS.kicad_sch")
		(duplicate_pad_numbers_are_jumpers no)
		(pad "1" smd rect
			(at -0.4 0)
			(size 0.45 0.45)
			(layers "F.Cu" "F.Mask" "F.Paste")
			(net "+3.3V")
		)
		(pad "2" smd rect
			(at 0.4 0)
			(size 0.45 0.45)
			(layers "F.Cu" "F.Mask" "F.Paste")
			(net "NetR57_2")
		)
	)
	(footprint "Vault:FP-0402-L_1_0_1-W_0_5_0_1-IPC_C"
		(layer "F.Cu")
		(at 239.4261 64.75066 90)
		(property "Reference" "C92"
			(at 2.20586 0.373069 270)
			(unlocked yes)
			(layer "F.SilkS")
			(effects
				(font
					(size 0.762 0.762)
					(thickness 0.2286)
				)
			)
		)
		(property "Value" "0.1uF_25V_0402"
			(at -2.465551 9.839205 0)
			(unlocked yes)
			(layer "F.SilkS")
			(hide yes)
			(effects
				(font
					(size 0.762 0.762)
					(thickness 0.2286)
				)
			)
		)
		(sheetname "USBUart_DipSelects")
		(sheetfile "USBUart_DipSelects.kicad_sch")
		(duplicate_pad_numbers_are_jumpers no)
		(fp_line
			(start -0.65607 -0.7)
			(end 0.65606 -0.7)
			(stroke
				(width 0.2)
				(type solid)
			)
			(layer "F.SilkS")
		)
		(fp_line
			(start -0.65607 0.7)
			(end 0.65606 0.7)
			(stroke
				(width 0.2)
				(type solid)
			)
			(layer "F.SilkS")
		)
		(fp_line
			(start 0.75606 -0.4)
			(end 0.75606 0.4)
			(stroke
				(width 0.2)
				(type solid)
			)
			(layer "F.CrtYd")
		)
		(fp_line
			(start -0.75607 -0.4)
			(end 0.75606 -0.4)
			(stroke
				(width 0.2)
				(type solid)
			)
			(layer "F.CrtYd")
		)
		(fp_line
			(start -0.75607 -0.4)
			(end -0.75607 0.4)
			(stroke
				(width 0.2)
				(type solid)
			)
			(layer "F.CrtYd")
		)
		(fp_line
			(start -0.75607 0.4)
			(end 0.75606 0.4)
			(stroke
				(width 0.2)
				(type solid)
			)
			(layer "F.CrtYd")
		)
		(fp_line
			(start 0 -0.5)
			(end 0 0.5)
			(stroke
				(width 0.1)
				(type solid)
			)
			(layer "F.Fab")
		)
		(fp_line
			(start 0.75606 -0.4)
			(end 0.75606 0.4)
			(stroke
				(width 0.2)
				(type solid)
			)
			(layer "F.Fab")
		)
		(fp_line
			(start -0.75607 -0.4)
			(end 0.75606 -0.4)
			(stroke
				(width 0.2)
				(type solid)
			)
			(layer "F.Fab")
		)
		(fp_line
			(start -0.75607 -0.4)
			(end -0.75607 0.4)
			(stroke
				(width 0.2)
				(type solid)
			)
			(layer "F.Fab")
		)
		(fp_line
			(start -0.5 0)
			(end 0.5 0)
			(stroke
				(width 0.1)
				(type solid)
			)
			(layer "F.Fab")
		)
		(fp_line
			(start -0.75607 0.4)
			(end 0.75606 0.4)
			(stroke
				(width 0.2)
				(type solid)
			)
			(layer "F.Fab")
		)
		(fp_text user "${REFERENCE}"
			(at -0.00001 0.09601 90)
			(unlocked yes)
			(layer "F.Fab")
			(effects
				(font
					(face "Arial")
					(size 0.63 0.63)
					(thickness 0.1)
				)
				(justify left bottom)
			)
		)
		(pad "1" smd rect
			(at -0.36554 0 90)
			(size 0.58106 0.51213)
			(layers "F.Cu" "F.Mask" "F.Paste")
			(net "NetC92_1")
			(solder_mask_margin 0)
			(solder_paste_margin 0)
		)
		(pad "2" smd rect
			(at 0.36553 0 90)
			(size 0.58106 0.51213)
			(layers "F.Cu" "F.Mask" "F.Paste")
			(net "GND")
			(solder_mask_margin 0)
			(solder_paste_margin 0)
		)
	)
	(footprint "SamacSys:155124M173200"
		(layer "F.Cu")
		(at 58.4511 114.8162 90)
		(property "Reference" "D16"
			(at -0.5714 1.701931 90)
			(unlocked yes)
			(layer "F.SilkS")
			(effects
				(font
					(size 0.762 0.762)
					(thickness 0.2286)
				)
			)
		)
		(property "Value" "155124M173200"
			(at 7.1471 2.605271 90)
			(unlocked yes)
			(layer "F.SilkS")
			(hide yes)
			(effects
				(font
					(size 0.762 0.762)
					(thickness 0.2286)
				)
			)
		)
		(sheetname "USER_IO_STATUS")
		(sheetfile "USER_IO_STATUS.kicad_sch")
		(duplicate_pad_numbers_are_jumpers no)
		(fp_line
			(start -0.8 0.5)
			(end 0.8 0.5)
			(stroke
				(width 0.1)
				(type solid)
			)
			(layer "F.SilkS")
		)
		(fp_arc
			(start -2 -0.1)
			(mid -1.95 -0.05)
			(end -2 0)
			(stroke
				(width 0.1)
				(type solid)
			)
			(layer "F.SilkS")
		)
		(fp_arc
			(start -2 0)
			(mid -2.05 -0.05)
			(end -2 -0.1)
			(stroke
				(width 0.1)
				(type solid)
			)
			(layer "F.SilkS")
		)
		(pad "1" smd rect
			(at -1.4 0 180)
			(size 0.9 0.6)
			(layers "F.Cu" "F.Mask" "F.Paste")
			(net "+3.3V")
		)
		(pad "2" smd rect
			(at -0.45 -0.325 90)
			(size 0.6 0.55)
			(layers "F.Cu" "F.Mask" "F.Paste")
			(net "NetD16_2")
		)
		(pad "3" smd rect
			(at 0.45 -0.325 90)
			(size 0.6 0.55)
			(layers "F.Cu" "F.Mask" "F.Paste")
			(net "NetD16_3")
		)
		(pad "4" smd rect
			(at 1.4 0 180)
			(size 0.9 0.6)
			(layers "F.Cu" "F.Mask" "F.Paste")
			(net "NetD16_4")
		)
	)
	(footprint "SA53:SolderSocket"
		(layer "F.Cu")
		(at 139.9261 135.5162 90)
		(property "Reference" "SKT9"
			(at -2.626921 7.6286 0)
			(unlocked yes)
			(layer "F.SilkS")
			(effects
				(font
					(size 0.762 0.762)
					(thickness 0.2286)
				)
			)
		)
		(property "Value" "0332-0-43-80-18-27-10-0"
			(at -2.910071 16.1362 0)
			(unlocked yes)
			(layer "F.SilkS")
			(hide yes)
			(effects
				(font
					(size 0.762 0.762)
					(thickness 0.2286)
				)
			)
		)
		(sheetname "MAC")
		(sheetfile "MAC.kicad_sch")
		(duplicate_pad_numbers_are_jumpers no)
		(pad "1" thru_hole circle
			(at 0 0 90)
			(size 2.54 2.54)
			(drill 2.0066)
			(layers "*.Cu" "*.Mask")
			(remove_unused_layers no)
			(net "GND")
			(thermal_bridge_angle 90)
		)
	)
	(footprint "Vault:FP-RUT0012A-MFG"
		(layer "F.Cu")
		(at 126.2261 85.9162 90)
		(property "Reference" "U23"
			(at -3.126931 -0.3714 0)
			(unlocked yes)
			(layer "F.SilkS")
			(effects
				(font
					(size 0.762 0.762)
					(thickness 0.2286)
				)
			)
		)
		(property "Value" "TMUX1072RUTR"
			(at 7.426665 3.164071 90)
			(unlocked yes)
			(layer "F.SilkS")
			(hide yes)
			(effects
				(font
					(size 0.762 0.762)
					(thickness 0.2286)
				)
			)
		)
		(sheetname "USBUart_DipSelects")
		(sheetfile "USBUart_DipSelects.kicad_sch")
		(duplicate_pad_numbers_are_jumpers no)
		(fp_line
			(start -0.9 -1.525)
			(end 0.9 -1.525)
			(stroke
				(width 0.2)
				(type solid)
			)
			(layer "F.SilkS")
		)
		(fp_line
			(start -0.9 1.525)
			(end 0.9 1.525)
			(stroke
				(width 0.2)
				(type solid)
			)
			(layer "F.SilkS")
		)
		(fp_circle
			(center -1.575 -0.8)
			(end -1.45 -0.8)
			(stroke
				(width 0.25)
				(type solid)
			)
			(fill no)
			(layer "F.SilkS")
		)
		(fp_rect
			(start 0.35 -0.7)
			(end 0.85 -0.9)
			(stroke
				(width 0)
				(type default)
			)
			(fill yes)
			(layer "F.Paste")
		)
		(fp_rect
			(start -0.1 -0.5)
			(end 0.1 -1)
			(stroke
				(width 0)
				(type default)
			)
			(fill yes)
			(layer "F.Paste")
		)
		(fp_rect
			(start 0.35 -0.3)
			(end 0.85 -0.5)
			(stroke
				(width 0)
				(type default)
			)
			(fill yes)
			(layer "F.Paste")
		)
		(fp_rect
			(start -0.85 -0.3)
			(end -0.35 -0.5)
			(stroke
				(width 0)
				(type default)
			)
			(fill yes)
			(layer "F.Paste")
		)
		(fp_rect
			(start 0.35 0.1)
			(end 0.85 -0.1)
			(stroke
				(width 0)
				(type default)
			)
			(fill yes)
			(layer "F.Paste")
		)
		(fp_rect
			(start -0.85 0.1)
			(end -0.35 -0.1)
			(stroke
				(width 0)
				(type default)
			)
			(fill yes)
			(layer "F.Paste")
		)
		(fp_rect
			(start 0.35 0.5)
			(end 0.85 0.3)
			(stroke
				(width 0)
				(type default)
			)
			(fill yes)
			(layer "F.Paste")
		)
		(fp_rect
			(start -0.85 0.5)
			(end -0.35 0.3)
			(stroke
				(width 0)
				(type default)
			)
			(fill yes)
			(layer "F.Paste")
		)
		(fp_rect
			(start 0.349995 0.900005)
			(end 0.850005 0.700005)
			(stroke
				(width 0)
				(type default)
			)
			(fill yes)
			(layer "F.Paste")
		)
		(fp_rect
			(start -0.850005 0.900005)
			(end -0.349995 0.700005)
			(stroke
				(width 0)
				(type default)
			)
			(fill yes)
			(layer "F.Paste")
		)
		(fp_rect
			(start -0.099995 1.000005)
			(end 0.100005 0.499995)
			(stroke
				(width 0)
				(type default)
			)
			(fill yes)
			(layer "F.Paste")
		)
		(fp_poly
			(pts
				(xy -0.5 -1) (xy -0.35 -1) (xy -0.35 -0.7) (xy -0.85 -0.7) (xy -0.85 -0.9) (xy -0.5 -0.9)
			)
			(stroke
				(width 0)
				(type default)
			)
			(fill yes)
			(layer "F.Paste")
		)
		(fp_line
			(start 1.05 -1.2)
			(end 1.05 1.2)
			(stroke
				(width 0.2)
				(type solid)
			)
			(layer "F.CrtYd")
		)
		(fp_line
			(start -1.05 -1.2)
			(end 1.05 -1.2)
			(stroke
				(width 0.2)
				(type solid)
			)
			(layer "F.CrtYd")
		)
		(fp_line
			(start -1.05 -1.2)
			(end -1.05 1.2)
			(stroke
				(width 0.2)
				(type solid)
			)
			(layer "F.CrtYd")
		)
		(fp_line
			(start -1.05 1.2)
			(end 1.05 1.2)
			(stroke
				(width 0.2)
				(type solid)
			)
			(layer "F.CrtYd")
		)
		(fp_line
			(start 1.05 -1.2)
			(end 1.05 1.2)
			(stroke
				(width 0.2)
				(type solid)
			)
			(layer "F.Fab")
		)
		(fp_line
			(start -1.05 -1.2)
			(end 1.05 -1.2)
			(stroke
				(width 0.2)
				(type solid)
			)
			(layer "F.Fab")
		)
		(fp_line
			(start -1.05 -1.2)
			(end -1.05 1.2)
			(stroke
				(width 0.2)
				(type solid)
			)
			(layer "F.Fab")
		)
		(fp_line
			(start 0 -0.5)
			(end 0 0.5)
			(stroke
				(width 0.1)
				(type solid)
			)
			(layer "F.Fab")
		)
		(fp_line
			(start -0.5 0)
			(end 0.5 0)
			(stroke
				(width 0.1)
				(type solid)
			)
			(layer "F.Fab")
		)
		(fp_line
			(start -1.05 1.2)
			(end 1.05 1.2)
			(stroke
				(width 0.2)
				(type solid)
			)
			(layer "F.Fab")
		)
		(fp_text user "${REFERENCE}"
			(at -0.00001 0.09602 90)
			(unlocked yes)
			(layer "F.Fab")
			(effects
				(font
					(face "Arial")
					(size 0.63 0.63)
					(thickness 0.1)
				)
				(justify left bottom)
			)
		)
		(pad "" smd custom
			(at -0.5 -1.1)
			(size 0.000001 0.000001)
			(layers "F.Cu" "F.Mask")
			(solder_mask_margin 0)
			(thermal_bridge_angle 90)
			(options
				(clearance outline)
				(anchor circle)
			)
			(primitives
				(gr_poly
					(pts
						(xy 0 0) (xy 0 -0.15) (xy 0.4 -0.15) (xy 0.4 0.45) (xy 0.2 0.45) (xy 0.2 0)
					)
					(width 0)
					(fill yes)
				)
			)
		)
		(pad "1" smd circle
			(at -0.45 -0.8 90)
			(size 0.18 0.18)
			(layers "F.Cu" "F.Mask" "F.Paste")
			(net "DIP_SW_PPS_SEL")
			(solder_mask_margin 0)
			(solder_paste_margin -1000)
			(thermal_bridge_angle 90)
		)
		(pad "2" smd rect
			(at -0.65 -0.4 90)
			(size 0.6 0.2)
			(layers "F.Cu" "F.Mask" "F.Paste")
			(net "NetR97_2")
			(solder_mask_margin 0)
			(solder_paste_margin -1000)
		)
		(pad "3" smd rect
			(at -0.65 0 90)
			(size 0.6 0.2)
			(layers "F.Cu" "F.Mask" "F.Paste")
			(net "GND")
			(solder_mask_margin 0)
			(solder_paste_margin -1000)
		)
		(pad "4" smd rect
			(at -0.65 0.4 90)
			(size 0.6 0.2)
			(layers "F.Cu" "F.Mask" "F.Paste")
			(net "NetR99_2")
			(solder_mask_margin 0)
			(solder_paste_margin -1000)
		)
		(pad "5" smd rect
			(at -0.65 0.8 90)
			(size 0.6 0.2)
			(layers "F.Cu" "F.Mask" "F.Paste")
			(net "DIP_SW_PPS_SEL")
			(solder_mask_margin 0)
			(solder_paste_margin -1000)
		)
		(pad "6" smd rect
			(at 0 0.8 90)
			(size 0.2 0.6)
			(layers "F.Cu" "F.Mask" "F.Paste")
			(net "GND")
			(solder_mask_margin 0)
			(solder_paste_margin -1000)
		)
		(pad "7" smd rect
			(at 0.65 0.8 90)
			(size 0.6 0.2)
			(layers "F.Cu" "F.Mask" "F.Paste")
			(net "FPGA_MAC_PPS_IN0-")
			(solder_mask_margin 0)
			(solder_paste_margin -1000)
		)
		(pad "8" smd rect
			(at 0.65 0.4 90)
			(size 0.6 0.2)
			(layers "F.Cu" "F.Mask" "F.Paste")
			(net "NetR98_2")
			(solder_mask_margin 0)
			(solder_paste_margin -1000)
		)
		(pad "9" smd rect
			(at 0.65 0 90)
			(size 0.6 0.2)
			(layers "F.Cu" "F.Mask" "F.Paste")
			(net "+3.3V")
			(solder_mask_margin 0)
			(solder_paste_margin -1000)
		)
		(pad "10" smd rect
			(at 0.65 -0.4 90)
			(size 0.6 0.2)
			(layers "F.Cu" "F.Mask" "F.Paste")
			(net "NetR96_2")
			(solder_mask_margin 0)
			(solder_paste_margin -1000)
		)
		(pad "11" smd rect
			(at 0.65 -0.8 90)
			(size 0.6 0.2)
			(layers "F.Cu" "F.Mask" "F.Paste")
			(net "FPGA_MAC_PPS_OUT-")
			(solder_mask_margin 0)
			(solder_paste_margin -1000)
		)
		(pad "12" smd rect
			(at 0 -0.8 90)
			(size 0.2 0.6)
			(layers "F.Cu" "F.Mask" "F.Paste")
			(net "GND")
			(solder_mask_margin 0)
			(solder_paste_margin -1000)
		)
	)
	(footprint "SamacSys:SOP50P310X90-8N"
		(layer "F.Cu")
		(at 82.3761 109.1162 180)
		(property "Reference" "U12"
			(at 0.2286 2.026931 180)
			(unlocked yes)
			(layer "F.SilkS")
			(effects
				(font
					(size 0.762 0.762)
					(thickness 0.2286)
				)
			)
		)
		(property "Value" "NC7WV125K8X"
			(at 6.207715 2.884671 180)
			(unlocked yes)
			(layer "F.SilkS")
			(hide yes)
			(effects
				(font
					(size 0.762 0.762)
					(thickness 0.2286)
				)
			)
		)
		(sheetname "USER_IO")
		(sheetfile "USER_IO.kicad_sch")
		(duplicate_pad_numbers_are_jumpers no)
		(fp_line
			(start 0.8 1)
			(end -0.8 1)
			(stroke
				(width 0.2)
				(type solid)
			)
			(layer "F.SilkS")
		)
		(fp_line
			(start 0.8 -1)
			(end 0.8 1)
			(stroke
				(width 0.2)
				(type solid)
			)
			(layer "F.SilkS")
		)
		(fp_line
			(start 0.8 -1)
			(end -0.8 -1)
			(stroke
				(width 0.2)
				(type solid)
			)
			(layer "F.SilkS")
		)
		(fp_line
			(start -0.8 -1)
			(end -0.8 1)
			(stroke
				(width 0.2)
				(type solid)
			)
			(layer "F.SilkS")
		)
		(fp_line
			(start -1.15 -1.25)
			(end -2 -1.25)
			(stroke
				(width 0.2)
				(type solid)
			)
			(layer "F.SilkS")
		)
		(pad "1" smd rect
			(at -1.575 -0.75 180)
			(size 0.85 0.3)
			(layers "F.Cu" "F.Mask" "F.Paste")
			(net "ANT2_IO_OUT")
		)
		(pad "2" smd rect
			(at -1.575 -0.25 180)
			(size 0.85 0.3)
			(layers "F.Cu" "F.Mask" "F.Paste")
			(net "ANT2_OUT")
		)
		(pad "3" smd rect
			(at -1.575 0.25 180)
			(size 0.85 0.3)
			(layers "F.Cu" "F.Mask" "F.Paste")
			(net "ANT2_IN")
		)
		(pad "4" smd rect
			(at -1.575 0.75 180)
			(size 0.85 0.3)
			(layers "F.Cu" "F.Mask" "F.Paste")
			(net "GND")
		)
		(pad "5" smd rect
			(at 1.575 0.75 180)
			(size 0.85 0.3)
			(layers "F.Cu" "F.Mask" "F.Paste")
			(net "NetR33_1")
		)
		(pad "6" smd rect
			(at 1.575 0.25 180)
			(size 0.85 0.3)
			(layers "F.Cu" "F.Mask" "F.Paste")
			(net "NetR33_1")
		)
		(pad "7" smd rect
			(at 1.575 -0.25 180)
			(size 0.85 0.3)
			(layers "F.Cu" "F.Mask" "F.Paste")
			(net "ANT2_IO_IN")
		)
		(pad "8" smd rect
			(at 1.575 -0.75 180)
			(size 0.85 0.3)
			(layers "F.Cu" "F.Mask" "F.Paste")
			(net "+3.3V")
		)
	)
	(footprint "Vault:RESC1005X40X25LL05T05"
		(layer "F.Cu")
		(at 236.4261 132.9162)
		(property "Reference" "R80"
			(at 2.4286 -0.073079 0)
			(unlocked yes)
			(layer "F.SilkS")
			(effects
				(font
					(size 0.762 0.762)
					(thickness 0.2286)
				)
			)
		)
		(property "Value" "0_1%_0402"
			(at -2.579881 6.66536 270)
			(unlocked yes)
			(layer "F.SilkS")
			(hide yes)
			(effects
				(font
					(size 0.762 0.762)
					(thickness 0.2286)
				)
			)
		)
		(sheetname "POWER")
		(sheetfile "POWER.kicad_sch")
		(duplicate_pad_numbers_are_jumpers no)
		(pad "1" smd rect
			(at -0.4 0 90)
			(size 0.45 0.45)
			(layers "F.Cu" "F.Mask" "F.Paste")
			(net "NetR80_1")
		)
		(pad "2" smd rect
			(at 0.4 0 90)
			(size 0.45 0.45)
			(layers "F.Cu" "F.Mask" "F.Paste")
			(net "+3.3V")
		)
	)
	(footprint "Vault:FP-CC0402-MFG"
		(layer "F.Cu")
		(at 202.2761 121.0662 -90)
		(property "Reference" "C73"
			(at -0.3786 1.423079 90)
			(unlocked yes)
			(layer "F.SilkS")
			(effects
				(font
					(size 0.762 0.762)
					(thickness 0.2286)
				)
			)
		)
		(property "Value" "4.7nF_50V_0402"
			(at -2.592551 9.991575 180)
			(unlocked yes)
			(layer "F.SilkS")
			(hide yes)
			(effects
				(font
					(size 0.762 0.762)
					(thickness 0.2286)
				)
			)
		)
		(sheetname "POWER")
		(sheetfile "POWER.kicad_sch")
		(duplicate_pad_numbers_are_jumpers no)
		(fp_line
			(start 0.51967 0.68067)
			(end -0.53033 0.68067)
			(stroke
				(width 0.2)
				(type solid)
			)
			(layer "F.SilkS")
		)
		(fp_line
			(start 0.525 -0.675)
			(end -0.525 -0.675)
			(stroke
				(width 0.2)
				(type solid)
			)
			(layer "F.SilkS")
		)
		(fp_line
			(start -0.875 0.475)
			(end -0.875 -0.475)
			(stroke
				(width 0.2)
				(type solid)
			)
			(layer "F.CrtYd")
		)
		(fp_line
			(start 0.875 0.475)
			(end -0.875 0.475)
			(stroke
				(width 0.2)
				(type solid)
			)
			(layer "F.CrtYd")
		)
		(fp_line
			(start 0.875 0.475)
			(end 0.875 -0.475)
			(stroke
				(width 0.2)
				(type solid)
			)
			(layer "F.CrtYd")
		)
		(fp_line
			(start 0.875 -0.475)
			(end -0.875 -0.475)
			(stroke
				(width 0.2)
				(type solid)
			)
			(layer "F.CrtYd")
		)
		(fp_line
			(start 0 0.5)
			(end 0 -0.5)
			(stroke
				(width 0.1)
				(type solid)
			)
			(layer "F.Fab")
		)
		(fp_line
			(start -0.875 0.475)
			(end -0.875 -0.475)
			(stroke
				(width 0.2)
				(type solid)
			)
			(layer "F.Fab")
		)
		(fp_line
			(start 0.875 0.475)
			(end -0.875 0.475)
			(stroke
				(width 0.2)
				(type solid)
			)
			(layer "F.Fab")
		)
		(fp_line
			(start 0.875 0.475)
			(end 0.875 -0.475)
			(stroke
				(width 0.2)
				(type solid)
			)
			(layer "F.Fab")
		)
		(fp_line
			(start 0.5 0)
			(end -0.5 0)
			(stroke
				(width 0.1)
				(type solid)
			)
			(layer "F.Fab")
		)
		(fp_line
			(start 0.875 -0.475)
			(end -0.875 -0.475)
			(stroke
				(width 0.2)
				(type solid)
			)
			(layer "F.Fab")
		)
		(fp_text user "${REFERENCE}"
			(at -0.00001 0.09602 270)
			(unlocked yes)
			(layer "F.Fab")
			(effects
				(font
					(face "Arial")
					(size 0.63 0.63)
					(thickness 0.1)
				)
				(justify left bottom)
			)
		)
		(pad "1" smd rect
			(at -0.5 0 270)
			(size 0.5 0.5)
			(layers "F.Cu" "F.Mask" "F.Paste")
			(net "P3V3_SENSE")
			(solder_mask_margin 0)
			(solder_paste_margin 0)
		)
		(pad "2" smd rect
			(at 0.5 0 270)
			(size 0.5 0.5)
			(layers "F.Cu" "F.Mask" "F.Paste")
			(net "P3V3_FB")
			(solder_mask_margin 0)
			(solder_paste_margin 0)
		)
	)
	(footprint "Capacitors:CAPC2012X14N"
		(layer "F.Cu")
		(at 153.9261 80.6162 90)
		(property "Reference" "C62"
			(at 2 1.706655 270)
			(unlocked yes)
			(layer "F.SilkS")
			(effects
				(font
					(size 0.762 0.762)
					(thickness 0.2286)
				)
				(justify left bottom)
			)
		)
		(property "Value" "CAP_0805_10UF_25V"
			(at -2.433445 -1.7875 0)
			(unlocked yes)
			(layer "F.SilkS")
			(hide yes)
			(effects
				(font
					(size 0.762 0.762)
					(thickness 0.2286)
				)
				(justify left bottom)
			)
		)
		(sheetname "MAC")
		(sheetfile "MAC.kicad_sch")
		(duplicate_pad_numbers_are_jumpers no)
		(fp_line
			(start -0.762 -0.9652)
			(end 0.762 -0.9652)
			(stroke
				(width 0.1524)
				(type solid)
			)
			(layer "F.SilkS")
		)
		(fp_line
			(start -0.762 0.9652)
			(end 0.762 0.9652)
			(stroke
				(width 0.1524)
				(type solid)
			)
			(layer "F.SilkS")
		)
		(pad "1" smd rect
			(at -0.9 0 180)
			(size 1.45 1.15)
			(layers "F.Cu" "F.Mask" "F.Paste")
			(net "MAC_VCC")
		)
		(pad "2" smd rect
			(at 0.9 0 180)
			(size 1.45 1.15)
			(layers "F.Cu" "F.Mask" "F.Paste")
			(net "GND")
		)
	)
	(footprint "Vault:FP-ERJ2RK-IPC_A"
		(layer "F.Cu")
		(at 237.4261 137.0162 180)
		(property "Reference" "R1"
			(at -1.6 -0.393345 0)
			(unlocked yes)
			(layer "F.SilkS")
			(effects
				(font
					(size 0.762 0.762)
					(thickness 0.2286)
				)
				(justify left bottom)
			)
		)
		(property "Value" "200_1%_0402"
			(at 19.0909 -11.290235 0)
			(unlocked yes)
			(layer "F.SilkS")
			(hide yes)
			(effects
				(font
					(size 0.762 0.762)
					(thickness 0.2286)
				)
				(justify left bottom)
			)
		)
		(sheetname "POWER")
		(sheetfile "POWER.kicad_sch")
		(duplicate_pad_numbers_are_jumpers no)
		(fp_line
			(start 0.83624 0.73624)
			(end -0.83624 0.73624)
			(stroke
				(width 0.2)
				(type solid)
			)
			(layer "F.SilkS")
		)
		(fp_line
			(start 0.83624 -0.73624)
			(end -0.83624 -0.73624)
			(stroke
				(width 0.2)
				(type solid)
			)
			(layer "F.SilkS")
		)
		(fp_line
			(start 1.03624 0.53624)
			(end -1.03623 0.53624)
			(stroke
				(width 0.2)
				(type solid)
			)
			(layer "F.CrtYd")
		)
		(fp_line
			(start 1.03624 -0.53624)
			(end 1.03624 0.53624)
			(stroke
				(width 0.2)
				(type solid)
			)
			(layer "F.CrtYd")
		)
		(fp_line
			(start 1.03624 -0.53624)
			(end -1.03623 -0.53624)
			(stroke
				(width 0.2)
				(type solid)
			)
			(layer "F.CrtYd")
		)
		(fp_line
			(start -1.03623 -0.53624)
			(end -1.03623 0.53624)
			(stroke
				(width 0.2)
				(type solid)
			)
			(layer "F.CrtYd")
		)
		(fp_line
			(start 1.03624 0.53624)
			(end -1.03623 0.53624)
			(stroke
				(width 0.2)
				(type solid)
			)
			(layer "F.Fab")
		)
		(fp_line
			(start 1.03624 -0.53624)
			(end 1.03624 0.53624)
			(stroke
				(width 0.2)
				(type solid)
			)
			(layer "F.Fab")
		)
		(fp_line
			(start 1.03624 -0.53624)
			(end -1.03623 -0.53624)
			(stroke
				(width 0.2)
				(type solid)
			)
			(layer "F.Fab")
		)
		(fp_line
			(start 0.5 0)
			(end -0.5 0)
			(stroke
				(width 0.1)
				(type solid)
			)
			(layer "F.Fab")
		)
		(fp_line
			(start 0 -0.5)
			(end 0 0.5)
			(stroke
				(width 0.1)
				(type solid)
			)
			(layer "F.Fab")
		)
		(fp_line
			(start -1.03623 -0.53624)
			(end -1.03623 0.53624)
			(stroke
				(width 0.2)
				(type solid)
			)
			(layer "F.Fab")
		)
		(fp_text user "${REFERENCE}"
			(at -0.00001 0.10711 180)
			(unlocked yes)
			(layer "F.Fab")
			(effects
				(font
					(face "Arial")
					(size 0.63 0.63)
					(thickness 0.1)
				)
				(justify left bottom)
			)
		)
		(pad "1" smd rect
			(at -0.50215 0 180)
			(size 0.66818 0.67248)
			(layers "F.Cu" "F.Mask" "F.Paste")
			(net "GND")
			(solder_mask_margin 0)
			(solder_paste_margin 0)
		)
		(pad "2" smd rect
			(at 0.50215 0 180)
			(size 0.66818 0.67248)
			(layers "F.Cu" "F.Mask" "F.Paste")
			(net "NetD4_1")
			(solder_mask_margin 0)
			(solder_paste_margin 0)
		)
	)
	(footprint "Vault:CAPC1608X87X45ML20T05"
		(layer "F.Cu")
		(at 216.9261 66.5162)
		(property "Reference" "C57"
			(at -2.7714 0.126921 0)
			(unlocked yes)
			(layer "F.SilkS")
			(effects
				(font
					(size 0.762 0.762)
					(thickness 0.2286)
				)
			)
		)
		(property "Value" "0.1uF"
			(at 2.069035 2.630671 0)
			(unlocked yes)
			(layer "F.SilkS")
			(hide yes)
			(effects
				(font
					(size 0.762 0.762)
					(thickness 0.2286)
				)
			)
		)
		(sheetname "GPS_IMU_SENSORS")
		(sheetfile "GPS_IMU_SENSORS.kicad_sch")
		(duplicate_pad_numbers_are_jumpers no)
		(pad "1" smd rect
			(at -0.7 0 90)
			(size 1.1 1.05)
			(layers "F.Cu" "F.Mask" "F.Paste")
			(net "GND")
		)
		(pad "2" smd rect
			(at 0.7 0 90)
			(size 1.1 1.05)
			(layers "F.Cu" "F.Mask" "F.Paste")
			(net "+3.3V")
		)
	)
	(footprint "Passives:SOT65P210X110-3N"
		(layer "F.Cu")
		(at 224.9261 137.6162 -90)
		(property "Reference" "D8"
			(at -2.006655 0.6 0)
			(unlocked yes)
			(layer "F.SilkS")
			(effects
				(font
					(size 0.762 0.762)
					(thickness 0.2286)
				)
				(justify left bottom)
			)
		)
		(property "Value" "BAT54SW"
			(at 7.401445 -2.7501 0)
			(unlocked yes)
			(layer "F.SilkS")
			(hide yes)
			(effects
				(font
					(size 0.762 0.762)
					(thickness 0.2286)
				)
				(justify left bottom)
			)
		)
		(sheetname "PCIe_JTAG")
		(sheetfile "PCIe_JTAG.kicad_sch")
		(duplicate_pad_numbers_are_jumpers no)
		(fp_line
			(start 0.675 1.1)
			(end -0.325 1.1)
			(stroke
				(width 0.2)
				(type solid)
			)
			(layer "F.SilkS")
		)
		(fp_line
			(start 0.675 1.1)
			(end 0.675 0.65)
			(stroke
				(width 0.2)
				(type solid)
			)
			(layer "F.SilkS")
		)
		(fp_line
			(start 0.675 -0.65)
			(end 0.675 -1.1)
			(stroke
				(width 0.2)
				(type solid)
			)
			(layer "F.SilkS")
		)
		(fp_line
			(start 0.675 -1.1)
			(end -0.325 -1.1)
			(stroke
				(width 0.2)
				(type solid)
			)
			(layer "F.SilkS")
		)
		(fp_circle
			(center -1.125 -1.45)
			(end -1.25 -1.45)
			(stroke
				(width 0.25)
				(type solid)
			)
			(fill no)
			(layer "F.SilkS")
		)
		(pad "1" smd rect
			(at -1.125 -0.65)
			(size 0.5 0.9)
			(layers "F.Cu" "F.Mask" "F.Paste")
			(net "GND")
		)
		(pad "2" smd rect
			(at -1.125 0.65)
			(size 0.5 0.9)
			(layers "F.Cu" "F.Mask" "F.Paste")
			(net "+3.3V")
		)
		(pad "3" smd rect
			(at 1.125 0)
			(size 0.5 0.9)
			(layers "F.Cu" "F.Mask" "F.Paste")
			(net "FPGA_TDI")
		)
	)
	(footprint "SA53:SolderSocket"
		(layer "F.Cu")
		(at 139.9261 94.9162 90)
		(property "Reference" "SKT7"
			(at -2.726921 7.1286 0)
			(unlocked yes)
			(layer "F.SilkS")
			(effects
				(font
					(size 0.762 0.762)
					(thickness 0.2286)
				)
			)
		)
		(property "Value" "0332-0-43-80-18-27-10-0"
			(at -2.910071 16.1362 0)
			(unlocked yes)
			(layer "F.SilkS")
			(hide yes)
			(effects
				(font
					(size 0.762 0.762)
					(thickness 0.2286)
				)
			)
		)
		(sheetname "MAC")
		(sheetfile "MAC.kicad_sch")
		(duplicate_pad_numbers_are_jumpers no)
		(pad "1" thru_hole circle
			(at 0 0 90)
			(size 2.54 2.54)
			(drill 2.0066)
			(layers "*.Cu" "*.Mask")
			(remove_unused_layers no)
			(net "MAC_VCC")
			(thermal_bridge_angle 90)
		)
	)
	(footprint "Vault:CAPC1608X87X45ML20T05"
		(layer "F.Cu")
		(at 194.1761 83.5786 180)
		(property "Reference" "C30"
			(at -0.5786 2.235469 0)
			(unlocked yes)
			(layer "F.SilkS")
			(effects
				(font
					(size 0.762 0.762)
					(thickness 0.2286)
				)
			)
		)
		(property "Value" "0.1uF"
			(at 2.069035 2.630671 180)
			(unlocked yes)
			(layer "F.SilkS")
			(hide yes)
			(effects
				(font
					(size 0.762 0.762)
					(thickness 0.2286)
				)
			)
		)
		(sheetname "GPS_IMU_SENSORS")
		(sheetfile "GPS_IMU_SENSORS.kicad_sch")
		(duplicate_pad_numbers_are_jumpers no)
		(pad "1" smd rect
			(at -0.7 0 270)
			(size 1.1 1.05)
			(layers "F.Cu" "F.Mask" "F.Paste")
			(net "GND")
		)
		(pad "2" smd rect
			(at 0.7 0 270)
			(size 1.1 1.05)
			(layers "F.Cu" "F.Mask" "F.Paste")
			(net "+3.3V")
		)
	)
	(footprint "Vault:RESC1608X55X25NL10T15"
		(layer "F.Cu")
		(at 77.6261 95.1162 180)
		(property "Reference" "R25"
			(at -0.2286 1.223079 0)
			(unlocked yes)
			(layer "F.SilkS")
			(effects
				(font
					(size 0.762 0.762)
					(thickness 0.2286)
				)
			)
		)
		(property "Value" "49.9R"
			(at -2.884671 3.186595 90)
			(unlocked yes)
			(layer "F.SilkS")
			(hide yes)
			(effects
				(font
					(size 0.762 0.762)
					(thickness 0.2286)
				)
			)
		)
		(sheetname "USER_IO")
		(sheetfile "USER_IO.kicad_sch")
		(duplicate_pad_numbers_are_jumpers no)
		(pad "1" smd rect
			(at -0.7 0 270)
			(size 0.9 0.7)
			(layers "F.Cu" "F.Mask" "F.Paste")
			(net "NetR25_1")
		)
		(pad "2" smd rect
			(at 0.7 0 270)
			(size 0.9 0.7)
			(layers "F.Cu" "F.Mask" "F.Paste")
			(net "NetAN1_1")
		)
	)
	(footprint "Vault:RESC1005X40X25LL05T05"
		(layer "F.Cu")
		(at 202.9261 124.9162)
		(property "Reference" "R67"
			(at -3.1714 4.426931 0)
			(unlocked yes)
			(layer "F.SilkS")
			(effects
				(font
					(size 0.762 0.762)
					(thickness 0.2286)
				)
			)
		)
		(property "Value" "4.7K_0402"
			(at -2.389351 6.538405 270)
			(unlocked yes)
			(layer "F.SilkS")
			(hide yes)
			(effects
				(font
					(size 0.762 0.762)
					(thickness 0.2286)
				)
			)
		)
		(sheetname "POWER")
		(sheetfile "POWER.kicad_sch")
		(duplicate_pad_numbers_are_jumpers no)
		(pad "1" smd rect
			(at -0.4 0 90)
			(size 0.45 0.45)
			(layers "F.Cu" "F.Mask" "F.Paste")
			(net "+12V")
		)
		(pad "2" smd rect
			(at 0.4 0 90)
			(size 0.45 0.45)
			(layers "F.Cu" "F.Mask" "F.Paste")
			(net "NetR67_2")
		)
	)
	(footprint "Resistors:RESC1005X04N"
		(layer "F.Cu")
		(at 96.9261 143.3162)
		(property "Reference" "R24"
			(at 1.35111 0.884735 180)
			(unlocked yes)
			(layer "F.SilkS")
			(effects
				(font
					(size 0.762 0.762)
					(thickness 0.2286)
				)
				(justify left bottom)
			)
		)
		(property "Value" "ERJ-2GE0R00X"
			(at -0.2413 3.331845 0)
			(unlocked yes)
			(layer "F.SilkS")
			(hide yes)
			(effects
				(font
					(size 0.762 0.762)
					(thickness 0.2286)
				)
				(justify left bottom)
			)
		)
		(sheetname "PCIe_JTAG")
		(sheetfile "PCIe_JTAG.kicad_sch")
		(duplicate_pad_numbers_are_jumpers no)
		(pad "1" smd rect
			(at -0.425 0 90)
			(size 0.6 0.65)
			(layers "F.Cu" "F.Mask" "F.Paste")
			(net "PRSNT")
		)
		(pad "2" smd rect
			(at 0.425 0 90)
			(size 0.6 0.65)
			(layers "F.Cu" "F.Mask" "F.Paste")
			(net "NetP2_B31")
		)
	)
	(footprint "Miscellaneous Connectors:HDR2X6_CEN"
		(layer "F.Cu")
		(at 212.7461 51.5762 180)
		(property "Reference" "P3"
			(at 18.324329 -2.146705 90)
			(unlocked yes)
			(layer "F.SilkS")
			(effects
				(font
					(size 0.762 0.762)
					(thickness 0.2286)
				)
			)
		)
		(property "Value" "EXT GPIO"
			(at -4.281671 2.296855 90)
			(unlocked yes)
			(layer "F.SilkS")
			(hide yes)
			(effects
				(font
					(size 0.762 0.762)
					(thickness 0.2286)
				)
			)
		)
		(sheetname "GPS_IMU_SENSORS")
		(sheetfile "GPS_IMU_SENSORS.kicad_sch")
		(duplicate_pad_numbers_are_jumpers no)
		(fp_line
			(start 13.97 1.27)
			(end -1.27 1.27)
			(stroke
				(width 0.2)
				(type solid)
			)
			(layer "F.SilkS")
		)
		(fp_line
			(start 13.97 -3.81)
			(end 13.97 1.27)
			(stroke
				(width 0.2)
				(type solid)
			)
			(layer "F.SilkS")
		)
		(fp_line
			(start 13.97 -3.81)
			(end -1.27 -3.81)
			(stroke
				(width 0.2)
				(type solid)
			)
			(layer "F.SilkS")
		)
		(fp_line
			(start -1.27 -3.81)
			(end -1.27 1.27)
			(stroke
				(width 0.2)
				(type solid)
			)
			(layer "F.SilkS")
		)
		(fp_text user "6"
			(at 14.732 0.663575 180)
			(unlocked yes)
			(layer "F.SilkS")
			(effects
				(font
					(size 1.27 1.27)
					(thickness 0.2032)
				)
				(justify left bottom)
			)
		)
		(fp_text user "12"
			(at 14.732 -1.876425 180)
			(unlocked yes)
			(layer "F.SilkS")
			(effects
				(font
					(size 1.27 1.27)
					(thickness 0.2032)
				)
				(justify left bottom)
			)
		)
		(fp_text user "1"
			(at -2.54 0.663575 180)
			(unlocked yes)
			(layer "F.SilkS")
			(effects
				(font
					(size 1.27 1.27)
					(thickness 0.2032)
				)
				(justify left bottom)
			)
		)
		(fp_text user "7"
			(at -2.54 -1.876425 180)
			(unlocked yes)
			(layer "F.SilkS")
			(effects
				(font
					(size 1.27 1.27)
					(thickness 0.2032)
				)
				(justify left bottom)
			)
		)
		(pad "1" thru_hole rect
			(at 0 0 180)
			(size 1.5 1.5)
			(drill 0.9)
			(layers "*.Cu" "*.Mask")
			(remove_unused_layers no)
			(net "EXT_GPIO_1")
		)
		(pad "2" thru_hole circle
			(at 2.54 0 180)
			(size 1.5 1.5)
			(drill 0.9)
			(layers "*.Cu" "*.Mask")
			(remove_unused_layers no)
			(net "EXT_GPIO_2")
			(thermal_bridge_angle 90)
		)
		(pad "3" thru_hole circle
			(at 5.08 0 180)
			(size 1.5 1.5)
			(drill 0.9)
			(layers "*.Cu" "*.Mask")
			(remove_unused_layers no)
			(net "EXT_GPIO_3")
			(thermal_bridge_angle 90)
		)
		(pad "4" thru_hole circle
			(at 7.62 0 180)
			(size 1.5 1.5)
			(drill 0.9)
			(layers "*.Cu" "*.Mask")
			(remove_unused_layers no)
			(net "EXT_GPIO_4")
			(thermal_bridge_angle 90)
		)
		(pad "5" thru_hole circle
			(at 10.16 0 180)
			(size 1.5 1.5)
			(drill 0.9)
			(layers "*.Cu" "*.Mask")
			(remove_unused_layers no)
			(net "GND")
			(thermal_bridge_angle 90)
		)
		(pad "6" thru_hole circle
			(at 12.7 0 180)
			(size 1.5 1.5)
			(drill 0.9)
			(layers "*.Cu" "*.Mask")
			(remove_unused_layers no)
			(net "+3.3V")
			(thermal_bridge_angle 90)
		)
		(pad "7" thru_hole circle
			(at 0 -2.54 180)
			(size 1.5 1.5)
			(drill 0.9)
			(layers "*.Cu" "*.Mask")
			(remove_unused_layers no)
			(net "EXT_GPIO_7")
			(thermal_bridge_angle 90)
		)
		(pad "8" thru_hole circle
			(at 2.54 -2.54 180)
			(size 1.5 1.5)
			(drill 0.9)
			(layers "*.Cu" "*.Mask")
			(remove_unused_layers no)
			(net "EXT_GPIO_8")
			(thermal_bridge_angle 90)
		)
		(pad "9" thru_hole circle
			(at 5.08 -2.54 180)
			(size 1.5 1.5)
			(drill 0.9)
			(layers "*.Cu" "*.Mask")
			(remove_unused_layers no)
			(net "EXT_GPIO_9")
			(thermal_bridge_angle 90)
		)
		(pad "10" thru_hole circle
			(at 7.62 -2.54 180)
			(size 1.5 1.5)
			(drill 0.9)
			(layers "*.Cu" "*.Mask")
			(remove_unused_layers no)
			(net "EXT_GPIO_10")
			(thermal_bridge_angle 90)
		)
		(pad "11" thru_hole circle
			(at 10.16 -2.54 180)
			(size 1.5 1.5)
			(drill 0.9)
			(layers "*.Cu" "*.Mask")
			(remove_unused_layers no)
			(net "GND")
			(thermal_bridge_angle 90)
		)
		(pad "12" thru_hole circle
			(at 12.7 -2.54 180)
			(size 1.5 1.5)
			(drill 0.9)
			(layers "*.Cu" "*.Mask")
			(remove_unused_layers no)
			(net "+3.3V")
			(thermal_bridge_angle 90)
		)
	)
	(footprint "Vault:FP-GRM31C-0_2-e0_3_0_8-IPC_C"
		(layer "F.Cu")
		(at 214.5261 103.0162 90)
		(property "Reference" "C11"
			(at 3.8 -0.493345 270)
			(unlocked yes)
			(layer "F.SilkS")
			(effects
				(font
					(size 0.762 0.762)
					(thickness 0.2286)
				)
				(justify left bottom)
			)
		)
		(property "Value" "4.7uF_50V_1206"
			(at -23.717045 -0.1957 0)
			(unlocked yes)
			(layer "F.SilkS")
			(hide yes)
			(effects
				(font
					(size 0.762 0.762)
					(thickness 0.2286)
				)
				(justify left bottom)
			)
		)
		(sheetname "POWER")
		(sheetfile "POWER.kicad_sch")
		(duplicate_pad_numbers_are_jumpers no)
		(fp_line
			(start -0.39847 -0.9)
			(end 0.39846 -0.9)
			(stroke
				(width 0.2)
				(type solid)
			)
			(layer "F.SilkS")
		)
		(fp_line
			(start -0.39847 0.9)
			(end 0.39846 0.9)
			(stroke
				(width 0.2)
				(type solid)
			)
			(layer "F.SilkS")
		)
		(fp_line
			(start 1.9531 -1)
			(end 1.9531 1)
			(stroke
				(width 0.2)
				(type solid)
			)
			(layer "F.CrtYd")
		)
		(fp_line
			(start -1.9531 -1)
			(end 1.9531 -1)
			(stroke
				(width 0.2)
				(type solid)
			)
			(layer "F.CrtYd")
		)
		(fp_line
			(start -1.9531 -1)
			(end -1.9531 1)
			(stroke
				(width 0.2)
				(type solid)
			)
			(layer "F.CrtYd")
		)
		(fp_line
			(start -1.9531 1)
			(end 1.9531 1)
			(stroke
				(width 0.2)
				(type solid)
			)
			(layer "F.CrtYd")
		)
		(fp_line
			(start 1.9531 -1)
			(end 1.9531 1)
			(stroke
				(width 0.2)
				(type solid)
			)
			(layer "F.Fab")
		)
		(fp_line
			(start -1.9531 -1)
			(end 1.9531 -1)
			(stroke
				(width 0.2)
				(type solid)
			)
			(layer "F.Fab")
		)
		(fp_line
			(start -1.9531 -1)
			(end -1.9531 1)
			(stroke
				(width 0.2)
				(type solid)
			)
			(layer "F.Fab")
		)
		(fp_line
			(start 0 -0.5)
			(end 0 0.5)
			(stroke
				(width 0.1)
				(type solid)
			)
			(layer "F.Fab")
		)
		(fp_line
			(start -0.5 0)
			(end 0.5 0)
			(stroke
				(width 0.1)
				(type solid)
			)
			(layer "F.Fab")
		)
		(fp_line
			(start -1.9531 1)
			(end 1.9531 1)
			(stroke
				(width 0.2)
				(type solid)
			)
			(layer "F.Fab")
		)
		(fp_text user "${REFERENCE}"
			(at -0.00001 0.09602 90)
			(unlocked yes)
			(layer "F.Fab")
			(effects
				(font
					(face "Arial")
					(size 0.63 0.63)
					(thickness 0.1)
				)
				(justify left bottom)
			)
		)
		(pad "1" smd rect
			(at -1.27578 0 90)
			(size 1.15464 1.7062)
			(layers "F.Cu" "F.Mask" "F.Paste")
			(net "+12V")
			(solder_mask_margin 0)
			(solder_paste_margin 0)
		)
		(pad "2" smd rect
			(at 1.27578 0 90)
			(size 1.15464 1.7062)
			(layers "F.Cu" "F.Mask" "F.Paste")
			(net "GND")
			(solder_mask_margin 0)
			(solder_paste_margin 0)
		)
	)
	(footprint "Vault:CAPC1608X87X45ML20T05"
		(layer "F.Cu")
		(at 80.3761 139.6162 -90)
		(property "Reference" "C29"
			(at 2.7714 -0.026931 90)
			(unlocked yes)
			(layer "F.SilkS")
			(effects
				(font
					(size 0.762 0.762)
					(thickness 0.2286)
				)
			)
		)
		(property "Value" "0.1uF"
			(at 2.069035 2.630671 270)
			(unlocked yes)
			(layer "F.SilkS")
			(hide yes)
			(effects
				(font
					(size 0.762 0.762)
					(thickness 0.2286)
				)
			)
		)
		(sheetname "USER_IO")
		(sheetfile "USER_IO.kicad_sch")
		(duplicate_pad_numbers_are_jumpers no)
		(pad "1" smd rect
			(at -0.7 0)
			(size 1.1 1.05)
			(layers "F.Cu" "F.Mask" "F.Paste")
			(net "+3.3V")
		)
		(pad "2" smd rect
			(at 0.7 0)
			(size 1.1 1.05)
			(layers "F.Cu" "F.Mask" "F.Paste")
			(net "GND")
		)
	)
	(footprint "Vault:RESC1005X40X25NL05T10"
		(layer "F.Cu")
		(at 215.3261 113.5162 90)
		(property "Reference" "R60"
			(at 2.423929 2.04404 0)
			(unlocked yes)
			(layer "F.SilkS")
			(effects
				(font
					(size 0.762 0.762)
					(thickness 0.2286)
				)
			)
		)
		(property "Value" "19.6K_1%_0402"
			(at -2.732271 9.40766 0)
			(unlocked yes)
			(layer "F.SilkS")
			(hide yes)
			(effects
				(font
					(size 0.762 0.762)
					(thickness 0.2286)
				)
			)
		)
		(sheetname "POWER")
		(sheetfile "POWER.kicad_sch")
		(duplicate_pad_numbers_are_jumpers no)
		(pad "1" smd rect
			(at -0.425 0 180)
			(size 0.55 0.6)
			(layers "F.Cu" "F.Mask" "F.Paste")
			(net "NetC9_1")
		)
		(pad "2" smd rect
			(at 0.425 0 180)
			(size 0.55 0.6)
			(layers "F.Cu" "F.Mask" "F.Paste")
			(net "NetL1_1")
		)
	)
	(footprint "Connectors:PCIE_4LANE_EDGE"
		(layer "F.Cu")
		(at 118.02597 154.3547)
		(property "Reference" "P2"
			(at -12.64987 -0.282755 0)
			(unlocked yes)
			(layer "F.SilkS")
			(hide yes)
			(effects
				(font
					(size 0.762 0.762)
					(thickness 0.2286)
				)
				(justify left bottom)
			)
		)
		(property "Value" "PCIex4"
			(at -5.44907 18.557875 0)
			(unlocked yes)
			(layer "F.SilkS")
			(hide yes)
			(effects
				(font
					(size 0.762 0.762)
					(thickness 0.2286)
				)
				(justify left bottom)
			)
		)
		(sheetname "PCIe_JTAG")
		(sheetfile "PCIe_JTAG.kicad_sch")
		(duplicate_pad_numbers_are_jumpers no)
		(pad "A1" smd rect
			(at -16.49984 2.2286)
			(size 0.7112 3.2004)
			(layers "B.Cu" "B.Mask" "B.Paste")
			(net "PRSNT")
		)
		(pad "A2" smd rect
			(at -15.49985 2.7239)
			(size 0.7112 4.191)
			(layers "B.Cu" "B.Mask" "B.Paste")
			(net "+12V_PCIE")
		)
		(pad "A3" smd rect
			(at -14.49985 2.7239)
			(size 0.7112 4.191)
			(layers "B.Cu" "B.Mask" "B.Paste")
			(net "+12V_PCIE")
		)
		(pad "A4" smd rect
			(at -13.49985 2.7239)
			(size 0.7112 4.191)
			(layers "B.Cu" "B.Mask" "B.Paste")
			(net "GND")
		)
		(pad "A5" smd rect
			(at -12.49985 2.7239)
			(size 0.7112 4.191)
			(layers "B.Cu" "B.Mask" "B.Paste")
		)
		(pad "A6" smd rect
			(at -11.49985 2.7239)
			(size 0.7112 4.191)
			(layers "B.Cu" "B.Mask" "B.Paste")
		)
		(pad "A7" smd rect
			(at -10.49986 2.7239)
			(size 0.7112 4.191)
			(layers "B.Cu" "B.Mask" "B.Paste")
		)
		(pad "A8" smd rect
			(at -9.49986 2.7239)
			(size 0.7112 4.191)
			(layers "B.Cu" "B.Mask" "B.Paste")
		)
		(pad "A9" smd rect
			(at -8.49986 2.7239)
			(size 0.7112 4.191)
			(layers "B.Cu" "B.Mask" "B.Paste")
			(net "+3.3V_PCIE")
		)
		(pad "A10" smd rect
			(at -7.49986 2.7239)
			(size 0.7112 4.191)
			(layers "B.Cu" "B.Mask" "B.Paste")
			(net "+3.3V_PCIE")
		)
		(pad "A11" smd rect
			(at -6.49986 2.7239)
			(size 0.7112 4.191)
			(layers "B.Cu" "B.Mask" "B.Paste")
			(net "PCIE_PERST")
		)
		(pad "A12" smd rect
			(at -3.49987 2.7239)
			(size 0.7112 4.191)
			(layers "B.Cu" "B.Mask" "B.Paste")
			(net "GND")
		)
		(pad "A13" smd rect
			(at -2.49987 2.7239)
			(size 0.7112 4.191)
			(layers "B.Cu" "B.Mask" "B.Paste")
			(net "NetC44_1")
		)
		(pad "A14" smd rect
			(at -1.49987 2.7239)
			(size 0.7112 4.191)
			(layers "B.Cu" "B.Mask" "B.Paste")
			(net "NetC45_1")
		)
		(pad "A15" smd rect
			(at -0.49988 2.7239)
			(size 0.7112 4.191)
			(layers "B.Cu" "B.Mask" "B.Paste")
			(net "GND")
		)
		(pad "A16" smd rect
			(at 0.50012 2.7239)
			(size 0.7112 4.191)
			(layers "B.Cu" "B.Mask" "B.Paste")
			(net "NetC46_1")
		)
		(pad "A17" smd rect
			(at 1.50012 2.7239)
			(size 0.7112 4.191)
			(layers "B.Cu" "B.Mask" "B.Paste")
			(net "NetC47_1")
		)
		(pad "A18" smd rect
			(at 2.50012 2.7239)
			(size 0.7112 4.191)
			(layers "B.Cu" "B.Mask" "B.Paste")
			(net "GND")
		)
		(pad "A19" smd rect
			(at 3.50012 2.7239)
			(size 0.7112 4.191)
			(layers "B.Cu" "B.Mask" "B.Paste")
		)
		(pad "A20" smd rect
			(at 4.50011 2.7239)
			(size 0.7112 4.191)
			(layers "B.Cu" "B.Mask" "B.Paste")
			(net "GND")
		)
		(pad "A21" smd rect
			(at 5.50011 2.7239)
			(size 0.7112 4.191)
			(layers "B.Cu" "B.Mask" "B.Paste")
			(net "NetC48_1")
		)
		(pad "A22" smd rect
			(at 6.50011 2.7239)
			(size 0.7112 4.191)
			(layers "B.Cu" "B.Mask" "B.Paste")
			(net "NetC49_1")
		)
		(pad "A23" smd rect
			(at 7.50011 2.7239)
			(size 0.7112 4.191)
			(layers "B.Cu" "B.Mask" "B.Paste")
			(net "GND")
		)
		(pad "A24" smd rect
			(at 8.50011 2.7239)
			(size 0.7112 4.191)
			(layers "B.Cu" "B.Mask" "B.Paste")
			(net "GND")
		)
		(pad "A25" smd rect
			(at 9.5001 2.7239)
			(size 0.7112 4.191)
			(layers "B.Cu" "B.Mask" "B.Paste")
			(net "NetC50_1")
		)
		(pad "A26" smd rect
			(at 10.5001 2.7239)
			(size 0.7112 4.191)
			(layers "B.Cu" "B.Mask" "B.Paste")
			(net "NetC51_1")
		)
		(pad "A27" smd rect
			(at 11.5001 2.7239)
			(size 0.7112 4.191)
			(layers "B.Cu" "B.Mask" "B.Paste")
			(net "GND")
		)
		(pad "A28" smd rect
			(at 12.5001 2.7239)
			(size 0.7112 4.191)
			(layers "B.Cu" "B.Mask" "B.Paste")
			(net "GND")
		)
		(pad "A29" smd rect
			(at 13.5001 2.7239)
			(size 0.7112 4.191)
			(layers "B.Cu" "B.Mask" "B.Paste")
			(net "NetC52_1")
		)
		(pad "A30" smd rect
			(at 14.50009 2.7239)
			(size 0.7112 4.191)
			(layers "B.Cu" "B.Mask" "B.Paste")
			(net "NetC53_1")
		)
		(pad "A31" smd rect
			(at 15.50009 2.7239)
			(size 0.7112 4.191)
			(layers "B.Cu" "B.Mask" "B.Paste")
			(net "GND")
		)
		(pad "A32" smd rect
			(at 16.50009 2.7239)
			(size 0.7112 4.191)
			(layers "B.Cu" "B.Mask" "B.Paste")
		)
		(pad "B1" smd rect
			(at -16.49984 2.7239)
			(size 0.7112 4.191)
			(layers "F.Cu" "F.Mask" "F.Paste")
			(net "+12V_PCIE")
		)
		(pad "B2" smd rect
			(at -15.49985 2.7239)
			(size 0.7112 4.191)
			(layers "F.Cu" "F.Mask" "F.Paste")
			(net "+12V_PCIE")
		)
		(pad "B3" smd rect
			(at -14.49985 2.7239)
			(size 0.7112 4.191)
			(layers "F.Cu" "F.Mask" "F.Paste")
			(net "+12V_PCIE")
		)
		(pad "B4" smd rect
			(at -13.49985 2.7239)
			(size 0.7112 4.191)
			(layers "F.Cu" "F.Mask" "F.Paste")
			(net "GND")
		)
		(pad "B5" smd rect
			(at -12.49985 2.7239)
			(size 0.7112 4.191)
			(layers "F.Cu" "F.Mask" "F.Paste")
		)
		(pad "B6" smd rect
			(at -11.49985 2.7239)
			(size 0.7112 4.191)
			(layers "F.Cu" "F.Mask" "F.Paste")
		)
		(pad "B7" smd rect
			(at -10.49986 2.7239)
			(size 0.7112 4.191)
			(layers "F.Cu" "F.Mask" "F.Paste")
			(net "GND")
		)
		(pad "B8" smd rect
			(at -9.49986 2.7239)
			(size 0.7112 4.191)
			(layers "F.Cu" "F.Mask" "F.Paste")
			(net "+3.3V_PCIE")
		)
		(pad "B9" smd rect
			(at -8.49986 2.7239)
			(size 0.7112 4.191)
			(layers "F.Cu" "F.Mask" "F.Paste")
		)
		(pad "B10" smd rect
			(at -7.49986 2.7239)
			(size 0.7112 4.191)
			(layers "F.Cu" "F.Mask" "F.Paste")
		)
		(pad "B11" smd rect
			(at -6.49986 2.7239)
			(size 0.7112 4.191)
			(layers "F.Cu" "F.Mask" "F.Paste")
		)
		(pad "B12" smd rect
			(at -3.49987 2.7239)
			(size 0.7112 4.191)
			(layers "F.Cu" "F.Mask" "F.Paste")
		)
		(pad "B13" smd rect
			(at -2.49987 2.7239)
			(size 0.7112 4.191)
			(layers "F.Cu" "F.Mask" "F.Paste")
			(net "GND")
		)
		(pad "B14" smd rect
			(at -1.49987 2.7239)
			(size 0.7112 4.191)
			(layers "F.Cu" "F.Mask" "F.Paste")
			(net "PCIE_RX0_P")
		)
		(pad "B15" smd rect
			(at -0.49988 2.7239)
			(size 0.7112 4.191)
			(layers "F.Cu" "F.Mask" "F.Paste")
			(net "PCIE_RX0_N")
		)
		(pad "B16" smd rect
			(at 0.50012 2.7239)
			(size 0.7112 4.191)
			(layers "F.Cu" "F.Mask" "F.Paste")
			(net "GND")
		)
		(pad "B17" smd rect
			(at 1.50012 2.7239)
			(size 0.7112 4.191)
			(layers "F.Cu" "F.Mask" "F.Paste")
			(net "NetP2_B17")
		)
		(pad "B18" smd rect
			(at 2.50012 2.7239)
			(size 0.7112 4.191)
			(layers "F.Cu" "F.Mask" "F.Paste")
			(net "GND")
		)
		(pad "B19" smd rect
			(at 3.50012 2.7239)
			(size 0.7112 4.191)
			(layers "F.Cu" "F.Mask" "F.Paste")
			(net "PCIE_RX1_P")
		)
		(pad "B20" smd rect
			(at 4.50011 2.7239)
			(size 0.7112 4.191)
			(layers "F.Cu" "F.Mask" "F.Paste")
			(net "PCIE_RX1_N")
		)
		(pad "B21" smd rect
			(at 5.50011 2.7239)
			(size 0.7112 4.191)
			(layers "F.Cu" "F.Mask" "F.Paste")
			(net "GND")
		)
		(pad "B22" smd rect
			(at 6.50011 2.7239)
			(size 0.7112 4.191)
			(layers "F.Cu" "F.Mask" "F.Paste")
			(net "GND")
		)
		(pad "B23" smd rect
			(at 7.50011 2.7239)
			(size 0.7112 4.191)
			(layers "F.Cu" "F.Mask" "F.Paste")
			(net "PCIE_RX2_P")
		)
		(pad "B24" smd rect
			(at 8.50011 2.7239)
			(size 0.7112 4.191)
			(layers "F.Cu" "F.Mask" "F.Paste")
			(net "PCIE_RX2_N")
		)
		(pad "B25" smd rect
			(at 9.5001 2.7239)
			(size 0.7112 4.191)
			(layers "F.Cu" "F.Mask" "F.Paste")
			(net "GND")
		)
		(pad "B26" smd rect
			(at 10.5001 2.7239)
			(size 0.7112 4.191)
			(layers "F.Cu" "F.Mask" "F.Paste")
			(net "GND")
		)
		(pad "B27" smd rect
			(at 11.5001 2.7239)
			(size 0.7112 4.191)
			(layers "F.Cu" "F.Mask" "F.Paste")
			(net "PCIE_RX3_P")
		)
		(pad "B28" smd rect
			(at 12.5001 2.7239)
			(size 0.7112 4.191)
			(layers "F.Cu" "F.Mask" "F.Paste")
			(net "PCIE_RX3_N")
		)
		(pad "B29" smd rect
			(at 13.5001 2.7239)
			(size 0.7112 4.191)
			(layers "F.Cu" "F.Mask" "F.Paste")
			(net "GND")
		)
		(pad "B30" smd rect
			(at 14.50009 2.7239)
			(size 0.7112 4.191)
			(layers "F.Cu" "F.Mask" "F.Paste")
		)
		(pad "B31" smd rect
			(at 15.50009 2.2286)
			(size 0.7112 3.2004)
			(layers "F.Cu" "F.Mask" "F.Paste")
			(net "NetP2_B31")
		)
		(pad "B32" smd rect
			(at 16.50009 2.7239)
			(size 0.7112 4.191)
			(layers "F.Cu" "F.Mask" "F.Paste")
			(net "GND")
		)
	)
	(footprint "Resistors:RESC1005X04N"
		(layer "F.Cu")
		(at 96.9261 142.2162)
		(property "Reference" "R23"
			(at 1.27491 0.808535 180)
			(unlocked yes)
			(layer "F.SilkS")
			(effects
				(font
					(size 0.762 0.762)
					(thickness 0.2286)
				)
				(justify left bottom)
			)
		)
		(property "Value" "ERJ-2GE0R00X"
			(at -0.2413 3.331845 0)
			(unlocked yes)
			(layer "F.SilkS")
			(hide yes)
			(effects
				(font
					(size 0.762 0.762)
					(thickness 0.2286)
				)
				(justify left bottom)
			)
		)
		(sheetname "PCIe_JTAG")
		(sheetfile "PCIe_JTAG.kicad_sch")
		(duplicate_pad_numbers_are_jumpers no)
		(pad "1" smd rect
			(at -0.425 0 90)
			(size 0.6 0.65)
			(layers "F.Cu" "F.Mask" "F.Paste")
			(net "PRSNT")
		)
		(pad "2" smd rect
			(at 0.425 0 90)
			(size 0.6 0.65)
			(layers "F.Cu" "F.Mask" "F.Paste")
			(net "NetP2_B17")
		)
	)
	(footprint "Vault:RESC1005X40X25NL05T05"
		(layer "F.Cu")
		(at 214.1261 80.0162 180)
		(property "Reference" "R92"
			(at -0.6286 -1.126921 0)
			(unlocked yes)
			(layer "F.SilkS")
			(effects
				(font
					(size 0.762 0.762)
					(thickness 0.2286)
				)
			)
		)
		(property "Value" "27_1%_0402"
			(at -2.732271 7.37632 90)
			(unlocked yes)
			(layer "F.SilkS")
			(hide yes)
			(effects
				(font
					(size 0.762 0.762)
					(thickness 0.2286)
				)
			)
		)
		(sheetname "USBUart_DipSelects")
		(sheetfile "USBUart_DipSelects.kicad_sch")
		(duplicate_pad_numbers_are_jumpers no)
		(pad "1" smd rect
			(at -0.45 0 270)
			(size 0.55 0.55)
			(layers "F.Cu" "F.Mask" "F.Paste")
			(net "FTDI_TX")
		)
		(pad "2" smd rect
			(at 0.45 0 270)
			(size 0.55 0.55)
			(layers "F.Cu" "F.Mask" "F.Paste")
			(net "NetR92_2")
		)
	)
	(footprint "FPGA_CONN:SingleFPGAConn"
		(layer "F.Cu")
		(at 149.7158 124.56234)
		(property "Reference" "J36"
			(at -0.39436 -23.455129 0)
			(unlocked yes)
			(layer "F.SilkS")
			(effects
				(font
					(size 0.762 0.762)
					(thickness 0.2286)
				)
			)
		)
		(property "Value" "Single FPGA Conn"
			(at 9.25452 3.621231 0)
			(unlocked yes)
			(layer "F.SilkS")
			(hide yes)
			(effects
				(font
					(size 0.762 0.762)
					(thickness 0.2286)
				)
			)
		)
		(sheetname "FPGA")
		(sheetfile "FPGA.kicad_sch")
		(duplicate_pad_numbers_are_jumpers no)
		(fp_line
			(start -1.99999 -20.69998)
			(end -1.40005 -20.69998)
			(stroke
				(width 0.15011)
				(type solid)
			)
			(layer "F.SilkS")
		)
		(fp_line
			(start -1.99999 -20.03298)
			(end -1.99999 -20.69998)
			(stroke
				(width 0.15011)
				(type solid)
			)
			(layer "F.SilkS")
		)
		(fp_line
			(start -1.99999 0.70003)
			(end -1.99999 0.03302)
			(stroke
				(width 0.15011)
				(type solid)
			)
			(layer "F.SilkS")
		)
		(fp_line
			(start -1.99999 0.70003)
			(end -1.40005 0.70003)
			(stroke
				(width 0.15011)
				(type solid)
			)
			(layer "F.SilkS")
		)
		(fp_line
			(start -1.40005 -21.24989)
			(end 1.40005 -21.24989)
			(stroke
				(width 0.15011)
				(type solid)
			)
			(layer "F.SilkS")
		)
		(fp_line
			(start -1.40005 -20.69998)
			(end -1.40005 -21.24989)
			(stroke
				(width 0.15011)
				(type solid)
			)
			(layer "F.SilkS")
		)
		(fp_line
			(start -1.40005 1.24994)
			(end -1.40005 0.70003)
			(stroke
				(width 0.15011)
				(type solid)
			)
			(layer "F.SilkS")
		)
		(fp_line
			(start -1.40005 1.24994)
			(end 1.40005 1.24994)
			(stroke
				(width 0.15011)
				(type solid)
			)
			(layer "F.SilkS")
		)
		(fp_line
			(start 1.40005 -21.24989)
			(end 2 -20.69998)
			(stroke
				(width 0.15011)
				(type solid)
			)
			(layer "F.SilkS")
		)
		(fp_line
			(start 1.40005 1.24994)
			(end 2 0.70003)
			(stroke
				(width 0.15011)
				(type solid)
			)
			(layer "F.SilkS")
		)
		(fp_line
			(start 2 -20.03298)
			(end 2 -20.69998)
			(stroke
				(width 0.15011)
				(type solid)
			)
			(layer "F.SilkS")
		)
		(fp_line
			(start 2 0.70003)
			(end 2 0.03302)
			(stroke
				(width 0.15011)
				(type solid)
			)
			(layer "F.SilkS")
		)
		(fp_circle
			(center 3.5052 -0.22453)
			(end 3.5052 -0.42468)
			(stroke
				(width 0.40005)
				(type solid)
			)
			(fill no)
			(layer "F.SilkS")
		)
		(pad "1" smd rect
			(at 2.02489 -0.24993)
			(size 1.54991 0.24994)
			(layers "F.Cu" "F.Mask" "F.Paste")
			(net "GPS2_TX_FPGA")
		)
		(pad "2" smd rect
			(at -2.02489 -0.24993)
			(size 1.54991 0.24994)
			(layers "F.Cu" "F.Mask" "F.Paste")
			(net "GPS2_RX_FPGA")
		)
		(pad "3" smd rect
			(at 2.02489 -0.75006)
			(size 1.54991 0.24994)
			(layers "F.Cu" "F.Mask" "F.Paste")
		)
		(pad "4" smd rect
			(at -2.02489 -0.75006)
			(size 1.54991 0.24994)
			(layers "F.Cu" "F.Mask" "F.Paste")
		)
		(pad "5" smd rect
			(at 2.02489 -1.24993)
			(size 1.54991 0.24994)
			(layers "F.Cu" "F.Mask" "F.Paste")
			(net "GPS2_TP1")
		)
		(pad "6" smd rect
			(at -2.02489 -1.24993)
			(size 1.54991 0.24994)
			(layers "F.Cu" "F.Mask" "F.Paste")
		)
		(pad "7" smd rect
			(at 2.02489 -1.75006)
			(size 1.54991 0.24994)
			(layers "F.Cu" "F.Mask" "F.Paste")
			(net "GPS2_TP2")
		)
		(pad "8" smd rect
			(at -2.02489 -1.75006)
			(size 1.54991 0.24994)
			(layers "F.Cu" "F.Mask" "F.Paste")
		)
		(pad "9" smd rect
			(at 2.02489 -2.24993)
			(size 1.54991 0.24994)
			(layers "F.Cu" "F.Mask" "F.Paste")
			(net "GND")
		)
		(pad "10" smd rect
			(at -2.02489 -2.24993)
			(size 1.54991 0.24994)
			(layers "F.Cu" "F.Mask" "F.Paste")
			(net "GND")
		)
		(pad "11" smd rect
			(at 2.02489 -2.75006)
			(size 1.54991 0.24994)
			(layers "F.Cu" "F.Mask" "F.Paste")
			(net "GPS2_RST")
		)
		(pad "12" smd rect
			(at -2.02489 -2.75006)
			(size 1.54991 0.24994)
			(layers "F.Cu" "F.Mask" "F.Paste")
			(net "IO_LED1")
		)
		(pad "13" smd rect
			(at 2.02489 -3.24993)
			(size 1.54991 0.24994)
			(layers "F.Cu" "F.Mask" "F.Paste")
		)
		(pad "14" smd rect
			(at -2.02489 -3.24993)
			(size 1.54991 0.24994)
			(layers "F.Cu" "F.Mask" "F.Paste")
			(net "IO_LED2")
		)
		(pad "15" smd rect
			(at 2.02489 -3.75005)
			(size 1.54991 0.24994)
			(layers "F.Cu" "F.Mask" "F.Paste")
		)
		(pad "16" smd rect
			(at -2.02489 -3.75005)
			(size 1.54991 0.24994)
			(layers "F.Cu" "F.Mask" "F.Paste")
			(net "IO_LED3")
		)
		(pad "17" smd rect
			(at 2.02489 -4.24993)
			(size 1.54991 0.24994)
			(layers "F.Cu" "F.Mask" "F.Paste")
		)
		(pad "18" smd rect
			(at -2.02489 -4.24993)
			(size 1.54991 0.24994)
			(layers "F.Cu" "F.Mask" "F.Paste")
			(net "IO_LED4")
		)
		(pad "19" smd rect
			(at 2.02489 -4.75005)
			(size 1.54991 0.24994)
			(layers "F.Cu" "F.Mask" "F.Paste")
			(net "GND")
		)
		(pad "20" smd rect
			(at -2.02489 -4.75005)
			(size 1.54991 0.24994)
			(layers "F.Cu" "F.Mask" "F.Paste")
			(net "GND")
		)
		(pad "21" smd rect
			(at 2.02489 -5.24992)
			(size 1.54991 0.24994)
			(layers "F.Cu" "F.Mask" "F.Paste")
			(net "PCIE_PERST")
		)
		(pad "22" smd rect
			(at -2.02489 -5.24992)
			(size 1.54991 0.24994)
			(layers "F.Cu" "F.Mask" "F.Paste")
		)
		(pad "23" smd rect
			(at 2.02489 -5.75005)
			(size 1.54991 0.24994)
			(layers "F.Cu" "F.Mask" "F.Paste")
			(net "KEY1")
		)
		(pad "24" smd rect
			(at -2.02489 -5.75005)
			(size 1.54991 0.24994)
			(layers "F.Cu" "F.Mask" "F.Paste")
		)
		(pad "25" smd rect
			(at 2.02489 -6.24992)
			(size 1.54991 0.24994)
			(layers "F.Cu" "F.Mask" "F.Paste")
		)
		(pad "26" smd rect
			(at -2.02489 -6.24992)
			(size 1.54991 0.24994)
			(layers "F.Cu" "F.Mask" "F.Paste")
		)
		(pad "27" smd rect
			(at 2.02489 -6.75005)
			(size 1.54991 0.24994)
			(layers "F.Cu" "F.Mask" "F.Paste")
		)
		(pad "28" smd rect
			(at -2.02489 -6.75005)
			(size 1.54991 0.24994)
			(layers "F.Cu" "F.Mask" "F.Paste")
		)
		(pad "29" smd rect
			(at 2.02489 -7.24992)
			(size 1.54991 0.24994)
			(layers "F.Cu" "F.Mask" "F.Paste")
			(net "GND")
		)
		(pad "30" smd rect
			(at -2.02489 -7.24992)
			(size 1.54991 0.24994)
			(layers "F.Cu" "F.Mask" "F.Paste")
			(net "GND")
		)
		(pad "31" smd rect
			(at 2.02489 -7.75005)
			(size 1.54991 0.24994)
			(layers "F.Cu" "F.Mask" "F.Paste")
			(net "ANT1_IO_OUT")
		)
		(pad "32" smd rect
			(at -2.02489 -7.75005)
			(size 1.54991 0.24994)
			(layers "F.Cu" "F.Mask" "F.Paste")
			(net "EXT_GPIO_7")
		)
		(pad "33" smd rect
			(at 2.02489 -8.24992)
			(size 1.54991 0.24994)
			(layers "F.Cu" "F.Mask" "F.Paste")
			(net "ANT1_IO_IN")
		)
		(pad "34" smd rect
			(at -2.02489 -8.24992)
			(size 1.54991 0.24994)
			(layers "F.Cu" "F.Mask" "F.Paste")
			(net "EXT_GPIO_8")
		)
		(pad "35" smd rect
			(at 2.02489 -8.75004)
			(size 1.54991 0.24994)
			(layers "F.Cu" "F.Mask" "F.Paste")
			(net "ANT2_IO_OUT")
		)
		(pad "36" smd rect
			(at -2.02489 -8.75004)
			(size 1.54991 0.24994)
			(layers "F.Cu" "F.Mask" "F.Paste")
			(net "EXT_GPIO_9")
		)
		(pad "37" smd rect
			(at 2.02489 -9.24992)
			(size 1.54991 0.24994)
			(layers "F.Cu" "F.Mask" "F.Paste")
			(net "ANT2_IO_IN")
		)
		(pad "38" smd rect
			(at -2.02489 -9.24992)
			(size 1.54991 0.24994)
			(layers "F.Cu" "F.Mask" "F.Paste")
			(net "EXT_GPIO_10")
		)
		(pad "39" smd rect
			(at 2.02489 -9.75004)
			(size 1.54991 0.24994)
			(layers "F.Cu" "F.Mask" "F.Paste")
			(net "GND")
		)
		(pad "40" smd rect
			(at -2.02489 -9.75004)
			(size 1.54991 0.24994)
			(layers "F.Cu" "F.Mask" "F.Paste")
			(net "GND")
		)
		(pad "41" smd rect
			(at 2.02489 -10.24991)
			(size 1.54991 0.24994)
			(layers "F.Cu" "F.Mask" "F.Paste")
			(net "ANT3_IO_OUT")
		)
		(pad "42" smd rect
			(at -2.02489 -10.24991)
			(size 1.54991 0.24994)
			(layers "F.Cu" "F.Mask" "F.Paste")
			(net "EXT_GPIO_1")
		)
		(pad "43" smd rect
			(at 2.02489 -10.75004)
			(size 1.54991 0.24994)
			(layers "F.Cu" "F.Mask" "F.Paste")
			(net "ANT3_IO_IN")
		)
		(pad "44" smd rect
			(at -2.02489 -10.75004)
			(size 1.54991 0.24994)
			(layers "F.Cu" "F.Mask" "F.Paste")
			(net "EXT_GPIO_2")
		)
		(pad "45" smd rect
			(at 2.02489 -11.24991)
			(size 1.54991 0.24994)
			(layers "F.Cu" "F.Mask" "F.Paste")
			(net "ANT4_IO_OUT")
		)
		(pad "46" smd rect
			(at -2.02489 -11.24991)
			(size 1.54991 0.24994)
			(layers "F.Cu" "F.Mask" "F.Paste")
			(net "EXT_GPIO_3")
		)
		(pad "47" smd rect
			(at 2.02489 -11.75004)
			(size 1.54991 0.24994)
			(layers "F.Cu" "F.Mask" "F.Paste")
			(net "ANT4_IO_IN")
		)
		(pad "48" smd rect
			(at -2.02489 -11.75004)
			(size 1.54991 0.24994)
			(layers "F.Cu" "F.Mask" "F.Paste")
			(net "EXT_GPIO_4")
		)
		(pad "49" smd rect
			(at 2.02489 -12.24991)
			(size 1.54991 0.24994)
			(layers "F.Cu" "F.Mask" "F.Paste")
			(net "GND")
		)
		(pad "50" smd rect
			(at -2.02489 -12.24991)
			(size 1.54991 0.24994)
			(layers "F.Cu" "F.Mask" "F.Paste")
			(net "GND")
		)
		(pad "51" smd rect
			(at 2.02489 -12.75004)
			(size 1.54991 0.24994)
			(layers "F.Cu" "F.Mask" "F.Paste")
		)
		(pad "52" smd rect
			(at -2.02489 -12.75004)
			(size 1.54991 0.24994)
			(layers "F.Cu" "F.Mask" "F.Paste")
		)
		(pad "53" smd rect
			(at 2.02489 -13.24991)
			(size 1.54991 0.24994)
			(layers "F.Cu" "F.Mask" "F.Paste")
		)
		(pad "54" smd rect
			(at -2.02489 -13.24991)
			(size 1.54991 0.24994)
			(layers "F.Cu" "F.Mask" "F.Paste")
		)
		(pad "55" smd rect
			(at 2.02489 -13.75003)
			(size 1.54991 0.24994)
			(layers "F.Cu" "F.Mask" "F.Paste")
		)
		(pad "56" smd rect
			(at -2.02489 -13.75003)
			(size 1.54991 0.24994)
			(layers "F.Cu" "F.Mask" "F.Paste")
		)
		(pad "57" smd rect
			(at 2.02489 -14.24991)
			(size 1.54991 0.24994)
			(layers "F.Cu" "F.Mask" "F.Paste")
		)
		(pad "58" smd rect
			(at -2.02489 -14.24991)
			(size 1.54991 0.24994)
			(layers "F.Cu" "F.Mask" "F.Paste")
		)
		(pad "59" smd rect
			(at 2.02489 -14.75003)
			(size 1.54991 0.24994)
			(layers "F.Cu" "F.Mask" "F.Paste")
			(net "GND")
		)
		(pad "60" smd rect
			(at -2.02489 -14.75003)
			(size 1.54991 0.24994)
			(layers "F.Cu" "F.Mask" "F.Paste")
			(net "GND")
		)
		(pad "61" smd rect
			(at 2.02489 -15.2499)
			(size 1.54991 0.24994)
			(layers "F.Cu" "F.Mask" "F.Paste")
		)
		(pad "62" smd rect
			(at -2.02489 -15.2499)
			(size 1.54991 0.24994)
			(layers "F.Cu" "F.Mask" "F.Paste")
		)
		(pad "63" smd rect
			(at 2.02489 -15.75003)
			(size 1.54991 0.24994)
			(layers "F.Cu" "F.Mask" "F.Paste")
		)
		(pad "64" smd rect
			(at -2.02489 -15.75003)
			(size 1.54991 0.24994)
			(layers "F.Cu" "F.Mask" "F.Paste")
		)
		(pad "65" smd rect
			(at 2.02489 -16.2499)
			(size 1.54991 0.24994)
			(layers "F.Cu" "F.Mask" "F.Paste")
		)
		(pad "66" smd rect
			(at -2.02489 -16.2499)
			(size 1.54991 0.24994)
			(layers "F.Cu" "F.Mask" "F.Paste")
		)
		(pad "67" smd rect
			(at 2.02489 -16.75003)
			(size 1.54991 0.24994)
			(layers "F.Cu" "F.Mask" "F.Paste")
		)
		(pad "68" smd rect
			(at -2.02489 -16.75003)
			(size 1.54991 0.24994)
			(layers "F.Cu" "F.Mask" "F.Paste")
		)
		(pad "69" smd rect
			(at 2.02489 -17.2499)
			(size 1.54991 0.24994)
			(layers "F.Cu" "F.Mask" "F.Paste")
			(net "GND")
		)
		(pad "70" smd rect
			(at -2.02489 -17.2499)
			(size 1.54991 0.24994)
			(layers "F.Cu" "F.Mask" "F.Paste")
			(net "GND")
		)
		(pad "71" smd rect
			(at 2.02489 -17.75003)
			(size 1.54991 0.24994)
			(layers "F.Cu" "F.Mask" "F.Paste")
		)
		(pad "72" smd rect
			(at -2.02489 -17.75003)
			(size 1.54991 0.24994)
			(layers "F.Cu" "F.Mask" "F.Paste")
		)
		(pad "73" smd rect
			(at 2.02489 -18.2499)
			(size 1.54991 0.24994)
			(layers "F.Cu" "F.Mask" "F.Paste")
		)
		(pad "74" smd rect
			(at -2.02489 -18.2499)
			(size 1.54991 0.24994)
			(layers "F.Cu" "F.Mask" "F.Paste")
		)
		(pad "75" smd rect
			(at 2.02489 -18.75002)
			(size 1.54991 0.24994)
			(layers "F.Cu" "F.Mask" "F.Paste")
		)
		(pad "76" smd rect
			(at -2.02489 -18.75002)
			(size 1.54991 0.24994)
			(layers "F.Cu" "F.Mask" "F.Paste")
		)
		(pad "77" smd rect
			(at 2.02489 -19.2499)
			(size 1.54991 0.24994)
			(layers "F.Cu" "F.Mask" "F.Paste")
			(net "FPGA_TCK")
		)
		(pad "78" smd rect
			(at -2.02489 -19.2499)
			(size 1.54991 0.24994)
			(layers "F.Cu" "F.Mask" "F.Paste")
			(net "FPGA_TDI")
		)
		(pad "79" smd rect
			(at 2.02489 -19.75002)
			(size 1.54991 0.24994)
			(layers "F.Cu" "F.Mask" "F.Paste")
			(net "FPGA_TDO")
		)
		(pad "80" smd rect
			(at -2.02489 -19.75002)
			(size 1.54991 0.24994)
			(layers "F.Cu" "F.Mask" "F.Paste")
			(net "FPGA_TMS")
		)
		(pad "81" smd rect
			(at 0.01136 1.17626)
			(size 1.70002 1.35001)
			(layers "F.Cu" "F.Mask" "F.Paste")
		)
		(pad "82" thru_hole circle
			(at 0 0)
			(size 0.55016 0.55016)
			(drill 0.55016)
			(layers "*.Cu" "*.Mask")
			(remove_unused_layers no)
			(thermal_bridge_angle 90)
		)
		(pad "83" thru_hole circle
			(at 0 -19.99996)
			(size 0.55016 0.55016)
			(drill 0.55016)
			(layers "*.Cu" "*.Mask")
			(remove_unused_layers no)
			(thermal_bridge_angle 90)
		)
		(pad "84" smd rect
			(at 0.01136 -21.17374)
			(size 1.70002 1.35001)
			(layers "F.Cu" "F.Mask" "F.Paste")
		)
	)
	(footprint "Vault:FP-0603-L_1_6_0_2-W_0_8_0-MFG"
		(layer "F.Cu")
		(at 232.1261 121.2162)
		(property "Reference" "C80"
			(at 2.6286 0.126921 0)
			(unlocked yes)
			(layer "F.SilkS")
			(effects
				(font
					(size 0.762 0.762)
					(thickness 0.2286)
				)
			)
		)
		(property "Value" "10uF_16V_0603"
			(at -2.871951 8.95046 270)
			(unlocked yes)
			(layer "F.SilkS")
			(hide yes)
			(effects
				(font
					(size 0.762 0.762)
					(thickness 0.2286)
				)
			)
		)
		(sheetname "POWER")
		(sheetfile "POWER.kicad_sch")
		(duplicate_pad_numbers_are_jumpers no)
		(fp_line
			(start -0.9 -0.825)
			(end 0.9 -0.825)
			(stroke
				(width 0.2)
				(type solid)
			)
			(layer "F.SilkS")
		)
		(fp_line
			(start -0.9 0.825)
			(end 0.9 0.825)
			(stroke
				(width 0.2)
				(type solid)
			)
			(layer "F.SilkS")
		)
		(fp_line
			(start -1.15 -0.6)
			(end 1.15 -0.6)
			(stroke
				(width 0.2)
				(type solid)
			)
			(layer "F.CrtYd")
		)
		(fp_line
			(start -1.15 0.6)
			(end -1.15 -0.6)
			(stroke
				(width 0.2)
				(type solid)
			)
			(layer "F.CrtYd")
		)
		(fp_line
			(start -1.15 0.6)
			(end 1.15 0.6)
			(stroke
				(width 0.2)
				(type solid)
			)
			(layer "F.CrtYd")
		)
		(fp_line
			(start 1.15 0.6)
			(end 1.15 -0.6)
			(stroke
				(width 0.2)
				(type solid)
			)
			(layer "F.CrtYd")
		)
		(fp_line
			(start -1.15 -0.6)
			(end 1.15 -0.6)
			(stroke
				(width 0.2)
				(type solid)
			)
			(layer "F.Fab")
		)
		(fp_line
			(start -1.15 0.6)
			(end -1.15 -0.6)
			(stroke
				(width 0.2)
				(type solid)
			)
			(layer "F.Fab")
		)
		(fp_line
			(start -1.15 0.6)
			(end 1.15 0.6)
			(stroke
				(width 0.2)
				(type solid)
			)
			(layer "F.Fab")
		)
		(fp_line
			(start -0.5 0)
			(end 0.5 0)
			(stroke
				(width 0.1)
				(type solid)
			)
			(layer "F.Fab")
		)
		(fp_line
			(start 0 0.5)
			(end 0 -0.5)
			(stroke
				(width 0.1)
				(type solid)
			)
			(layer "F.Fab")
		)
		(fp_line
			(start 1.15 0.6)
			(end 1.15 -0.6)
			(stroke
				(width 0.2)
				(type solid)
			)
			(layer "F.Fab")
		)
		(fp_text user "${REFERENCE}"
			(at -0.00001 0.09602 360)
			(unlocked yes)
			(layer "F.Fab")
			(effects
				(font
					(face "Arial")
					(size 0.63 0.63)
					(thickness 0.1)
				)
				(justify left bottom)
			)
		)
		(pad "1" smd rect
			(at -0.7 0)
			(size 0.7 0.7)
			(layers "F.Cu" "F.Mask" "F.Paste")
			(net "+3.3V")
			(solder_mask_margin 0)
			(solder_paste_margin 0)
		)
		(pad "2" smd rect
			(at 0.7 0)
			(size 0.7 0.7)
			(layers "F.Cu" "F.Mask" "F.Paste")
			(net "GND")
			(solder_mask_margin 0)
			(solder_paste_margin 0)
		)
	)
	(footprint "Vault:RESC1005X40X25NL05T05"
		(layer "F.Cu")
		(at 222.6261 80.4162 180)
		(property "Reference" "R86"
			(at -2.4286 -0.326921 0)
			(unlocked yes)
			(layer "F.SilkS")
			(effects
				(font
					(size 0.762 0.762)
					(thickness 0.2286)
				)
			)
		)
		(property "Value" "27_1%_0402"
			(at -2.732271 7.37632 90)
			(unlocked yes)
			(layer "F.SilkS")
			(hide yes)
			(effects
				(font
					(size 0.762 0.762)
					(thickness 0.2286)
				)
			)
		)
		(sheetname "USBUart_DipSelects")
		(sheetfile "USBUart_DipSelects.kicad_sch")
		(duplicate_pad_numbers_are_jumpers no)
		(pad "1" smd rect
			(at -0.45 0 270)
			(size 0.55 0.55)
			(layers "F.Cu" "F.Mask" "F.Paste")
			(net "GND")
		)
		(pad "2" smd rect
			(at 0.45 0 270)
			(size 0.55 0.55)
			(layers "F.Cu" "F.Mask" "F.Paste")
			(net "NetR86_2")
		)
	)
	(footprint "Vault:RESC1005X40X25LL05T10"
		(layer "F.Cu")
		(at 129.1261 85.7162 -90)
		(property "Reference" "R107"
			(at 0.3286 -0.873069 270)
			(unlocked yes)
			(layer "F.SilkS")
			(effects
				(font
					(size 0.762 0.762)
					(thickness 0.2286)
				)
			)
		)
		(property "Value" "DNI_49.9_1%_0402"
			(at -2.579871 11.74373 180)
			(unlocked yes)
			(layer "F.SilkS")
			(hide yes)
			(effects
				(font
					(size 0.762 0.762)
					(thickness 0.2286)
				)
			)
		)
		(sheetname "USBUart_DipSelects")
		(sheetfile "USBUart_DipSelects.kicad_sch")
		(duplicate_pad_numbers_are_jumpers no)
		(pad "1" smd rect
			(at -0.375 0)
			(size 0.45 0.5)
			(layers "F.Cu" "F.Mask" "F.Paste")
			(net "FPGA_MAC_PPS_IN0-")
		)
		(pad "2" smd rect
			(at 0.375 0)
			(size 0.45 0.5)
			(layers "F.Cu" "F.Mask" "F.Paste")
			(net "FPGA_MAC_PPS_DIFF_IN0")
		)
	)
	(footprint "Vault:FP-0603-L_1_6_0_2-W_0_8_0-MFG"
		(layer "F.Cu")
		(at 228.3261 112.2162 -90)
		(property "Reference" "C22"
			(at 1.5 0.393345 270)
			(unlocked yes)
			(layer "F.SilkS")
			(effects
				(font
					(size 0.762 0.762)
					(thickness 0.2286)
				)
				(justify left bottom)
			)
		)
		(property "Value" "10uF_16V_0603"
			(at 4.193045 -22.9043 0)
			(unlocked yes)
			(layer "F.SilkS")
			(hide yes)
			(effects
				(font
					(size 0.762 0.762)
					(thickness 0.2286)
				)
				(justify left bottom)
			)
		)
		(sheetname "POWER")
		(sheetfile "POWER.kicad_sch")
		(duplicate_pad_numbers_are_jumpers no)
		(fp_line
			(start 0.9 0.825)
			(end -0.9 0.825)
			(stroke
				(width 0.2)
				(type solid)
			)
			(layer "F.SilkS")
		)
		(fp_line
			(start 0.9 -0.825)
			(end -0.9 -0.825)
			(stroke
				(width 0.2)
				(type solid)
			)
			(layer "F.SilkS")
		)
		(fp_line
			(start -1.15 0.6)
			(end -1.15 -0.6)
			(stroke
				(width 0.2)
				(type solid)
			)
			(layer "F.CrtYd")
		)
		(fp_line
			(start 1.15 0.6)
			(end -1.15 0.6)
			(stroke
				(width 0.2)
				(type solid)
			)
			(layer "F.CrtYd")
		)
		(fp_line
			(start 1.15 0.6)
			(end 1.15 -0.6)
			(stroke
				(width 0.2)
				(type solid)
			)
			(layer "F.CrtYd")
		)
		(fp_line
			(start 1.15 -0.6)
			(end -1.15 -0.6)
			(stroke
				(width 0.2)
				(type solid)
			)
			(layer "F.CrtYd")
		)
		(fp_line
			(start -1.15 0.6)
			(end -1.15 -0.6)
			(stroke
				(width 0.2)
				(type solid)
			)
			(layer "F.Fab")
		)
		(fp_line
			(start 1.15 0.6)
			(end -1.15 0.6)
			(stroke
				(width 0.2)
				(type solid)
			)
			(layer "F.Fab")
		)
		(fp_line
			(start 1.15 0.6)
			(end 1.15 -0.6)
			(stroke
				(width 0.2)
				(type solid)
			)
			(layer "F.Fab")
		)
		(fp_line
			(start 0 0.5)
			(end 0 -0.5)
			(stroke
				(width 0.1)
				(type solid)
			)
			(layer "F.Fab")
		)
		(fp_line
			(start 0.5 0)
			(end -0.5 0)
			(stroke
				(width 0.1)
				(type solid)
			)
			(layer "F.Fab")
		)
		(fp_line
			(start 1.15 -0.6)
			(end -1.15 -0.6)
			(stroke
				(width 0.2)
				(type solid)
			)
			(layer "F.Fab")
		)
		(fp_text user "${REFERENCE}"
			(at -0.00001 0.09602 270)
			(unlocked yes)
			(layer "F.Fab")
			(effects
				(font
					(face "Arial")
					(size 0.63 0.63)
					(thickness 0.1)
				)
				(justify left bottom)
			)
		)
		(pad "1" smd rect
			(at -0.7 0 270)
			(size 0.7 0.7)
			(layers "F.Cu" "F.Mask" "F.Paste")
			(net "+3.3V")
			(solder_mask_margin 0)
			(solder_paste_margin 0)
		)
		(pad "2" smd rect
			(at 0.7 0 270)
			(size 0.7 0.7)
			(layers "F.Cu" "F.Mask" "F.Paste")
			(net "GND")
			(solder_mask_margin 0)
			(solder_paste_margin 0)
		)
	)
	(footprint "Vault:RESC1608X55X30NL15T15"
		(layer "F.Cu")
		(at 84.1261 98.8662 -90)
		(property "Reference" "R14"
			(at 2.7714 -0.026931 90)
			(unlocked yes)
			(layer "F.SilkS")
			(effects
				(font
					(size 0.762 0.762)
					(thickness 0.2286)
				)
			)
		)
		(property "Value" "4.7K"
			(at 2.808471 -4.71014 0)
			(unlocked yes)
			(layer "F.SilkS")
			(hide yes)
			(effects
				(font
					(size 0.762 0.762)
					(thickness 0.2286)
				)
			)
		)
		(sheetname "USER_IO")
		(sheetfile "USER_IO.kicad_sch")
		(duplicate_pad_numbers_are_jumpers no)
		(pad "1" smd rect
			(at -0.75 0)
			(size 0.95 0.95)
			(layers "F.Cu" "F.Mask" "F.Paste")
			(net "ANT1_IO_OUT")
		)
		(pad "2" smd rect
			(at 0.75 0)
			(size 0.95 0.95)
			(layers "F.Cu" "F.Mask" "F.Paste")
			(net "+3.3V")
		)
	)
	(footprint "SamacSys:SOP50P310X90-8N"
		(layer "F.Cu")
		(at 82.1261 95.6162 180)
		(property "Reference" "U8"
			(at 0.228605 2.026931 180)
			(unlocked yes)
			(layer "F.SilkS")
			(effects
				(font
					(size 0.762 0.762)
					(thickness 0.2286)
				)
			)
		)
		(property "Value" "NC7WV125K8X"
			(at 6.207715 2.884671 180)
			(unlocked yes)
			(layer "F.SilkS")
			(hide yes)
			(effects
				(font
					(size 0.762 0.762)
					(thickness 0.2286)
				)
			)
		)
		(sheetname "USER_IO")
		(sheetfile "USER_IO.kicad_sch")
		(duplicate_pad_numbers_are_jumpers no)
		(fp_line
			(start 0.8 1)
			(end -0.8 1)
			(stroke
				(width 0.2)
				(type solid)
			)
			(layer "F.SilkS")
		)
		(fp_line
			(start 0.8 -1)
			(end 0.8 1)
			(stroke
				(width 0.2)
				(type solid)
			)
			(layer "F.SilkS")
		)
		(fp_line
			(start 0.8 -1)
			(end -0.8 -1)
			(stroke
				(width 0.2)
				(type solid)
			)
			(layer "F.SilkS")
		)
		(fp_line
			(start -0.8 -1)
			(end -0.8 1)
			(stroke
				(width 0.2)
				(type solid)
			)
			(layer "F.SilkS")
		)
		(fp_line
			(start -1.15 -1.25)
			(end -2 -1.25)
			(stroke
				(width 0.2)
				(type solid)
			)
			(layer "F.SilkS")
		)
		(pad "1" smd rect
			(at -1.575 -0.75 180)
			(size 0.85 0.3)
			(layers "F.Cu" "F.Mask" "F.Paste")
			(net "ANT1_IO_OUT")
		)
		(pad "2" smd rect
			(at -1.575 -0.25 180)
			(size 0.85 0.3)
			(layers "F.Cu" "F.Mask" "F.Paste")
			(net "ANT1_OUT")
		)
		(pad "3" smd rect
			(at -1.575 0.25 180)
			(size 0.85 0.3)
			(layers "F.Cu" "F.Mask" "F.Paste")
			(net "ANT1_IN")
		)
		(pad "4" smd rect
			(at -1.575 0.75 180)
			(size 0.85 0.3)
			(layers "F.Cu" "F.Mask" "F.Paste")
			(net "GND")
		)
		(pad "5" smd rect
			(at 1.575 0.75 180)
			(size 0.85 0.3)
			(layers "F.Cu" "F.Mask" "F.Paste")
			(net "NetR25_1")
		)
		(pad "6" smd rect
			(at 1.575 0.25 180)
			(size 0.85 0.3)
			(layers "F.Cu" "F.Mask" "F.Paste")
			(net "NetR25_1")
		)
		(pad "7" smd rect
			(at 1.575 -0.25 180)
			(size 0.85 0.3)
			(layers "F.Cu" "F.Mask" "F.Paste")
			(net "ANT1_IO_IN")
		)
		(pad "8" smd rect
			(at 1.575 -0.75 180)
			(size 0.85 0.3)
			(layers "F.Cu" "F.Mask" "F.Paste")
			(net "+3.3V")
		)
	)
	(footprint "Vault:FP-MK212BG-MFG"
		(layer "F.Cu")
		(at 233.2261 61.1162)
		(property "Reference" "C35"
			(at 2.6286 -1.173069 0)
			(unlocked yes)
			(layer "F.SilkS")
			(effects
				(font
					(size 0.762 0.762)
					(thickness 0.2286)
				)
			)
		)
		(property "Value" "10uF"
			(at -3.240281 2.22164 270)
			(unlocked yes)
			(layer "F.SilkS")
			(hide yes)
			(effects
				(font
					(size 0.762 0.762)
					(thickness 0.2286)
				)
			)
		)
		(sheetname "GPS_IMU_SENSORS")
		(sheetfile "GPS_IMU_SENSORS.kicad_sch")
		(duplicate_pad_numbers_are_jumpers no)
		(fp_line
			(start -0.125 -0.725)
			(end 0.125 -0.725)
			(stroke
				(width 0.2)
				(type solid)
			)
			(layer "F.SilkS")
		)
		(fp_line
			(start -0.125 0.725)
			(end 0.125 0.725)
			(stroke
				(width 0.2)
				(type solid)
			)
			(layer "F.SilkS")
		)
		(fp_line
			(start -1.6 -0.825)
			(end 1.6 -0.825)
			(stroke
				(width 0.2)
				(type solid)
			)
			(layer "F.CrtYd")
		)
		(fp_line
			(start -1.6 0.825)
			(end -1.6 -0.825)
			(stroke
				(width 0.2)
				(type solid)
			)
			(layer "F.CrtYd")
		)
		(fp_line
			(start -1.6 0.825)
			(end 1.6 0.825)
			(stroke
				(width 0.2)
				(type solid)
			)
			(layer "F.CrtYd")
		)
		(fp_line
			(start 1.6 0.825)
			(end 1.6 -0.825)
			(stroke
				(width 0.2)
				(type solid)
			)
			(layer "F.CrtYd")
		)
		(fp_line
			(start -1.6 -0.825)
			(end 1.6 -0.825)
			(stroke
				(width 0.2)
				(type solid)
			)
			(layer "F.Fab")
		)
		(fp_line
			(start -1.6 0.825)
			(end -1.6 -0.825)
			(stroke
				(width 0.2)
				(type solid)
			)
			(layer "F.Fab")
		)
		(fp_line
			(start -1.6 0.825)
			(end 1.6 0.825)
			(stroke
				(width 0.2)
				(type solid)
			)
			(layer "F.Fab")
		)
		(fp_line
			(start -0.5 0)
			(end 0.5 0)
			(stroke
				(width 0.1)
				(type solid)
			)
			(layer "F.Fab")
		)
		(fp_line
			(start 0 0.5)
			(end 0 -0.5)
			(stroke
				(width 0.1)
				(type solid)
			)
			(layer "F.Fab")
		)
		(fp_line
			(start 1.6 0.825)
			(end 1.6 -0.825)
			(stroke
				(width 0.2)
				(type solid)
			)
			(layer "F.Fab")
		)
		(fp_text user "${REFERENCE}"
			(at -0.00001 0.09602 360)
			(unlocked yes)
			(layer "F.Fab")
			(effects
				(font
					(face "Arial")
					(size 0.63 0.63)
					(thickness 0.1)
				)
				(justify left bottom)
			)
		)
		(pad "1" smd rect
			(at -1 0)
			(size 1 1.25)
			(layers "F.Cu" "F.Mask" "F.Paste")
			(net "+5.0V")
			(solder_mask_margin 0)
			(solder_paste_margin 0)
		)
		(pad "2" smd rect
			(at 1 0)
			(size 1 1.25)
			(layers "F.Cu" "F.Mask" "F.Paste")
			(net "GND")
			(solder_mask_margin 0)
			(solder_paste_margin 0)
		)
	)
	(footprint "Vault:TECO-1909763-1_V"
		(layer "F.Cu")
		(at 74.3761 95.1162 -90)
		(property "Reference" "J1"
			(at -2.723079 1.271395 0)
			(unlocked yes)
			(layer "F.SilkS")
			(effects
				(font
					(size 0.762 0.762)
					(thickness 0.2286)
				)
			)
		)
		(property "Value" "1909763-1"
			(at 4.582685 3.722871 270)
			(unlocked yes)
			(layer "F.SilkS")
			(hide yes)
			(effects
				(font
					(size 0.762 0.762)
					(thickness 0.2286)
				)
			)
		)
		(sheetname "USER_IO")
		(sheetfile "USER_IO.kicad_sch")
		(duplicate_pad_numbers_are_jumpers no)
		(fp_line
			(start 0.55 -1.3)
			(end -0.55 -1.3)
			(stroke
				(width 0.2)
				(type solid)
			)
			(layer "F.SilkS")
		)
		(fp_circle
			(center -1.778 1.65)
			(end -1.903 1.65)
			(stroke
				(width 0.25)
				(type solid)
			)
			(fill no)
			(layer "F.SilkS")
		)
		(pad "1" smd rect
			(at -1.475 0 270)
			(size 1.05 2.2)
			(layers "F.Cu" "F.Mask" "F.Paste")
			(net "GND")
		)
		(pad "2" smd rect
			(at 0 1.525 270)
			(size 1 1.05)
			(layers "F.Cu" "F.Mask" "F.Paste")
			(net "NetAN1_1")
		)
		(pad "3" smd rect
			(at 1.475 0 270)
			(size 1.05 2.2)
			(layers "F.Cu" "F.Mask" "F.Paste")
			(net "GND")
		)
	)
	(footprint "MIC24052YJL-TR:QFN28_5X6_MCH"
		(layer "F.Cu")
		(at 211.66439 109.33006 90)
		(property "Reference" "U1"
			(at 3.120515 1.76171 0)
			(unlocked yes)
			(layer "F.SilkS")
			(effects
				(font
					(size 0.762 0.762)
					(thickness 0.2286)
				)
				(justify left bottom)
			)
		)
		(property "Value" "MIC24052YJL-TR"
			(at -10.550285 4.81527 0)
			(unlocked yes)
			(layer "F.SilkS")
			(hide yes)
			(effects
				(font
					(size 0.762 0.762)
					(thickness 0.2286)
				)
				(justify left bottom)
			)
		)
		(sheetname "POWER")
		(sheetfile "POWER.kicad_sch")
		(duplicate_pad_numbers_are_jumpers no)
		(fp_line
			(start 2.9083 -3.4036)
			(end 2.9083 -2.56017)
			(stroke
				(width 0.1524)
				(type solid)
			)
			(layer "F.SilkS")
		)
		(fp_line
			(start 1.9205 -3.4036)
			(end 2.9083 -3.4036)
			(stroke
				(width 0.1524)
				(type solid)
			)
			(layer "F.SilkS")
		)
		(fp_line
			(start -2.9083 -3.4036)
			(end -1.92049 -3.4036)
			(stroke
				(width 0.1524)
				(type solid)
			)
			(layer "F.SilkS")
		)
		(fp_line
			(start -2.9083 -3.4036)
			(end -2.9083 -2.56017)
			(stroke
				(width 0.1524)
				(type solid)
			)
			(layer "F.SilkS")
		)
		(fp_line
			(start 2.9083 2.56018)
			(end 2.9083 3.4036)
			(stroke
				(width 0.1524)
				(type solid)
			)
			(layer "F.SilkS")
		)
		(fp_line
			(start -2.9083 2.56018)
			(end -2.9083 3.4036)
			(stroke
				(width 0.1524)
				(type solid)
			)
			(layer "F.SilkS")
		)
		(fp_line
			(start 1.9205 3.4036)
			(end 2.9083 3.4036)
			(stroke
				(width 0.1524)
				(type solid)
			)
			(layer "F.SilkS")
		)
		(fp_line
			(start -2.9083 3.4036)
			(end -1.92049 3.4036)
			(stroke
				(width 0.1524)
				(type solid)
			)
			(layer "F.SilkS")
		)
		(fp_text user "*"
			(at -3.5557 -2.190415 90)
			(unlocked yes)
			(layer "F.SilkS")
			(effects
				(font
					(size 1.27 1.27)
					(thickness 0.0762)
				)
				(justify left bottom)
			)
		)
		(pad "1" smd rect
			(at -2.4 -2.27499)
			(size 0.3 0.4)
			(layers "F.Cu" "F.Mask" "F.Paste")
			(net "P5V_PVDD")
			(solder_mask_margin 0)
			(solder_paste_margin -0.15)
		)
		(pad "2" smd rect
			(at -2.4 -1.625)
			(size 0.3 0.4)
			(layers "F.Cu" "F.Mask" "F.Paste")
			(net "GND")
			(solder_mask_margin 0)
			(solder_paste_margin -0.15)
		)
		(pad "3" smd rect
			(at -2.4 -0.97499)
			(size 0.3 0.4)
			(layers "F.Cu" "F.Mask" "F.Paste")
			(solder_mask_margin 0)
			(solder_paste_margin -0.15)
		)
		(pad "4" smd rect
			(at -2.4 -0.325)
			(size 0.3 0.4)
			(layers "F.Cu" "F.Mask" "F.Paste")
			(net "NetL1_1")
			(solder_mask_margin 0)
			(solder_paste_margin -0.15)
		)
		(pad "5" smd rect
			(at -2.4 0.32501)
			(size 0.3 0.4)
			(layers "F.Cu" "F.Mask" "F.Paste")
			(net "GND")
			(solder_mask_margin 0)
			(solder_paste_margin -0.15)
		)
		(pad "6" smd rect
			(at -2.4 0.975)
			(size 0.3 0.4)
			(layers "F.Cu" "F.Mask" "F.Paste")
			(net "GND")
			(solder_mask_margin 0)
			(solder_paste_margin -0.15)
		)
		(pad "7" smd rect
			(at -2.4 1.62501)
			(size 0.3 0.4)
			(layers "F.Cu" "F.Mask" "F.Paste")
			(net "GND")
			(solder_mask_margin 0)
			(solder_paste_margin -0.15)
		)
		(pad "8" smd rect
			(at -2.4 2.275)
			(size 0.3 0.4)
			(layers "F.Cu" "F.Mask" "F.Paste")
			(net "GND")
			(solder_mask_margin 0)
			(solder_paste_margin -0.15)
		)
		(pad "9" smd rect
			(at -1.625 2.9 270)
			(size 0.3 0.4)
			(layers "F.Cu" "F.Mask" "F.Paste")
			(net "NetL1_1")
			(solder_mask_margin 0)
			(solder_paste_margin -0.15)
		)
		(pad "10" smd rect
			(at -0.975 2.9 270)
			(size 0.3 0.4)
			(layers "F.Cu" "F.Mask" "F.Paste")
			(net "NetL1_1")
			(solder_mask_margin 0)
			(solder_paste_margin -0.15)
		)
		(pad "11" smd rect
			(at -0.325 2.9 270)
			(size 0.3 0.4)
			(layers "F.Cu" "F.Mask" "F.Paste")
			(net "NetL1_1")
			(solder_mask_margin 0)
			(solder_paste_margin -0.15)
		)
		(pad "12" smd rect
			(at 0.325 2.9 270)
			(size 0.3 0.4)
			(layers "F.Cu" "F.Mask" "F.Paste")
			(net "NetL1_1")
			(solder_mask_margin 0)
			(solder_paste_margin -0.15)
		)
		(pad "13" smd rect
			(at 0.975 2.9 270)
			(size 0.3 0.4)
			(layers "F.Cu" "F.Mask" "F.Paste")
			(net "+12V")
			(solder_mask_margin 0)
			(solder_paste_margin -0.15)
		)
		(pad "14" smd rect
			(at 1.625 2.9 270)
			(size 0.3 0.4)
			(layers "F.Cu" "F.Mask" "F.Paste")
			(net "+12V")
			(solder_mask_margin 0)
			(solder_paste_margin -0.15)
		)
		(pad "15" smd rect
			(at 2.4 2.275)
			(size 0.3 0.4)
			(layers "F.Cu" "F.Mask" "F.Paste")
			(net "+12V")
			(solder_mask_margin 0)
			(solder_paste_margin -0.15)
		)
		(pad "16" smd rect
			(at 2.4 1.62501)
			(size 0.3 0.4)
			(layers "F.Cu" "F.Mask" "F.Paste")
			(net "+12V")
			(solder_mask_margin 0)
			(solder_paste_margin -0.15)
		)
		(pad "17" smd rect
			(at 2.4 0.975)
			(size 0.3 0.4)
			(layers "F.Cu" "F.Mask" "F.Paste")
			(net "+12V")
			(solder_mask_margin 0)
			(solder_paste_margin -0.15)
		)
		(pad "18" smd rect
			(at 2.4 0.32501)
			(size 0.3 0.4)
			(layers "F.Cu" "F.Mask" "F.Paste")
			(net "+12V")
			(solder_mask_margin 0)
			(solder_paste_margin -0.15)
		)
		(pad "19" smd rect
			(at 2.4 -0.325)
			(size 0.3 0.4)
			(layers "F.Cu" "F.Mask" "F.Paste")
			(net "+12V")
			(solder_mask_margin 0)
			(solder_paste_margin -0.15)
		)
		(pad "20" smd rect
			(at 2.4 -0.97499)
			(size 0.3 0.4)
			(layers "F.Cu" "F.Mask" "F.Paste")
			(net "NetR4_1")
			(solder_mask_margin 0)
			(solder_paste_margin -0.15)
		)
		(pad "21" smd rect
			(at 2.4 -1.625)
			(size 0.3 0.4)
			(layers "F.Cu" "F.Mask" "F.Paste")
			(net "GND")
			(solder_mask_margin 0)
			(solder_paste_margin -0.15)
		)
		(pad "22" smd rect
			(at 2.4 -2.27499)
			(size 0.3 0.4)
			(layers "F.Cu" "F.Mask" "F.Paste")
			(net "NetC3_2")
			(solder_mask_margin 0)
			(solder_paste_margin -0.15)
		)
		(pad "23" smd rect
			(at 1.625 -2.89999 270)
			(size 0.3 0.4)
			(layers "F.Cu" "F.Mask" "F.Paste")
			(net "GND")
			(solder_mask_margin 0)
			(solder_paste_margin -0.15)
		)
		(pad "24" smd rect
			(at 0.975 -2.89999 270)
			(size 0.3 0.4)
			(layers "F.Cu" "F.Mask" "F.Paste")
			(net "P5V_FB")
			(solder_mask_margin 0)
			(solder_paste_margin -0.15)
		)
		(pad "25" smd rect
			(at 0.325 -2.89999 270)
			(size 0.3 0.4)
			(layers "F.Cu" "F.Mask" "F.Paste")
			(net "NetR3_2")
			(solder_mask_margin 0)
			(solder_paste_margin -0.15)
		)
		(pad "26" smd rect
			(at -0.325 -2.89999 270)
			(size 0.3 0.4)
			(layers "F.Cu" "F.Mask" "F.Paste")
			(net "NetR2_2")
			(solder_mask_margin 0)
			(solder_paste_margin -0.15)
		)
		(pad "27" smd rect
			(at -0.975 -2.89999 270)
			(size 0.3 0.4)
			(layers "F.Cu" "F.Mask" "F.Paste")
			(net "NetC6_1")
			(solder_mask_margin 0)
			(solder_paste_margin -0.15)
		)
		(pad "28" smd rect
			(at -1.625 -2.89999 270)
			(size 0.3 0.4)
			(layers "F.Cu" "F.Mask" "F.Paste")
			(net "P5V_VDD")
			(solder_mask_margin 0)
			(solder_paste_margin -0.15)
		)
		(pad "29" smd rect
			(at 0 -1.54999 90)
			(size 3.69999 1.6)
			(layers "F.Cu" "F.Mask" "F.Paste")
			(net "GND")
			(solder_mask_margin 0)
			(solder_paste_margin -0.8)
		)
		(pad "30" smd rect
			(at -0.5 1.015 90)
			(size 2.2 2.82999)
			(layers "F.Cu" "F.Mask" "F.Paste")
			(net "NetL1_1")
			(solder_mask_margin 0)
			(solder_paste_margin 0)
		)
		(pad "31" smd rect
			(at 1.4 1.015 90)
			(size 0.9 2.82999)
			(layers "F.Cu" "F.Mask" "F.Paste")
		)
	)
	(footprint "Vault:FP-C1005-050-0_05-IPC_A"
		(layer "F.Cu")
		(at 205.35952 129.4162 180)
		(property "Reference" "C70"
			(at -0.19518 -2.626931 0)
			(unlocked yes)
			(layer "F.SilkS")
			(effects
				(font
					(size 0.762 0.762)
					(thickness 0.2286)
				)
			)
		)
		(property "Value" "2.2uF_16V_0402"
			(at -2.744951 9.813815 90)
			(unlocked yes)
			(layer "F.SilkS")
			(hide yes)
			(effects
				(font
					(size 0.762 0.762)
					(thickness 0.2286)
				)
			)
		)
		(sheetname "POWER")
		(sheetfile "POWER.kicad_sch")
		(duplicate_pad_numbers_are_jumpers no)
		(fp_line
			(start 0.83623 0.73624)
			(end -0.83624 0.73624)
			(stroke
				(width 0.2)
				(type solid)
			)
			(layer "F.SilkS")
		)
		(fp_line
			(start 0.83623 -0.73624)
			(end -0.83624 -0.73624)
			(stroke
				(width 0.2)
				(type solid)
			)
			(layer "F.SilkS")
		)
		(fp_line
			(start 1.03623 0.53624)
			(end -1.03624 0.53624)
			(stroke
				(width 0.2)
				(type solid)
			)
			(layer "F.CrtYd")
		)
		(fp_line
			(start 1.03623 -0.53624)
			(end 1.03623 0.53624)
			(stroke
				(width 0.2)
				(type solid)
			)
			(layer "F.CrtYd")
		)
		(fp_line
			(start 1.03623 -0.53624)
			(end -1.03624 -0.53624)
			(stroke
				(width 0.2)
				(type solid)
			)
			(layer "F.CrtYd")
		)
		(fp_line
			(start -1.03624 -0.53624)
			(end -1.03624 0.53624)
			(stroke
				(width 0.2)
				(type solid)
			)
			(layer "F.CrtYd")
		)
		(fp_line
			(start 1.03623 0.53624)
			(end -1.03624 0.53624)
			(stroke
				(width 0.2)
				(type solid)
			)
			(layer "F.Fab")
		)
		(fp_line
			(start 1.03623 -0.53624)
			(end 1.03623 0.53624)
			(stroke
				(width 0.2)
				(type solid)
			)
			(layer "F.Fab")
		)
		(fp_line
			(start 1.03623 -0.53624)
			(end -1.03624 -0.53624)
			(stroke
				(width 0.2)
				(type solid)
			)
			(layer "F.Fab")
		)
		(fp_line
			(start 0.5 0)
			(end -0.5 0)
			(stroke
				(width 0.1)
				(type solid)
			)
			(layer "F.Fab")
		)
		(fp_line
			(start 0 -0.5)
			(end 0 0.5)
			(stroke
				(width 0.1)
				(type solid)
			)
			(layer "F.Fab")
		)
		(fp_line
			(start -1.03624 -0.53624)
			(end -1.03624 0.53624)
			(stroke
				(width 0.2)
				(type solid)
			)
			(layer "F.Fab")
		)
		(fp_text user "${REFERENCE}"
			(at -0.00001 0.09602 180)
			(unlocked yes)
			(layer "F.Fab")
			(effects
				(font
					(face "Arial")
					(size 0.63 0.63)
					(thickness 0.1)
				)
				(justify left bottom)
			)
		)
		(pad "1" smd rect
			(at -0.46658 0 180)
			(size 0.73933 0.67248)
			(layers "F.Cu" "F.Mask" "F.Paste")
			(net "P3V3_PVDD")
			(solder_mask_margin 0)
			(solder_paste_margin 0)
		)
		(pad "2" smd rect
			(at 0.46657 0 180)
			(size 0.73933 0.67248)
			(layers "F.Cu" "F.Mask" "F.Paste")
			(net "GND")
			(solder_mask_margin 0)
			(solder_paste_margin 0)
		)
	)
	(footprint "Vault:RESC1608X55X30NL15T15"
		(layer "F.Cu")
		(at 69.8761 55.6162 90)
		(property "Reference" "R35"
			(at -5.7714 0.026921 90)
			(unlocked yes)
			(layer "F.SilkS")
			(effects
				(font
					(size 0.762 0.762)
					(thickness 0.2286)
				)
			)
		)
		(property "Value" "200 OHM"
			(at -2.935471 4.78626 0)
			(unlocked yes)
			(layer "F.SilkS")
			(hide yes)
			(effects
				(font
					(size 0.762 0.762)
					(thickness 0.2286)
				)
			)
		)
		(sheetname "USER_IO_STATUS")
		(sheetfile "USER_IO_STATUS.kicad_sch")
		(duplicate_pad_numbers_are_jumpers no)
		(pad "1" smd rect
			(at -0.675 0 180)
			(size 0.95 0.8)
			(layers "F.Cu" "F.Mask" "F.Paste")
			(net "LED1")
		)
		(pad "2" smd rect
			(at 0.675 0 180)
			(size 0.95 0.8)
			(layers "F.Cu" "F.Mask" "F.Paste")
			(net "NetD3_1")
		)
	)
	(footprint "Vault:RESC1005X40X25NL05T05"
		(layer "F.Cu")
		(at 217.1261 80.8162)
		(property "Reference" "R101"
			(at 0.0286 -0.773069 0)
			(unlocked yes)
			(layer "F.SilkS")
			(effects
				(font
					(size 0.762 0.762)
					(thickness 0.2286)
				)
			)
		)
		(property "Value" "DNI_27_1%_0402"
			(at -2.732271 10.296375 270)
			(unlocked yes)
			(layer "F.SilkS")
			(hide yes)
			(effects
				(font
					(size 0.762 0.762)
					(thickness 0.2286)
				)
			)
		)
		(sheetname "USBUart_DipSelects")
		(sheetfile "USBUart_DipSelects.kicad_sch")
		(duplicate_pad_numbers_are_jumpers no)
		(pad "1" smd rect
			(at -0.45 0 90)
			(size 0.55 0.55)
			(layers "F.Cu" "F.Mask" "F.Paste")
			(net "FTDI_TX")
		)
		(pad "2" smd rect
			(at 0.45 0 90)
			(size 0.55 0.55)
			(layers "F.Cu" "F.Mask" "F.Paste")
			(net "UART1_RXD")
		)
	)
	(footprint "Passives:SOT65P210X110-3N"
		(layer "F.Cu")
		(at 229.6761 137.6412 -90)
		(property "Reference" "D7"
			(at -1.931655 0.45 0)
			(unlocked yes)
			(layer "F.SilkS")
			(effects
				(font
					(size 0.762 0.762)
					(thickness 0.2286)
				)
				(justify left bottom)
			)
		)
		(property "Value" "BAT54SW"
			(at 0.551455 -1.0501 0)
			(unlocked yes)
			(layer "F.SilkS")
			(hide yes)
			(effects
				(font
					(size 0.762 0.762)
					(thickness 0.2286)
				)
				(justify left bottom)
			)
		)
		(sheetname "PCIe_JTAG")
		(sheetfile "PCIe_JTAG.kicad_sch")
		(duplicate_pad_numbers_are_jumpers no)
		(fp_line
			(start 0.675 1.1)
			(end -0.32499 1.1)
			(stroke
				(width 0.2)
				(type solid)
			)
			(layer "F.SilkS")
		)
		(fp_line
			(start 0.675 1.1)
			(end 0.675 0.65)
			(stroke
				(width 0.2)
				(type solid)
			)
			(layer "F.SilkS")
		)
		(fp_line
			(start 0.675 -0.65)
			(end 0.675 -1.1)
			(stroke
				(width 0.2)
				(type solid)
			)
			(layer "F.SilkS")
		)
		(fp_line
			(start 0.675 -1.1)
			(end -0.32499 -1.1)
			(stroke
				(width 0.2)
				(type solid)
			)
			(layer "F.SilkS")
		)
		(fp_circle
			(center -1.125 -1.45)
			(end -1.25 -1.45)
			(stroke
				(width 0.25)
				(type solid)
			)
			(fill no)
			(layer "F.SilkS")
		)
		(pad "1" smd rect
			(at -1.125 -0.65)
			(size 0.5 0.9)
			(layers "F.Cu" "F.Mask" "F.Paste")
			(net "GND")
		)
		(pad "2" smd rect
			(at -1.125 0.65)
			(size 0.5 0.9)
			(layers "F.Cu" "F.Mask" "F.Paste")
			(net "+3.3V")
		)
		(pad "3" smd rect
			(at 1.125 0)
			(size 0.5 0.9)
			(layers "F.Cu" "F.Mask" "F.Paste")
			(net "FPGA_TMS")
		)
	)
	(footprint "Vault:RESC3216X89X64NL25T25"
		(layer "F.Cu")
		(at 225.5261 123.5162)
		(property "Reference" "R72"
			(at 3.1286 1.426931 0)
			(unlocked yes)
			(layer "F.SilkS")
			(effects
				(font
					(size 0.762 0.762)
					(thickness 0.2286)
				)
			)
		)
		(property "Value" "2mOhm_1%_1206"
			(at 7.62962 3.037071 0)
			(unlocked yes)
			(layer "F.SilkS")
			(hide yes)
			(effects
				(font
					(size 0.762 0.762)
					(thickness 0.2286)
				)
			)
		)
		(sheetname "POWER")
		(sheetfile "POWER.kicad_sch")
		(duplicate_pad_numbers_are_jumpers no)
		(fp_line
			(start -0.2 -0.825)
			(end 0.2 -0.825)
			(stroke
				(width 0.2)
				(type solid)
			)
			(layer "F.SilkS")
		)
		(fp_line
			(start -0.2 0.825)
			(end 0.2 0.825)
			(stroke
				(width 0.2)
				(type solid)
			)
			(layer "F.SilkS")
		)
		(pad "1" smd rect
			(at -1.325 0 90)
			(size 1.85 1.5)
			(layers "F.Cu" "F.Mask" "F.Paste")
			(net "P3V3_SENSE")
		)
		(pad "2" smd rect
			(at 1.325 0 90)
			(size 1.85 1.5)
			(layers "F.Cu" "F.Mask" "F.Paste")
			(net "+3.3V")
		)
	)
	(footprint "Vault:RESC1005X40X25LL05T05"
		(layer "F.Cu")
		(at 183.0261 84.8162 180)
		(property "Reference" "R53"
			(at 0.0714 1.073069 0)
			(unlocked yes)
			(layer "F.SilkS")
			(effects
				(font
					(size 0.762 0.762)
					(thickness 0.2286)
				)
			)
		)
		(property "Value" "4.7K_0402"
			(at -3.024391 2.374045 90)
			(unlocked yes)
			(layer "F.SilkS")
			(hide yes)
			(effects
				(font
					(size 0.762 0.762)
					(thickness 0.2286)
				)
			)
		)
		(sheetname "GPS_IMU_SENSORS")
		(sheetfile "GPS_IMU_SENSORS.kicad_sch")
		(duplicate_pad_numbers_are_jumpers no)
		(pad "1" smd rect
			(at -0.4 0 270)
			(size 0.45 0.45)
			(layers "F.Cu" "F.Mask" "F.Paste")
			(net "NetR53_1")
		)
		(pad "2" smd rect
			(at 0.4 0 270)
			(size 0.45 0.45)
			(layers "F.Cu" "F.Mask" "F.Paste")
			(net "+3.3V")
		)
	)
	(footprint "Vault:RESC1005X40X25LL05T05"
		(layer "F.Cu")
		(at 188.0261 82.8162 180)
		(property "Reference" "R55"
			(at 0.3714 1.673079 0)
			(unlocked yes)
			(layer "F.SilkS")
			(effects
				(font
					(size 0.762 0.762)
					(thickness 0.2286)
				)
			)
		)
		(property "Value" "4.7K_0402"
			(at -3.024391 2.374045 90)
			(unlocked yes)
			(layer "F.SilkS")
			(hide yes)
			(effects
				(font
					(size 0.762 0.762)
					(thickness 0.2286)
				)
			)
		)
		(sheetname "GPS_IMU_SENSORS")
		(sheetfile "GPS_IMU_SENSORS.kicad_sch")
		(duplicate_pad_numbers_are_jumpers no)
		(pad "1" smd rect
			(at -0.4 0 270)
			(size 0.45 0.45)
			(layers "F.Cu" "F.Mask" "F.Paste")
			(net "BNO_BLIND")
		)
		(pad "2" smd rect
			(at 0.4 0 270)
			(size 0.45 0.45)
			(layers "F.Cu" "F.Mask" "F.Paste")
			(net "NetR55_2")
		)
	)
	(footprint "Vault:RESC1005X40X25LL05T05"
		(layer "F.Cu")
		(at 236.4261 131.8162)
		(property "Reference" "R79"
			(at 2.4286 -0.173079 0)
			(unlocked yes)
			(layer "F.SilkS")
			(effects
				(font
					(size 0.762 0.762)
					(thickness 0.2286)
				)
			)
		)
		(property "Value" "0_1%_0402"
			(at -2.579881 6.66536 270)
			(unlocked yes)
			(layer "F.SilkS")
			(hide yes)
			(effects
				(font
					(size 0.762 0.762)
					(thickness 0.2286)
				)
			)
		)
		(sheetname "POWER")
		(sheetfile "POWER.kicad_sch")
		(duplicate_pad_numbers_are_jumpers no)
		(pad "1" smd rect
			(at -0.4 0 90)
			(size 0.45 0.45)
			(layers "F.Cu" "F.Mask" "F.Paste")
			(net "NetR79_1")
		)
		(pad "2" smd rect
			(at 0.4 0 90)
			(size 0.45 0.45)
			(layers "F.Cu" "F.Mask" "F.Paste")
			(net "GND")
		)
	)
	(footprint "Vault:FP-MK212BG-MFG"
		(layer "F.Cu")
		(at 216.9261 68.8162 180)
		(property "Reference" "C55"
			(at 0.2286 -1.873079 180)
			(unlocked yes)
			(layer "F.SilkS")
			(effects
				(font
					(size 0.762 0.762)
					(thickness 0.2286)
				)
			)
		)
		(property "Value" "10uF"
			(at -3.240271 2.22164 90)
			(unlocked yes)
			(layer "F.SilkS")
			(hide yes)
			(effects
				(font
					(size 0.762 0.762)
					(thickness 0.2286)
				)
			)
		)
		(sheetname "GPS_IMU_SENSORS")
		(sheetfile "GPS_IMU_SENSORS.kicad_sch")
		(duplicate_pad_numbers_are_jumpers no)
		(fp_line
			(start 0.125 0.725)
			(end -0.125 0.725)
			(stroke
				(width 0.2)
				(type solid)
			)
			(layer "F.SilkS")
		)
		(fp_line
			(start 0.125 -0.725)
			(end -0.125 -0.725)
			(stroke
				(width 0.2)
				(type solid)
			)
			(layer "F.SilkS")
		)
		(fp_line
			(start 1.6 0.825)
			(end -1.6 0.825)
			(stroke
				(width 0.2)
				(type solid)
			)
			(layer "F.CrtYd")
		)
		(fp_line
			(start 1.6 -0.825)
			(end 1.6 0.825)
			(stroke
				(width 0.2)
				(type solid)
			)
			(layer "F.CrtYd")
		)
		(fp_line
			(start 1.6 -0.825)
			(end -1.6 -0.825)
			(stroke
				(width 0.2)
				(type solid)
			)
			(layer "F.CrtYd")
		)
		(fp_line
			(start -1.6 -0.825)
			(end -1.6 0.825)
			(stroke
				(width 0.2)
				(type solid)
			)
			(layer "F.CrtYd")
		)
		(fp_line
			(start 1.6 0.825)
			(end -1.6 0.825)
			(stroke
				(width 0.2)
				(type solid)
			)
			(layer "F.Fab")
		)
		(fp_line
			(start 1.6 -0.825)
			(end 1.6 0.825)
			(stroke
				(width 0.2)
				(type solid)
			)
			(layer "F.Fab")
		)
		(fp_line
			(start 1.6 -0.825)
			(end -1.6 -0.825)
			(stroke
				(width 0.2)
				(type solid)
			)
			(layer "F.Fab")
		)
		(fp_line
			(start 0.5 0)
			(end -0.5 0)
			(stroke
				(width 0.1)
				(type solid)
			)
			(layer "F.Fab")
		)
		(fp_line
			(start 0 -0.5)
			(end 0 0.5)
			(stroke
				(width 0.1)
				(type solid)
			)
			(layer "F.Fab")
		)
		(fp_line
			(start -1.6 -0.825)
			(end -1.6 0.825)
			(stroke
				(width 0.2)
				(type solid)
			)
			(layer "F.Fab")
		)
		(fp_text user "${REFERENCE}"
			(at -0.00001 0.09602 180)
			(unlocked yes)
			(layer "F.Fab")
			(effects
				(font
					(face "Arial")
					(size 0.63 0.63)
					(thickness 0.1)
				)
				(justify left bottom)
			)
		)
		(pad "1" smd rect
			(at -1 0 180)
			(size 1 1.25)
			(layers "F.Cu" "F.Mask" "F.Paste")
			(net "+3.3V")
			(solder_mask_margin 0)
			(solder_paste_margin 0)
		)
		(pad "2" smd rect
			(at 1 0 180)
			(size 1 1.25)
			(layers "F.Cu" "F.Mask" "F.Paste")
			(net "GND")
			(solder_mask_margin 0)
			(solder_paste_margin 0)
		)
	)
	(footprint "SamacSys:SOP50P310X90-8N"
		(layer "F.Cu")
		(at 82.1261 136.1162 180)
		(property "Reference" "U16"
			(at 0.2286 2.026931 180)
			(unlocked yes)
			(layer "F.SilkS")
			(effects
				(font
					(size 0.762 0.762)
					(thickness 0.2286)
				)
			)
		)
		(property "Value" "NC7WV125K8X"
			(at 6.207715 2.884671 180)
			(unlocked yes)
			(layer "F.SilkS")
			(hide yes)
			(effects
				(font
					(size 0.762 0.762)
					(thickness 0.2286)
				)
			)
		)
		(sheetname "USER_IO")
		(sheetfile "USER_IO.kicad_sch")
		(duplicate_pad_numbers_are_jumpers no)
		(fp_line
			(start 0.8 1)
			(end -0.8 1)
			(stroke
				(width 0.2)
				(type solid)
			)
			(layer "F.SilkS")
		)
		(fp_line
			(start 0.8 -1)
			(end 0.8 1)
			(stroke
				(width 0.2)
				(type solid)
			)
			(layer "F.SilkS")
		)
		(fp_line
			(start 0.8 -1)
			(end -0.8 -1)
			(stroke
				(width 0.2)
				(type solid)
			)
			(layer "F.SilkS")
		)
		(fp_line
			(start -0.8 -1)
			(end -0.8 1)
			(stroke
				(width 0.2)
				(type solid)
			)
			(layer "F.SilkS")
		)
		(fp_line
			(start -1.15 -1.25)
			(end -2 -1.25)
			(stroke
				(width 0.2)
				(type solid)
			)
			(layer "F.SilkS")
		)
		(pad "1" smd rect
			(at -1.575 -0.75 180)
			(size 0.85 0.3)
			(layers "F.Cu" "F.Mask" "F.Paste")
			(net "ANT4_IO_OUT")
		)
		(pad "2" smd rect
			(at -1.575 -0.25 180)
			(size 0.85 0.3)
			(layers "F.Cu" "F.Mask" "F.Paste")
			(net "ANT4_OUT")
		)
		(pad "3" smd rect
			(at -1.575 0.25 180)
			(size 0.85 0.3)
			(layers "F.Cu" "F.Mask" "F.Paste")
			(net "ANT4_IN")
		)
		(pad "4" smd rect
			(at -1.575 0.75 180)
			(size 0.85 0.3)
			(layers "F.Cu" "F.Mask" "F.Paste")
			(net "GND")
		)
		(pad "5" smd rect
			(at 1.575 0.75 180)
			(size 0.85 0.3)
			(layers "F.Cu" "F.Mask" "F.Paste")
			(net "NetR34_1")
		)
		(pad "6" smd rect
			(at 1.575 0.25 180)
			(size 0.85 0.3)
			(layers "F.Cu" "F.Mask" "F.Paste")
			(net "NetR34_1")
		)
		(pad "7" smd rect
			(at 1.575 -0.25 180)
			(size 0.85 0.3)
			(layers "F.Cu" "F.Mask" "F.Paste")
			(net "ANT4_IO_IN")
		)
		(pad "8" smd rect
			(at 1.575 -0.75 180)
			(size 0.85 0.3)
			(layers "F.Cu" "F.Mask" "F.Paste")
			(net "+3.3V")
		)
	)
	(footprint "SamacSys:155124M173200"
		(layer "F.Cu")
		(at 58.4511 71.6662 90)
		(property "Reference" "D13"
			(at -4.7 -0.231655 90)
			(unlocked yes)
			(layer "F.SilkS")
			(effects
				(font
					(size 0.762 0.762)
					(thickness 0.2286)
				)
				(justify left bottom)
			)
		)
		(property "Value" "155124M173200"
			(at -4.043045 -0.5715 0)
			(unlocked yes)
			(layer "F.SilkS")
			(hide yes)
			(effects
				(font
					(size 0.762 0.762)
					(thickness 0.2286)
				)
				(justify left bottom)
			)
		)
		(sheetname "USER_IO_STATUS")
		(sheetfile "USER_IO_STATUS.kicad_sch")
		(duplicate_pad_numbers_are_jumpers no)
		(fp_line
			(start -0.8 0.5)
			(end 0.8 0.5)
			(stroke
				(width 0.1)
				(type solid)
			)
			(layer "F.SilkS")
		)
		(fp_arc
			(start -2 -0.1)
			(mid -1.95 -0.05)
			(end -2 0)
			(stroke
				(width 0.1)
				(type solid)
			)
			(layer "F.SilkS")
		)
		(fp_arc
			(start -2 0)
			(mid -2.05 -0.05)
			(end -2 -0.1)
			(stroke
				(width 0.1)
				(type solid)
			)
			(layer "F.SilkS")
		)
		(pad "1" smd rect
			(at -1.4 0 180)
			(size 0.9 0.6)
			(layers "F.Cu" "F.Mask" "F.Paste")
			(net "+3.3V")
		)
		(pad "2" smd rect
			(at -0.45 -0.325 90)
			(size 0.6 0.55)
			(layers "F.Cu" "F.Mask" "F.Paste")
			(net "NetD13_2")
		)
		(pad "3" smd rect
			(at 0.45 -0.325 90)
			(size 0.6 0.55)
			(layers "F.Cu" "F.Mask" "F.Paste")
			(net "NetD13_3")
		)
		(pad "4" smd rect
			(at 1.4 0 180)
			(size 0.9 0.6)
			(layers "F.Cu" "F.Mask" "F.Paste")
			(net "NetD13_4")
		)
	)
	(footprint "Vault:RESC1005X40X25NL05T05"
		(layer "F.Cu")
		(at 240.0261 66.9162 -90)
		(property "Reference" "R13"
			(at -0.0233 0.775031 270)
			(unlocked yes)
			(layer "F.SilkS")
			(effects
				(font
					(size 0.762 0.762)
					(thickness 0.2286)
				)
			)
		)
		(property "Value" "27_1%_0402"
			(at -2.884671 3.18659 180)
			(unlocked yes)
			(layer "F.SilkS")
			(hide yes)
			(effects
				(font
					(size 0.762 0.762)
					(thickness 0.2286)
				)
			)
		)
		(sheetname "USBUart_DipSelects")
		(sheetfile "USBUart_DipSelects.kicad_sch")
		(duplicate_pad_numbers_are_jumpers no)
		(pad "1" smd rect
			(at -0.45 0)
			(size 0.55 0.55)
			(layers "F.Cu" "F.Mask" "F.Paste")
			(net "NetR13_1")
		)
		(pad "2" smd rect
			(at 0.45 0)
			(size 0.55 0.55)
			(layers "F.Cu" "F.Mask" "F.Paste")
			(net "FTDI_TX")
		)
	)
	(footprint "Vault:RESC1005X40X25LL05T10"
		(layer "F.Cu")
		(at 174.4261 83.3162 180)
		(property "Reference" "R89"
			(at -0.3286 2.273079 0)
			(unlocked yes)
			(layer "F.SilkS")
			(effects
				(font
					(size 0.762 0.762)
					(thickness 0.2286)
				)
			)
		)
		(property "Value" "10K_1%_0402"
			(at -2.579871 8.061915 90)
			(unlocked yes)
			(layer "F.SilkS")
			(hide yes)
			(effects
				(font
					(size 0.762 0.762)
					(thickness 0.2286)
				)
			)
		)
		(sheetname "USBUart_DipSelects")
		(sheetfile "USBUart_DipSelects.kicad_sch")
		(duplicate_pad_numbers_are_jumpers no)
		(pad "1" smd rect
			(at -0.375 0 270)
			(size 0.45 0.5)
			(layers "F.Cu" "F.Mask" "F.Paste")
			(net "+3.3V")
		)
		(pad "2" smd rect
			(at 0.375 0 270)
			(size 0.45 0.5)
			(layers "F.Cu" "F.Mask" "F.Paste")
			(net "DIP_SW_PPS_SEL")
		)
	)
	(footprint "SamacSys:155124M173200"
		(layer "F.Cu")
		(at 58.4511 128.4162 90)
		(property "Reference" "D17"
			(at -0.4714 1.701931 90)
			(unlocked yes)
			(layer "F.SilkS")
			(effects
				(font
					(size 0.762 0.762)
					(thickness 0.2286)
				)
			)
		)
		(property "Value" "155124M173200"
			(at 7.1471 2.605271 90)
			(unlocked yes)
			(layer "F.SilkS")
			(hide yes)
			(effects
				(font
					(size 0.762 0.762)
					(thickness 0.2286)
				)
			)
		)
		(sheetname "USER_IO_STATUS")
		(sheetfile "USER_IO_STATUS.kicad_sch")
		(duplicate_pad_numbers_are_jumpers no)
		(fp_line
			(start -0.8 0.5)
			(end 0.8 0.5)
			(stroke
				(width 0.1)
				(type solid)
			)
			(layer "F.SilkS")
		)
		(fp_arc
			(start -2 -0.1)
			(mid -1.95 -0.05)
			(end -2 0)
			(stroke
				(width 0.1)
				(type solid)
			)
			(layer "F.SilkS")
		)
		(fp_arc
			(start -2 0)
			(mid -2.05 -0.05)
			(end -2 -0.1)
			(stroke
				(width 0.1)
				(type solid)
			)
			(layer "F.SilkS")
		)
		(pad "1" smd rect
			(at -1.4 0 180)
			(size 0.9 0.6)
			(layers "F.Cu" "F.Mask" "F.Paste")
			(net "+3.3V")
		)
		(pad "2" smd rect
			(at -0.45 -0.325 90)
			(size 0.6 0.55)
			(layers "F.Cu" "F.Mask" "F.Paste")
			(net "NetD17_2")
		)
		(pad "3" smd rect
			(at 0.45 -0.325 90)
			(size 0.6 0.55)
			(layers "F.Cu" "F.Mask" "F.Paste")
			(net "NetD17_3")
		)
		(pad "4" smd rect
			(at 1.4 0 180)
			(size 0.9 0.6)
			(layers "F.Cu" "F.Mask" "F.Paste")
			(net "NetD17_4")
		)
	)
	(footprint "Vault:FP-C1005-050-0_05-IPC_A"
		(layer "F.Cu")
		(at 232.5261 107.8162 -90)
		(property "Reference" "C16"
			(at 1.3 1.106655 90)
			(unlocked yes)
			(layer "F.SilkS")
			(effects
				(font
					(size 0.762 0.762)
					(thickness 0.2286)
				)
				(justify left bottom)
			)
		)
		(property "Value" "2.2uF_16V_0402"
			(at 2.993045 -13.2355 0)
			(unlocked yes)
			(layer "F.SilkS")
			(hide yes)
			(effects
				(font
					(size 0.762 0.762)
					(thickness 0.2286)
				)
				(justify left bottom)
			)
		)
		(sheetname "POWER")
		(sheetfile "POWER.kicad_sch")
		(duplicate_pad_numbers_are_jumpers no)
		(fp_line
			(start 0.83624 0.73624)
			(end -0.83624 0.73624)
			(stroke
				(width 0.2)
				(type solid)
			)
			(layer "F.SilkS")
		)
		(fp_line
			(start 0.83624 -0.73624)
			(end -0.83624 -0.73624)
			(stroke
				(width 0.2)
				(type solid)
			)
			(layer "F.SilkS")
		)
		(fp_line
			(start -1.03624 0.53624)
			(end -1.03624 -0.53624)
			(stroke
				(width 0.2)
				(type solid)
			)
			(layer "F.CrtYd")
		)
		(fp_line
			(start 1.03624 0.53624)
			(end -1.03624 0.53624)
			(stroke
				(width 0.2)
				(type solid)
			)
			(layer "F.CrtYd")
		)
		(fp_line
			(start 1.03624 0.53624)
			(end 1.03624 -0.53624)
			(stroke
				(width 0.2)
				(type solid)
			)
			(layer "F.CrtYd")
		)
		(fp_line
			(start 1.03624 -0.53624)
			(end -1.03624 -0.53624)
			(stroke
				(width 0.2)
				(type solid)
			)
			(layer "F.CrtYd")
		)
		(fp_line
			(start -1.03624 0.53624)
			(end -1.03624 -0.53624)
			(stroke
				(width 0.2)
				(type solid)
			)
			(layer "F.Fab")
		)
		(fp_line
			(start 1.03624 0.53624)
			(end -1.03624 0.53624)
			(stroke
				(width 0.2)
				(type solid)
			)
			(layer "F.Fab")
		)
		(fp_line
			(start 1.03624 0.53624)
			(end 1.03624 -0.53624)
			(stroke
				(width 0.2)
				(type solid)
			)
			(layer "F.Fab")
		)
		(fp_line
			(start 0 0.5)
			(end 0 -0.5)
			(stroke
				(width 0.1)
				(type solid)
			)
			(layer "F.Fab")
		)
		(fp_line
			(start 0.5 0)
			(end -0.5 0)
			(stroke
				(width 0.1)
				(type solid)
			)
			(layer "F.Fab")
		)
		(fp_line
			(start 1.03624 -0.53624)
			(end -1.03624 -0.53624)
			(stroke
				(width 0.2)
				(type solid)
			)
			(layer "F.Fab")
		)
		(fp_text user "${REFERENCE}"
			(at -0.00001 0.09602 270)
			(unlocked yes)
			(layer "F.Fab")
			(effects
				(font
					(face "Arial")
					(size 0.63 0.63)
					(thickness 0.1)
				)
				(justify left bottom)
			)
		)
		(pad "1" smd rect
			(at -0.46657 0 270)
			(size 0.73933 0.67248)
			(layers "F.Cu" "F.Mask" "F.Paste")
			(net "+5.0V")
			(solder_mask_margin 0)
			(solder_paste_margin 0)
		)
		(pad "2" smd rect
			(at 0.46658 0 270)
			(size 0.73933 0.67248)
			(layers "F.Cu" "F.Mask" "F.Paste")
			(net "GND")
			(solder_mask_margin 0)
			(solder_paste_margin 0)
		)
	)
	(footprint "Vault:FP-0402-L_1_0_1-W_0_5_0_1-IPC_C"
		(layer "F.Cu")
		(at 206.0261 109.6162 90)
		(property "Reference" "C6"
			(at -4.1 0.593345 90)
			(unlocked yes)
			(layer "F.SilkS")
			(effects
				(font
					(size 0.762 0.762)
					(thickness 0.2286)
				)
				(justify left bottom)
			)
		)
		(property "Value" "0.1uF_25V_0402"
			(at -5.449845 12.8601 0)
			(unlocked yes)
			(layer "F.SilkS")
			(hide yes)
			(effects
				(font
					(size 0.762 0.762)
					(thickness 0.2286)
				)
				(justify left bottom)
			)
		)
		(sheetname "POWER")
		(sheetfile "POWER.kicad_sch")
		(duplicate_pad_numbers_are_jumpers no)
		(fp_line
			(start -0.65607 -0.7)
			(end 0.65607 -0.7)
			(stroke
				(width 0.2)
				(type solid)
			)
			(layer "F.SilkS")
		)
		(fp_line
			(start -0.65607 0.7)
			(end 0.65607 0.7)
			(stroke
				(width 0.2)
				(type solid)
			)
			(layer "F.SilkS")
		)
		(fp_line
			(start 0.75607 -0.4)
			(end 0.75607 0.4)
			(stroke
				(width 0.2)
				(type solid)
			)
			(layer "F.CrtYd")
		)
		(fp_line
			(start -0.75607 -0.4)
			(end 0.75607 -0.4)
			(stroke
				(width 0.2)
				(type solid)
			)
			(layer "F.CrtYd")
		)
		(fp_line
			(start -0.75607 -0.4)
			(end -0.75607 0.4)
			(stroke
				(width 0.2)
				(type solid)
			)
			(layer "F.CrtYd")
		)
		(fp_line
			(start -0.75607 0.4)
			(end 0.75607 0.4)
			(stroke
				(width 0.2)
				(type solid)
			)
			(layer "F.CrtYd")
		)
		(fp_line
			(start 0 -0.5)
			(end 0 0.5)
			(stroke
				(width 0.1)
				(type solid)
			)
			(layer "F.Fab")
		)
		(fp_line
			(start 0.75607 -0.4)
			(end 0.75607 0.4)
			(stroke
				(width 0.2)
				(type solid)
			)
			(layer "F.Fab")
		)
		(fp_line
			(start -0.75607 -0.4)
			(end 0.75607 -0.4)
			(stroke
				(width 0.2)
				(type solid)
			)
			(layer "F.Fab")
		)
		(fp_line
			(start -0.75607 -0.4)
			(end -0.75607 0.4)
			(stroke
				(width 0.2)
				(type solid)
			)
			(layer "F.Fab")
		)
		(fp_line
			(start -0.5 0)
			(end 0.5 0)
			(stroke
				(width 0.1)
				(type solid)
			)
			(layer "F.Fab")
		)
		(fp_line
			(start -0.75607 0.4)
			(end 0.75607 0.4)
			(stroke
				(width 0.2)
				(type solid)
			)
			(layer "F.Fab")
		)
		(fp_text user "${REFERENCE}"
			(at -0.00001 0.09602 90)
			(unlocked yes)
			(layer "F.Fab")
			(effects
				(font
					(face "Arial")
					(size 0.63 0.63)
					(thickness 0.1)
				)
				(justify left bottom)
			)
		)
		(pad "1" smd rect
			(at -0.36554 0 90)
			(size 0.58106 0.51213)
			(layers "F.Cu" "F.Mask" "F.Paste")
			(net "NetC6_1")
			(solder_mask_margin 0)
			(solder_paste_margin 0)
		)
		(pad "2" smd rect
			(at 0.36554 0 90)
			(size 0.58106 0.51213)
			(layers "F.Cu" "F.Mask" "F.Paste")
			(net "GND")
			(solder_mask_margin 0)
			(solder_paste_margin 0)
		)
	)
	(footprint "Capacitors:CAPC2012X14N"
		(layer "F.Cu")
		(at 209.8261 85.8162 90)
		(property "Reference" "C1"
			(at 1.9 0.393345 90)
			(unlocked yes)
			(layer "F.SilkS")
			(effects
				(font
					(size 0.762 0.762)
					(thickness 0.2286)
				)
				(justify left bottom)
			)
		)
		(property "Value" "CAP_0805_10UF_25V"
			(at -3.433445 -1.5875 0)
			(unlocked yes)
			(layer "F.SilkS")
			(hide yes)
			(effects
				(font
					(size 0.762 0.762)
					(thickness 0.2286)
				)
				(justify left bottom)
			)
		)
		(sheetname "POWER")
		(sheetfile "POWER.kicad_sch")
		(duplicate_pad_numbers_are_jumpers no)
		(fp_line
			(start -0.762 -0.9652)
			(end 0.762 -0.9652)
			(stroke
				(width 0.1524)
				(type solid)
			)
			(layer "F.SilkS")
		)
		(fp_line
			(start -0.762 0.9652)
			(end 0.762 0.9652)
			(stroke
				(width 0.1524)
				(type solid)
			)
			(layer "F.SilkS")
		)
		(pad "1" smd rect
			(at -0.9 0 180)
			(size 1.45 1.15)
			(layers "F.Cu" "F.Mask" "F.Paste")
			(net "+12V")
		)
		(pad "2" smd rect
			(at 0.9 0 180)
			(size 1.45 1.15)
			(layers "F.Cu" "F.Mask" "F.Paste")
			(net "GND")
		)
	)
	(footprint "Vault:FP-MK212BG-MFG"
		(layer "F.Cu")
		(at 232.7261 69.5162)
		(property "Reference" "C56"
			(at 0.9286 1.726931 0)
			(unlocked yes)
			(layer "F.SilkS")
			(effects
				(font
					(size 0.762 0.762)
					(thickness 0.2286)
				)
			)
		)
		(property "Value" "10uF"
			(at -3.240271 2.22164 270)
			(unlocked yes)
			(layer "F.SilkS")
			(hide yes)
			(effects
				(font
					(size 0.762 0.762)
					(thickness 0.2286)
				)
			)
		)
		(sheetname "GPS_IMU_SENSORS")
		(sheetfile "GPS_IMU_SENSORS.kicad_sch")
		(duplicate_pad_numbers_are_jumpers no)
		(fp_line
			(start -0.125 -0.725)
			(end 0.125 -0.725)
			(stroke
				(width 0.2)
				(type solid)
			)
			(layer "F.SilkS")
		)
		(fp_line
			(start -0.125 0.725)
			(end 0.125 0.725)
			(stroke
				(width 0.2)
				(type solid)
			)
			(layer "F.SilkS")
		)
		(fp_line
			(start -1.6 -0.825)
			(end 1.6 -0.825)
			(stroke
				(width 0.2)
				(type solid)
			)
			(layer "F.CrtYd")
		)
		(fp_line
			(start -1.6 0.825)
			(end -1.6 -0.825)
			(stroke
				(width 0.2)
				(type solid)
			)
			(layer "F.CrtYd")
		)
		(fp_line
			(start -1.6 0.825)
			(end 1.6 0.825)
			(stroke
				(width 0.2)
				(type solid)
			)
			(layer "F.CrtYd")
		)
		(fp_line
			(start 1.6 0.825)
			(end 1.6 -0.825)
			(stroke
				(width 0.2)
				(type solid)
			)
			(layer "F.CrtYd")
		)
		(fp_line
			(start -1.6 -0.825)
			(end 1.6 -0.825)
			(stroke
				(width 0.2)
				(type solid)
			)
			(layer "F.Fab")
		)
		(fp_line
			(start -1.6 0.825)
			(end -1.6 -0.825)
			(stroke
				(width 0.2)
				(type solid)
			)
			(layer "F.Fab")
		)
		(fp_line
			(start -1.6 0.825)
			(end 1.6 0.825)
			(stroke
				(width 0.2)
				(type solid)
			)
			(layer "F.Fab")
		)
		(fp_line
			(start -0.5 0)
			(end 0.5 0)
			(stroke
				(width 0.1)
				(type solid)
			)
			(layer "F.Fab")
		)
		(fp_line
			(start 0 0.5)
			(end 0 -0.5)
			(stroke
				(width 0.1)
				(type solid)
			)
			(layer "F.Fab")
		)
		(fp_line
			(start 1.6 0.825)
			(end 1.6 -0.825)
			(stroke
				(width 0.2)
				(type solid)
			)
			(layer "F.Fab")
		)
		(fp_text user "${REFERENCE}"
			(at -0.00001 0.09602 360)
			(unlocked yes)
			(layer "F.Fab")
			(effects
				(font
					(face "Arial")
					(size 0.63 0.63)
					(thickness 0.1)
				)
				(justify left bottom)
			)
		)
		(pad "1" smd rect
			(at -1 0)
			(size 1 1.25)
			(layers "F.Cu" "F.Mask" "F.Paste")
			(net "+5.0V")
			(solder_mask_margin 0)
			(solder_paste_margin 0)
		)
		(pad "2" smd rect
			(at 1 0)
			(size 1 1.25)
			(layers "F.Cu" "F.Mask" "F.Paste")
			(net "GND")
			(solder_mask_margin 0)
			(solder_paste_margin 0)
		)
	)
	(footprint "Vault:RESC1608X55X30NL15T15"
		(layer "F.Cu")
		(at 82.1261 98.8662 -90)
		(property "Reference" "R15"
			(at 2.7714 -0.026921 90)
			(unlocked yes)
			(layer "F.SilkS")
			(effects
				(font
					(size 0.762 0.762)
					(thickness 0.2286)
				)
			)
		)
		(property "Value" "4.7K"
			(at 2.808471 -4.96406 0)
			(unlocked yes)
			(layer "F.SilkS")
			(hide yes)
			(effects
				(font
					(size 0.762 0.762)
					(thickness 0.2286)
				)
			)
		)
		(sheetname "USER_IO")
		(sheetfile "USER_IO.kicad_sch")
		(duplicate_pad_numbers_are_jumpers no)
		(pad "1" smd rect
			(at -0.75 0)
			(size 0.95 0.95)
			(layers "F.Cu" "F.Mask" "F.Paste")
			(net "ANT1_IO_IN")
		)
		(pad "2" smd rect
			(at 0.75 0)
			(size 0.95 0.95)
			(layers "F.Cu" "F.Mask" "F.Paste")
			(net "+3.3V")
		)
	)
	(footprint "Vault:RESC3116X65X50ML20T20"
		(layer "F.Cu")
		(at 214.3261 97.7162 180)
		(property "Reference" "R44"
			(at -1.9714 -1.673069 180)
			(unlocked yes)
			(layer "F.SilkS")
			(effects
				(font
					(size 0.762 0.762)
					(thickness 0.2286)
				)
			)
		)
		(property "Value" "DNI_0_5%_1206"
			(at 7.27402 3.291071 180)
			(unlocked yes)
			(layer "F.SilkS")
			(hide yes)
			(effects
				(font
					(size 0.762 0.762)
					(thickness 0.2286)
				)
			)
		)
		(sheetname "POWER")
		(sheetfile "POWER.kicad_sch")
		(duplicate_pad_numbers_are_jumpers no)
		(fp_line
			(start 0.35 0.85)
			(end -0.35 0.85)
			(stroke
				(width 0.2)
				(type solid)
			)
			(layer "F.SilkS")
		)
		(fp_line
			(start 0.35 -0.85)
			(end -0.35 -0.85)
			(stroke
				(width 0.2)
				(type solid)
			)
			(layer "F.SilkS")
		)
		(pad "1" smd rect
			(at -1.475 0 270)
			(size 1.9 1.45)
			(layers "F.Cu" "F.Mask" "F.Paste")
			(net "NetD12_1")
		)
		(pad "2" smd rect
			(at 1.475 0 270)
			(size 1.9 1.45)
			(layers "F.Cu" "F.Mask" "F.Paste")
			(net "+12V_SENS")
		)
	)
	(footprint "Vault:RESC1005X40X25LL05T05"
		(layer "F.Cu")
		(at 206.4261 82.9162)
		(property "Reference" "R64"
			(at 0.2286 -1.173069 0)
			(unlocked yes)
			(layer "F.SilkS")
			(effects
				(font
					(size 0.762 0.762)
					(thickness 0.2286)
				)
			)
		)
		(property "Value" "0_1%_0402"
			(at -2.579871 6.66536 270)
			(unlocked yes)
			(layer "F.SilkS")
			(hide yes)
			(effects
				(font
					(size 0.762 0.762)
					(thickness 0.2286)
				)
			)
		)
		(sheetname "POWER")
		(sheetfile "POWER.kicad_sch")
		(duplicate_pad_numbers_are_jumpers no)
		(pad "1" smd rect
			(at -0.4 0 90)
			(size 0.45 0.45)
			(layers "F.Cu" "F.Mask" "F.Paste")
			(net "NetR64_1")
		)
		(pad "2" smd rect
			(at 0.4 0 90)
			(size 0.45 0.45)
			(layers "F.Cu" "F.Mask" "F.Paste")
			(net "GND")
		)
	)
	(footprint "Vault:RESC1005X40X25LL10T10"
		(layer "F.Cu")
		(at 214.0261 127.2162 90)
		(property "Reference" "R73"
			(at 1.9714 -0.226931 270)
			(unlocked yes)
			(layer "F.SilkS")
			(effects
				(font
					(size 0.762 0.762)
					(thickness 0.2286)
				)
			)
		)
		(property "Value" "1.21_1%_0402"
			(at -2.579871 8.569745 0)
			(unlocked yes)
			(layer "F.SilkS")
			(hide yes)
			(effects
				(font
					(size 0.762 0.762)
					(thickness 0.2286)
				)
			)
		)
		(sheetname "POWER")
		(sheetfile "POWER.kicad_sch")
		(duplicate_pad_numbers_are_jumpers no)
		(pad "1" smd rect
			(at -0.375 0 180)
			(size 0.5 0.55)
			(layers "F.Cu" "F.Mask" "F.Paste")
			(net "NetC72_1")
		)
		(pad "2" smd rect
			(at 0.375 0 180)
			(size 0.5 0.55)
			(layers "F.Cu" "F.Mask" "F.Paste")
			(net "NetL2_1")
		)
	)
	(footprint "Vault:RESC1608X55X30NL15T15"
		(layer "F.Cu")
		(at 83.3761 89.6162)
		(property "Reference" "R41"
			(at -2.521405 0.026921 0)
			(unlocked yes)
			(layer "F.SilkS")
			(effects
				(font
					(size 0.762 0.762)
					(thickness 0.2286)
				)
			)
		)
		(property "Value" "4.7K"
			(at 1.61204 2.325871 0)
			(unlocked yes)
			(layer "F.SilkS")
			(hide yes)
			(effects
				(font
					(size 0.762 0.762)
					(thickness 0.2286)
				)
			)
		)
		(sheetname "USER_IO_STATUS")
		(sheetfile "USER_IO_STATUS.kicad_sch")
		(duplicate_pad_numbers_are_jumpers no)
		(pad "1" smd rect
			(at -0.75 0 90)
			(size 0.95 0.95)
			(layers "F.Cu" "F.Mask" "F.Paste")
			(net "GND")
		)
		(pad "2" smd rect
			(at 0.75 0 90)
			(size 0.95 0.95)
			(layers "F.Cu" "F.Mask" "F.Paste")
			(net "NetR41_2")
		)
	)
	(footprint "Vault:SOT143-4L"
		(layer "F.Cu")
		(at 71.8761 100.7662 90)
		(property "Reference" "D1"
			(at -2.776921 1.478595 0)
			(unlocked yes)
			(layer "F.SilkS")
			(effects
				(font
					(size 0.762 0.762)
					(thickness 0.2286)
				)
			)
		)
		(property "Value" "8240136"
			(at 2.6781 3.341871 90)
			(unlocked yes)
			(layer "F.SilkS")
			(hide yes)
			(effects
				(font
					(size 0.762 0.762)
					(thickness 0.2286)
				)
			)
		)
		(sheetname "USER_IO")
		(sheetfile "USER_IO.kicad_sch")
		(duplicate_pad_numbers_are_jumpers no)
		(fp_line
			(start 2.05 -1.7)
			(end 2.05 1.7)
			(stroke
				(width 0.2)
				(type solid)
			)
			(layer "F.SilkS")
		)
		(fp_line
			(start -2.05 -1.7)
			(end 2.05 -1.7)
			(stroke
				(width 0.2)
				(type solid)
			)
			(layer "F.SilkS")
		)
		(fp_line
			(start -2.05 -1.7)
			(end -2.05 1.675)
			(stroke
				(width 0.2)
				(type solid)
			)
			(layer "F.SilkS")
		)
		(fp_line
			(start -2.05 1.7)
			(end 2.05 1.7)
			(stroke
				(width 0.2)
				(type solid)
			)
			(layer "F.SilkS")
		)
		(fp_circle
			(center -2.404 -1.075)
			(end -2.15 -1.075)
			(stroke
				(width 0.2)
				(type solid)
			)
			(fill no)
			(layer "F.SilkS")
		)
		(pad "1" smd rect
			(at -1.1 -0.75 180)
			(size 1.4 1.4)
			(layers "F.Cu" "F.Mask" "F.Paste")
			(net "GND")
		)
		(pad "2" smd rect
			(at -1.1 0.95 180)
			(size 1 1.4)
			(layers "F.Cu" "F.Mask" "F.Paste")
			(net "NetAN2_1")
		)
		(pad "3" smd rect
			(at 1.1 0.95 180)
			(size 1 1.4)
			(layers "F.Cu" "F.Mask" "F.Paste")
			(net "NetAN1_1")
		)
		(pad "4" smd rect
			(at 1.1 -0.95 180)
			(size 1 1.4)
			(layers "F.Cu" "F.Mask" "F.Paste")
			(net "+3.3V")
		)
	)
	(footprint "Vault:FP-ERJ2RK-IPC_A"
		(layer "F.Cu")
		(at 174.0261 85.31405 -90)
		(property "Reference" "R94"
			(at 0.33075 -1.573069 270)
			(unlocked yes)
			(layer "F.SilkS")
			(effects
				(font
					(size 0.762 0.762)
					(thickness 0.2286)
				)
			)
		)
		(property "Value" "200_1%_0402"
			(at -2.935471 7.782475 180)
			(unlocked yes)
			(layer "F.SilkS")
			(hide yes)
			(effects
				(font
					(size 0.762 0.762)
					(thickness 0.2286)
				)
			)
		)
		(sheetname "USBUart_DipSelects")
		(sheetfile "USBUart_DipSelects.kicad_sch")
		(duplicate_pad_numbers_are_jumpers no)
		(fp_line
			(start 0.83624 0.73624)
			(end -0.83623 0.73624)
			(stroke
				(width 0.2)
				(type solid)
			)
			(layer "F.SilkS")
		)
		(fp_line
			(start 0.83624 -0.73624)
			(end -0.83623 -0.73624)
			(stroke
				(width 0.2)
				(type solid)
			)
			(layer "F.SilkS")
		)
		(fp_line
			(start -1.03623 0.53624)
			(end -1.03623 -0.53624)
			(stroke
				(width 0.2)
				(type solid)
			)
			(layer "F.CrtYd")
		)
		(fp_line
			(start 1.03624 0.53624)
			(end -1.03623 0.53624)
			(stroke
				(width 0.2)
				(type solid)
			)
			(layer "F.CrtYd")
		)
		(fp_line
			(start 1.03624 0.53624)
			(end 1.03624 -0.53624)
			(stroke
				(width 0.2)
				(type solid)
			)
			(layer "F.CrtYd")
		)
		(fp_line
			(start 1.03624 -0.53624)
			(end -1.03623 -0.53624)
			(stroke
				(width 0.2)
				(type solid)
			)
			(layer "F.CrtYd")
		)
		(fp_line
			(start -1.03623 0.53624)
			(end -1.03623 -0.53624)
			(stroke
				(width 0.2)
				(type solid)
			)
			(layer "F.Fab")
		)
		(fp_line
			(start 1.03624 0.53624)
			(end -1.03623 0.53624)
			(stroke
				(width 0.2)
				(type solid)
			)
			(layer "F.Fab")
		)
		(fp_line
			(start 1.03624 0.53624)
			(end 1.03624 -0.53624)
			(stroke
				(width 0.2)
				(type solid)
			)
			(layer "F.Fab")
		)
		(fp_line
			(start 0 0.5)
			(end 0 -0.5)
			(stroke
				(width 0.1)
				(type solid)
			)
			(layer "F.Fab")
		)
		(fp_line
			(start 0.5 0)
			(end -0.5 0)
			(stroke
				(width 0.1)
				(type solid)
			)
			(layer "F.Fab")
		)
		(fp_line
			(start 1.03624 -0.53624)
			(end -1.03623 -0.53624)
			(stroke
				(width 0.2)
				(type solid)
			)
			(layer "F.Fab")
		)
		(fp_text user "${REFERENCE}"
			(at -0.00001 0.09602 270)
			(unlocked yes)
			(layer "F.Fab")
			(effects
				(font
					(face "Arial")
					(size 0.63 0.63)
					(thickness 0.1)
				)
				(justify left bottom)
			)
		)
		(pad "1" smd rect
			(at -0.50214 0 270)
			(size 0.66818 0.67248)
			(layers "F.Cu" "F.Mask" "F.Paste")
			(net "DIP_SW_PPS_SEL")
			(solder_mask_margin 0)
			(solder_paste_margin 0)
		)
		(pad "2" smd rect
			(at 0.50215 0 270)
			(size 0.66818 0.67248)
			(layers "F.Cu" "F.Mask" "F.Paste")
			(net "NetD24_1")
			(solder_mask_margin 0)
			(solder_paste_margin 0)
		)
	)
	(footprint "Passives:SOT65P210X110-3N"
		(layer "F.Cu")
		(at 195.11136 139.37763)
		(property "Reference" "D5"
			(at -3.38526 -0.968085 0)
			(unlocked yes)
			(layer "F.SilkS")
			(effects
				(font
					(size 0.762 0.762)
					(thickness 0.2286)
				)
				(justify left bottom)
			)
		)
		(property "Value" "BAT54SW"
			(at -10.7749 -6.323555 0)
			(unlocked yes)
			(layer "F.SilkS")
			(hide yes)
			(effects
				(font
					(size 0.762 0.762)
					(thickness 0.2286)
				)
				(justify left bottom)
			)
		)
		(sheetname "PCIe_JTAG")
		(sheetfile "PCIe_JTAG.kicad_sch")
		(duplicate_pad_numbers_are_jumpers no)
		(fp_line
			(start -0.325 -1.1)
			(end 0.675 -1.1)
			(stroke
				(width 0.2)
				(type solid)
			)
			(layer "F.SilkS")
		)
		(fp_line
			(start -0.325 1.1)
			(end 0.675 1.1)
			(stroke
				(width 0.2)
				(type solid)
			)
			(layer "F.SilkS")
		)
		(fp_line
			(start 0.675 -0.65)
			(end 0.675 -1.1)
			(stroke
				(width 0.2)
				(type solid)
			)
			(layer "F.SilkS")
		)
		(fp_line
			(start 0.675 1.1)
			(end 0.675 0.65)
			(stroke
				(width 0.2)
				(type solid)
			)
			(layer "F.SilkS")
		)
		(fp_circle
			(center -1.125 -1.45)
			(end -1.125 -1.575)
			(stroke
				(width 0.25)
				(type solid)
			)
			(fill no)
			(layer "F.SilkS")
		)
		(pad "1" smd rect
			(at -1.125 -0.65 90)
			(size 0.5 0.9)
			(layers "F.Cu" "F.Mask" "F.Paste")
			(net "GND")
		)
		(pad "2" smd rect
			(at -1.125 0.65 90)
			(size 0.5 0.9)
			(layers "F.Cu" "F.Mask" "F.Paste")
			(net "+3.3V")
		)
		(pad "3" smd rect
			(at 1.125 0 90)
			(size 0.5 0.9)
			(layers "F.Cu" "F.Mask" "F.Paste")
			(net "FPGA_TCK")
		)
	)
	(footprint "Vault:CAPC1608X87X45ML20T05"
		(layer "F.Cu")
		(at 218.76876 58.67651)
		(property "Reference" "C36"
			(at -2.91406 -0.070979 0)
			(unlocked yes)
			(layer "F.SilkS")
			(effects
				(font
					(size 0.762 0.762)
					(thickness 0.2286)
				)
			)
		)
		(property "Value" "0.1uF"
			(at 2.069035 2.630671 0)
			(unlocked yes)
			(layer "F.SilkS")
			(hide yes)
			(effects
				(font
					(size 0.762 0.762)
					(thickness 0.2286)
				)
			)
		)
		(sheetname "GPS_IMU_SENSORS")
		(sheetfile "GPS_IMU_SENSORS.kicad_sch")
		(duplicate_pad_numbers_are_jumpers no)
		(pad "1" smd rect
			(at -0.7 0 90)
			(size 1.1 1.05)
			(layers "F.Cu" "F.Mask" "F.Paste")
			(net "GND")
		)
		(pad "2" smd rect
			(at 0.7 0 90)
			(size 1.1 1.05)
			(layers "F.Cu" "F.Mask" "F.Paste")
			(net "+3.3V")
		)
	)
	(footprint "Vault:FP-T495D107K016ATE125-MFG"
		(layer "F.Cu")
		(at 206.7261 117.3162)
		(property "Reference" "C75"
			(at 6.589529 0.01204 270)
			(unlocked yes)
			(layer "F.SilkS")
			(effects
				(font
					(size 0.762 0.762)
					(thickness 0.2286)
				)
			)
		)
		(property "Value" "100uF_16V_2917"
			(at -5.818361 8.010455 270)
			(unlocked yes)
			(layer "F.SilkS")
			(hide yes)
			(effects
				(font
					(size 0.762 0.762)
					(thickness 0.2286)
				)
			)
		)
		(sheetname "POWER")
		(sheetfile "POWER.kicad_sch")
		(duplicate_pad_numbers_are_jumpers no)
		(fp_line
			(start -3.8 -2.3)
			(end 3.8 -2.3)
			(stroke
				(width 0.2)
				(type solid)
			)
			(layer "F.SilkS")
		)
		(fp_line
			(start -3.8 -1.54)
			(end -3.8 -2.3)
			(stroke
				(width 0.2)
				(type solid)
			)
			(layer "F.SilkS")
		)
		(fp_line
			(start -3.8 2.3)
			(end -3.8 1.54)
			(stroke
				(width 0.2)
				(type solid)
			)
			(layer "F.SilkS")
		)
		(fp_line
			(start -3.8 2.3)
			(end 3.8 2.3)
			(stroke
				(width 0.2)
				(type solid)
			)
			(layer "F.SilkS")
		)
		(fp_line
			(start 3.8 -1.54)
			(end 3.8 -2.3)
			(stroke
				(width 0.2)
				(type solid)
			)
			(layer "F.SilkS")
		)
		(fp_line
			(start 3.8 2.3)
			(end 3.8 1.54)
			(stroke
				(width 0.2)
				(type solid)
			)
			(layer "F.SilkS")
		)
		(fp_line
			(start 4.4 0)
			(end 5 0)
			(stroke
				(width 0.2)
				(type solid)
			)
			(layer "F.SilkS")
		)
		(fp_line
			(start 4.7 0.3)
			(end 4.7 -0.3)
			(stroke
				(width 0.2)
				(type solid)
			)
			(layer "F.SilkS")
		)
		(fp_line
			(start -4.105 -2.4)
			(end 4.105 -2.4)
			(stroke
				(width 0.2)
				(type solid)
			)
			(layer "F.CrtYd")
		)
		(fp_line
			(start -4.105 2.4)
			(end -4.105 -2.4)
			(stroke
				(width 0.2)
				(type solid)
			)
			(layer "F.CrtYd")
		)
		(fp_line
			(start -4.105 2.4)
			(end 4.105 2.4)
			(stroke
				(width 0.2)
				(type solid)
			)
			(layer "F.CrtYd")
		)
		(fp_line
			(start 4.105 2.4)
			(end 4.105 -2.4)
			(stroke
				(width 0.2)
				(type solid)
			)
			(layer "F.CrtYd")
		)
		(fp_line
			(start -4.105 -2.4)
			(end 4.105 -2.4)
			(stroke
				(width 0.2)
				(type solid)
			)
			(layer "F.Fab")
		)
		(fp_line
			(start -4.105 2.4)
			(end -4.105 -2.4)
			(stroke
				(width 0.2)
				(type solid)
			)
			(layer "F.Fab")
		)
		(fp_line
			(start -4.105 2.4)
			(end 4.105 2.4)
			(stroke
				(width 0.2)
				(type solid)
			)
			(layer "F.Fab")
		)
		(fp_line
			(start -0.5 0)
			(end 0.5 0)
			(stroke
				(width 0.1)
				(type solid)
			)
			(layer "F.Fab")
		)
		(fp_line
			(start 0 0.5)
			(end 0 -0.5)
			(stroke
				(width 0.1)
				(type solid)
			)
			(layer "F.Fab")
		)
		(fp_line
			(start 4.105 2.4)
			(end 4.105 -2.4)
			(stroke
				(width 0.2)
				(type solid)
			)
			(layer "F.Fab")
		)
		(fp_text user "${REFERENCE}"
			(at 0 0.28425 360)
			(unlocked yes)
			(layer "F.Fab")
			(effects
				(font
					(face "Arial")
					(size 0.63 0.63)
					(thickness 0.1)
				)
				(justify left bottom)
			)
		)
		(pad "1" smd rect
			(at -3.01 0)
			(size 1.99 2.33)
			(layers "F.Cu" "F.Mask" "F.Paste")
			(net "GND")
			(solder_mask_margin 0)
			(solder_paste_margin 0)
		)
		(pad "2" smd rect
			(at 3.01 0)
			(size 1.99 2.33)
			(layers "F.Cu" "F.Mask" "F.Paste")
			(net "+12V")
			(solder_mask_margin 0)
			(solder_paste_margin 0)
		)
	)
	(footprint "Vault:FP-2049261103-MFG"
		(layer "F.Cu")
		(at 239.3261 77.7162 90)
		(property "Reference" "J43"
			(at -5.773069 -1.0286 180)
			(unlocked yes)
			(layer "F.SilkS")
			(effects
				(font
					(size 0.762 0.762)
					(thickness 0.2286)
				)
			)
		)
		(property "Value" "2049261103"
			(at 2.6266 5.323071 90)
			(unlocked yes)
			(layer "F.SilkS")
			(hide yes)
			(effects
				(font
					(size 0.762 0.762)
					(thickness 0.2286)
				)
			)
		)
		(sheetname "USBUart_DipSelects")
		(sheetfile "USBUart_DipSelects.kicad_sch")
		(duplicate_pad_numbers_are_jumpers no)
		(fp_line
			(start 4.875 -3.525)
			(end 4.875 -2.475)
			(stroke
				(width 0.2)
				(type solid)
			)
			(layer "F.SilkS")
		)
		(fp_line
			(start 4.575 -3.525)
			(end 4.875 -3.525)
			(stroke
				(width 0.2)
				(type solid)
			)
			(layer "F.SilkS")
		)
		(fp_line
			(start 1.9 -3.525)
			(end 2.625 -3.525)
			(stroke
				(width 0.2)
				(type solid)
			)
			(layer "F.SilkS")
		)
		(fp_line
			(start -2.625 -3.525)
			(end -1.9 -3.525)
			(stroke
				(width 0.2)
				(type solid)
			)
			(layer "F.SilkS")
		)
		(fp_line
			(start -4.875 -3.525)
			(end -4.575 -3.525)
			(stroke
				(width 0.2)
				(type solid)
			)
			(layer "F.SilkS")
		)
		(fp_line
			(start -4.875 -3.525)
			(end -4.875 -2.475)
			(stroke
				(width 0.2)
				(type solid)
			)
			(layer "F.SilkS")
		)
		(fp_circle
			(center -1.3 -4.375)
			(end -1.175 -4.375)
			(stroke
				(width 0.25)
				(type solid)
			)
			(fill no)
			(layer "F.SilkS")
		)
		(fp_line
			(start 4.875 -3.9)
			(end 4.875 3.675)
			(stroke
				(width 0.2)
				(type solid)
			)
			(layer "F.CrtYd")
		)
		(fp_line
			(start -4.875 -3.9)
			(end 4.875 -3.9)
			(stroke
				(width 0.2)
				(type solid)
			)
			(layer "F.CrtYd")
		)
		(fp_line
			(start -4.875 -3.9)
			(end -4.875 3.675)
			(stroke
				(width 0.2)
				(type solid)
			)
			(layer "F.CrtYd")
		)
		(fp_line
			(start -4.875 3.675)
			(end 4.875 3.675)
			(stroke
				(width 0.2)
				(type solid)
			)
			(layer "F.CrtYd")
		)
		(fp_line
			(start 4.875 -3.9)
			(end 4.875 3.675)
			(stroke
				(width 0.2)
				(type solid)
			)
			(layer "F.Fab")
		)
		(fp_line
			(start -4.875 -3.9)
			(end 4.875 -3.9)
			(stroke
				(width 0.2)
				(type solid)
			)
			(layer "F.Fab")
		)
		(fp_line
			(start -4.875 -3.9)
			(end -4.875 3.675)
			(stroke
				(width 0.2)
				(type solid)
			)
			(layer "F.Fab")
		)
		(fp_line
			(start 0 -0.5)
			(end 0 0.5)
			(stroke
				(width 0.1)
				(type solid)
			)
			(layer "F.Fab")
		)
		(fp_line
			(start -0.5 0)
			(end 0.5 0)
			(stroke
				(width 0.1)
				(type solid)
			)
			(layer "F.Fab")
		)
		(fp_line
			(start -4.875 3.675)
			(end 4.875 3.675)
			(stroke
				(width 0.2)
				(type solid)
			)
			(layer "F.Fab")
		)
		(fp_text user "${REFERENCE}"
			(at -0.00185 0.17175 90)
			(unlocked yes)
			(layer "F.Fab")
			(effects
				(font
					(face "Arial")
					(size 0.63 0.63)
					(thickness 0.1)
				)
				(justify left bottom)
			)
		)
		(pad "1" smd rect
			(at -1.3 -3.2 90)
			(size 0.45 1.2)
			(layers "F.Cu" "F.Mask" "F.Paste")
			(net "USB_VBUS")
			(solder_mask_margin 0)
			(solder_paste_margin 0)
		)
		(pad "2" smd rect
			(at -0.65 -3.2 90)
			(size 0.45 1.2)
			(layers "F.Cu" "F.Mask" "F.Paste")
			(net "FTDI_USB_R_N")
			(solder_mask_margin 0)
			(solder_paste_margin 0)
		)
		(pad "3" smd rect
			(at 0 -3.2 90)
			(size 0.45 1.2)
			(layers "F.Cu" "F.Mask" "F.Paste")
			(net "FTDI_USB_R_P")
			(solder_mask_margin 0)
			(solder_paste_margin 0)
		)
		(pad "4" smd rect
			(at 0.65 -3.2 90)
			(size 0.45 1.2)
			(layers "F.Cu" "F.Mask" "F.Paste")
			(solder_mask_margin 0)
			(solder_paste_margin 0)
		)
		(pad "5" smd rect
			(at 1.3 -3.2 90)
			(size 0.45 1.2)
			(layers "F.Cu" "F.Mask" "F.Paste")
			(net "GND")
			(solder_mask_margin 0)
			(solder_paste_margin 0)
		)
		(pad "6" thru_hole roundrect
			(at -3.6 -2.9 90)
			(size 1.2 1.6)
			(drill oval 0.6 1)
			(layers "*.Cu" "*.Mask")
			(remove_unused_layers no)
			(roundrect_rratio 0.5)
			(net "GND")
			(solder_mask_margin 0)
			(solder_paste_margin -1000)
		)
		(pad "7" thru_hole roundrect
			(at 3.6 -2.9 90)
			(size 1.2 1.6)
			(drill oval 0.6 1)
			(layers "*.Cu" "*.Mask")
			(remove_unused_layers no)
			(roundrect_rratio 0.5)
			(net "GND")
			(solder_mask_margin 0)
			(solder_paste_margin -1000)
		)
		(pad "8" thru_hole roundrect
			(at -4.225 -1.2 90)
			(size 1.1 1.8)
			(drill oval 0.5 1.2)
			(layers "*.Cu" "*.Mask")
			(remove_unused_layers no)
			(roundrect_rratio 0.5)
			(net "GND")
			(solder_mask_margin 0)
			(solder_paste_margin -1000)
		)
		(pad "8" smd roundrect
			(at -4.225 -0.325 90)
			(size 1.1 3.55)
			(layers "F.Cu" "F.Mask" "F.Paste")
			(roundrect_rratio 0.5)
			(net "GND")
			(solder_mask_margin 0)
			(solder_paste_margin -1000)
		)
		(pad "8" smd roundrect
			(at -4.225 -0.325 90)
			(size 1.1 3.55)
			(layers "B.Cu" "B.Mask" "B.Paste")
			(roundrect_rratio 0.5)
			(net "GND")
			(solder_mask_margin 0)
			(solder_paste_margin -1000)
		)
		(pad "8" thru_hole roundrect
			(at -4.225 0.55 90)
			(size 1.1 1.8)
			(drill oval 0.5 1.2)
			(layers "*.Cu" "*.Mask")
			(remove_unused_layers no)
			(roundrect_rratio 0.5)
			(net "GND")
			(solder_mask_margin 0)
			(solder_paste_margin -1000)
		)
		(pad "9" thru_hole roundrect
			(at 4.225 -1.2 90)
			(size 1.1 1.8)
			(drill oval 0.5 1.2)
			(layers "*.Cu" "*.Mask")
			(remove_unused_layers no)
			(roundrect_rratio 0.5)
			(net "GND")
			(solder_mask_margin 0)
			(solder_paste_margin -1000)
		)
		(pad "9" smd roundrect
			(at 4.225 -0.325 90)
			(size 1.1 3.55)
			(layers "F.Cu" "F.Mask" "F.Paste")
			(roundrect_rratio 0.5)
			(net "GND")
			(solder_mask_margin 0)
			(solder_paste_margin -1000)
		)
		(pad "9" smd roundrect
			(at 4.225 -0.325 90)
			(size 1.1 3.55)
			(layers "B.Cu" "B.Mask" "B.Paste")
			(roundrect_rratio 0.5)
			(net "GND")
			(solder_mask_margin 0)
			(solder_paste_margin -1000)
		)
		(pad "9" thru_hole roundrect
			(at 4.225 0.55 90)
			(size 1.1 1.8)
			(drill oval 0.5 1.2)
			(layers "*.Cu" "*.Mask")
			(remove_unused_layers no)
			(roundrect_rratio 0.5)
			(net "GND")
			(solder_mask_margin 0)
			(solder_paste_margin -1000)
		)
	)
	(footprint "SamacSys:155124M173200"
		(layer "F.Cu")
		(at 58.4511 141.8162 90)
		(property "Reference" "D18"
			(at -0.5714 1.701931 90)
			(unlocked yes)
			(layer "F.SilkS")
			(effects
				(font
					(size 0.762 0.762)
					(thickness 0.2286)
				)
			)
		)
		(property "Value" "155124M173200"
			(at 7.1471 2.605271 90)
			(unlocked yes)
			(layer "F.SilkS")
			(hide yes)
			(effects
				(font
					(size 0.762 0.762)
					(thickness 0.2286)
				)
			)
		)
		(sheetname "USER_IO_STATUS")
		(sheetfile "USER_IO_STATUS.kicad_sch")
		(duplicate_pad_numbers_are_jumpers no)
		(fp_line
			(start -0.8 0.5)
			(end 0.8 0.5)
			(stroke
				(width 0.1)
				(type solid)
			)
			(layer "F.SilkS")
		)
		(fp_arc
			(start -2 -0.1)
			(mid -1.95 -0.05)
			(end -2 0)
			(stroke
				(width 0.1)
				(type solid)
			)
			(layer "F.SilkS")
		)
		(fp_arc
			(start -2 0)
			(mid -2.05 -0.05)
			(end -2 -0.1)
			(stroke
				(width 0.1)
				(type solid)
			)
			(layer "F.SilkS")
		)
		(pad "1" smd rect
			(at -1.4 0 180)
			(size 0.9 0.6)
			(layers "F.Cu" "F.Mask" "F.Paste")
			(net "+3.3V")
		)
		(pad "2" smd rect
			(at -0.45 -0.325 90)
			(size 0.6 0.55)
			(layers "F.Cu" "F.Mask" "F.Paste")
			(net "NetD18_2")
		)
		(pad "3" smd rect
			(at 0.45 -0.325 90)
			(size 0.6 0.55)
			(layers "F.Cu" "F.Mask" "F.Paste")
			(net "NetD18_3")
		)
		(pad "4" smd rect
			(at 1.4 0 180)
			(size 0.9 0.6)
			(layers "F.Cu" "F.Mask" "F.Paste")
			(net "NetD18_4")
		)
	)
	(footprint "Vault:FP-0402-L_1_0_1-W_0_5_0_1-IPC_C"
		(layer "F.Cu")
		(at 126.7261 83.2162 90)
		(property "Reference" "C96"
			(at 3.1286 0.026921 90)
			(unlocked yes)
			(layer "F.SilkS")
			(effects
				(font
					(size 0.762 0.762)
					(thickness 0.2286)
				)
			)
		)
		(property "Value" "0.1uF_25V_0402"
			(at -2.465551 9.839215 0)
			(unlocked yes)
			(layer "F.SilkS")
			(hide yes)
			(effects
				(font
					(size 0.762 0.762)
					(thickness 0.2286)
				)
			)
		)
		(sheetname "USBUart_DipSelects")
		(sheetfile "USBUart_DipSelects.kicad_sch")
		(duplicate_pad_numbers_are_jumpers no)
		(fp_line
			(start -0.65607 -0.7)
			(end 0.65607 -0.7)
			(stroke
				(width 0.2)
				(type solid)
			)
			(layer "F.SilkS")
		)
		(fp_line
			(start -0.65607 0.7)
			(end 0.65607 0.7)
			(stroke
				(width 0.2)
				(type solid)
			)
			(layer "F.SilkS")
		)
		(fp_line
			(start 0.75607 -0.4)
			(end 0.75607 0.4)
			(stroke
				(width 0.2)
				(type solid)
			)
			(layer "F.CrtYd")
		)
		(fp_line
			(start -0.75607 -0.4)
			(end 0.75607 -0.4)
			(stroke
				(width 0.2)
				(type solid)
			)
			(layer "F.CrtYd")
		)
		(fp_line
			(start -0.75607 -0.4)
			(end -0.75607 0.4)
			(stroke
				(width 0.2)
				(type solid)
			)
			(layer "F.CrtYd")
		)
		(fp_line
			(start -0.75607 0.4)
			(end 0.75607 0.4)
			(stroke
				(width 0.2)
				(type solid)
			)
			(layer "F.CrtYd")
		)
		(fp_line
			(start 0 -0.5)
			(end 0 0.5)
			(stroke
				(width 0.1)
				(type solid)
			)
			(layer "F.Fab")
		)
		(fp_line
			(start 0.75607 -0.4)
			(end 0.75607 0.4)
			(stroke
				(width 0.2)
				(type solid)
			)
			(layer "F.Fab")
		)
		(fp_line
			(start -0.75607 -0.4)
			(end 0.75607 -0.4)
			(stroke
				(width 0.2)
				(type solid)
			)
			(layer "F.Fab")
		)
		(fp_line
			(start -0.75607 -0.4)
			(end -0.75607 0.4)
			(stroke
				(width 0.2)
				(type solid)
			)
			(layer "F.Fab")
		)
		(fp_line
			(start -0.5 0)
			(end 0.5 0)
			(stroke
				(width 0.1)
				(type solid)
			)
			(layer "F.Fab")
		)
		(fp_line
			(start -0.75607 0.4)
			(end 0.75607 0.4)
			(stroke
				(width 0.2)
				(type solid)
			)
			(layer "F.Fab")
		)
		(fp_text user "${REFERENCE}"
			(at -0.00001 0.09601 90)
			(unlocked yes)
			(layer "F.Fab")
			(effects
				(font
					(face "Arial")
					(size 0.63 0.63)
					(thickness 0.1)
				)
				(justify left bottom)
			)
		)
		(pad "1" smd rect
			(at -0.36554 0 90)
			(size 0.58106 0.51213)
			(layers "F.Cu" "F.Mask" "F.Paste")
			(net "+3.3V")
			(solder_mask_margin 0)
			(solder_paste_margin 0)
		)
		(pad "2" smd rect
			(at 0.36554 0 90)
			(size 0.58106 0.51213)
			(layers "F.Cu" "F.Mask" "F.Paste")
			(net "GND")
			(solder_mask_margin 0)
			(solder_paste_margin 0)
		)
	)
	(footprint "Vault:RESC1005X40X25LL05T05"
		(layer "F.Cu")
		(at 191.2261 85.5162 180)
		(property "Reference" "R51"
			(at -0.528605 0.773079 0)
			(unlocked yes)
			(layer "F.SilkS")
			(effects
				(font
					(size 0.762 0.762)
					(thickness 0.2286)
				)
			)
		)
		(property "Value" "4.7K_0402"
			(at 1.612045 2.262391 180)
			(unlocked yes)
			(layer "F.SilkS")
			(hide yes)
			(effects
				(font
					(size 0.762 0.762)
					(thickness 0.2286)
				)
			)
		)
		(sheetname "GPS_IMU_SENSORS")
		(sheetfile "GPS_IMU_SENSORS.kicad_sch")
		(duplicate_pad_numbers_are_jumpers no)
		(pad "1" smd rect
			(at -0.4 0 270)
			(size 0.45 0.45)
			(layers "F.Cu" "F.Mask" "F.Paste")
			(net "+3.3V")
		)
		(pad "2" smd rect
			(at 0.4 0 270)
			(size 0.45 0.45)
			(layers "F.Cu" "F.Mask" "F.Paste")
			(net "NetR51_2")
		)
	)
	(footprint "Vault:RESC1005X40X25NL05T05"
		(layer "F.Cu")
		(at 233.6261 75.7162 90)
		(property "Reference" "R81"
			(at 0.271395 -4.526931 270)
			(unlocked yes)
			(layer "F.SilkS")
			(effects
				(font
					(size 0.762 0.762)
					(thickness 0.2286)
				)
			)
		)
		(property "Value" "27_1%_0402"
			(at -2.732271 7.37632 0)
			(unlocked yes)
			(layer "F.SilkS")
			(hide yes)
			(effects
				(font
					(size 0.762 0.762)
					(thickness 0.2286)
				)
			)
		)
		(sheetname "USBUart_DipSelects")
		(sheetfile "USBUart_DipSelects.kicad_sch")
		(duplicate_pad_numbers_are_jumpers no)
		(pad "1" smd rect
			(at -0.45 0 180)
			(size 0.55 0.55)
			(layers "F.Cu" "F.Mask" "F.Paste")
			(net "FTDI_USB_R_P")
		)
		(pad "2" smd rect
			(at 0.45 0 180)
			(size 0.55 0.55)
			(layers "F.Cu" "F.Mask" "F.Paste")
			(net "FTDI_USB_P")
		)
	)
	(footprint "Vault:RESC1005X40X25LL05T10"
		(layer "F.Cu")
		(at 235.7261 72.3162)
		(property "Reference" "R82"
			(at -2.0714 -0.173069 0)
			(unlocked yes)
			(layer "F.SilkS")
			(effects
				(font
					(size 0.762 0.762)
					(thickness 0.2286)
				)
			)
		)
		(property "Value" "10K_1%_0402"
			(at -2.579871 8.061915 270)
			(unlocked yes)
			(layer "F.SilkS")
			(hide yes)
			(effects
				(font
					(size 0.762 0.762)
					(thickness 0.2286)
				)
			)
		)
		(sheetname "USBUart_DipSelects")
		(sheetfile "USBUart_DipSelects.kicad_sch")
		(duplicate_pad_numbers_are_jumpers no)
		(pad "1" smd rect
			(at -0.375 0 90)
			(size 0.45 0.5)
			(layers "F.Cu" "F.Mask" "F.Paste")
			(net "NetC91_1")
		)
		(pad "2" smd rect
			(at 0.375 0 90)
			(size 0.45 0.5)
			(layers "F.Cu" "F.Mask" "F.Paste")
			(net "FTDI_VBUS")
		)
	)
	(footprint "Vault:FP-LTST-C191TBKT-MFG"
		(layer "F.Cu")
		(at 69.8761 52.1162 90)
		(property "Reference" "D3"
			(at -6.771395 0.026921 90)
			(unlocked yes)
			(layer "F.SilkS")
			(effects
				(font
					(size 0.762 0.762)
					(thickness 0.2286)
				)
			)
		)
		(property "Value" "BLUE"
			(at 1.2818 2.452871 90)
			(unlocked yes)
			(layer "F.SilkS")
			(hide yes)
			(effects
				(font
					(size 0.762 0.762)
					(thickness 0.2286)
				)
			)
		)
		(sheetname "USER_IO_STATUS")
		(sheetfile "USER_IO_STATUS.kicad_sch")
		(duplicate_pad_numbers_are_jumpers no)
		(fp_line
			(start -0.85 -0.8)
			(end 0.85 -0.8)
			(stroke
				(width 0.2)
				(type solid)
			)
			(layer "F.SilkS")
		)
		(fp_line
			(start -0.85 0.8)
			(end 0.85 0.8)
			(stroke
				(width 0.2)
				(type solid)
			)
			(layer "F.SilkS")
		)
		(fp_circle
			(center -1.75 0)
			(end -1.625 0)
			(stroke
				(width 0.25)
				(type solid)
			)
			(fill no)
			(layer "F.SilkS")
		)
		(fp_line
			(start 1.25 -0.55)
			(end 1.25 0.55)
			(stroke
				(width 0.2)
				(type solid)
			)
			(layer "F.CrtYd")
		)
		(fp_line
			(start -1.25 -0.55)
			(end 1.25 -0.55)
			(stroke
				(width 0.2)
				(type solid)
			)
			(layer "F.CrtYd")
		)
		(fp_line
			(start -1.25 -0.55)
			(end -1.25 0.55)
			(stroke
				(width 0.2)
				(type solid)
			)
			(layer "F.CrtYd")
		)
		(fp_line
			(start -1.25 0.55)
			(end 1.25 0.55)
			(stroke
				(width 0.2)
				(type solid)
			)
			(layer "F.CrtYd")
		)
		(fp_line
			(start 1.25 -0.55)
			(end 1.25 0.55)
			(stroke
				(width 0.2)
				(type solid)
			)
			(layer "F.Fab")
		)
		(fp_line
			(start -1.25 -0.55)
			(end 1.25 -0.55)
			(stroke
				(width 0.2)
				(type solid)
			)
			(layer "F.Fab")
		)
		(fp_line
			(start -1.25 -0.55)
			(end -1.25 0.55)
			(stroke
				(width 0.2)
				(type solid)
			)
			(layer "F.Fab")
		)
		(fp_line
			(start 0 -0.5)
			(end 0 0.5)
			(stroke
				(width 0.1)
				(type solid)
			)
			(layer "F.Fab")
		)
		(fp_line
			(start -0.5 0)
			(end 0.5 0)
			(stroke
				(width 0.1)
				(type solid)
			)
			(layer "F.Fab")
		)
		(fp_line
			(start -1.25 0.55)
			(end 1.25 0.55)
			(stroke
				(width 0.2)
				(type solid)
			)
			(layer "F.Fab")
		)
		(fp_text user "${REFERENCE}"
			(at 0 0.28424 90)
			(unlocked yes)
			(layer "F.Fab")
			(effects
				(font
					(face "Arial")
					(size 0.63 0.63)
					(thickness 0.1)
				)
				(justify left bottom)
			)
		)
		(pad "1" smd rect
			(at -0.75 0 90)
			(size 0.8 0.8)
			(layers "F.Cu" "F.Mask" "F.Paste")
			(net "NetD3_1")
			(solder_mask_margin 0)
			(solder_paste_margin 0)
		)
		(pad "2" smd rect
			(at 0.75 0 90)
			(size 0.8 0.8)
			(layers "F.Cu" "F.Mask" "F.Paste")
			(net "+3.3V")
			(solder_mask_margin 0)
			(solder_paste_margin 0)
		)
	)
	(footprint "Resistors:RESC2012X50N"
		(layer "F.Cu")
		(at 224.9261 142.2162 -90)
		(property "Reference" "R21"
			(at -1.25 -1.406655 270)
			(unlocked yes)
			(layer "F.SilkS")
			(effects
				(font
					(size 0.762 0.762)
					(thickness 0.2286)
				)
				(justify left bottom)
			)
		)
		(property "Value" "CRCW080533R0FKEA"
			(at -3.179155 -11.2251 0)
			(unlocked yes)
			(layer "F.SilkS")
			(hide yes)
			(effects
				(font
					(size 0.762 0.762)
					(thickness 0.2286)
				)
				(justify left bottom)
			)
		)
		(sheetname "PCIe_JTAG")
		(sheetfile "PCIe_JTAG.kicad_sch")
		(duplicate_pad_numbers_are_jumpers no)
		(fp_line
			(start 0 0.762)
			(end 0 -0.762)
			(stroke
				(width 0.1524)
				(type solid)
			)
			(layer "F.SilkS")
		)
		(pad "1" smd rect
			(at -1 0)
			(size 1.45 0.95)
			(layers "F.Cu" "F.Mask" "F.Paste")
			(net "FPGA_TDI")
		)
		(pad "2" smd rect
			(at 1 0)
			(size 1.45 0.95)
			(layers "F.Cu" "F.Mask" "F.Paste")
			(net "NetR21_2")
		)
	)
	(footprint "Vault:RESC1005X40X25LL05T05"
		(layer "F.Cu")
		(at 80.3261 83.1162)
		(property "Reference" "R109"
			(at -2.8714 -0.073069 0)
			(unlocked yes)
			(layer "F.SilkS")
			(effects
				(font
					(size 0.762 0.762)
					(thickness 0.2286)
				)
			)
		)
		(property "Value" "4.7K_0402"
			(at -2.352802 6.563805 270)
			(unlocked yes)
			(layer "F.SilkS")
			(hide yes)
			(effects
				(font
					(size 1.524 1.524)
					(thickness 0.254)
				)
			)
		)
		(sheetname "USER_IO_STATUS")
		(sheetfile "USER_IO_STATUS.kicad_sch")
		(duplicate_pad_numbers_are_jumpers no)
		(pad "1" smd rect
			(at -0.4 0 90)
			(size 0.45 0.45)
			(layers "F.Cu" "F.Mask" "F.Paste")
			(net "+3.3V")
		)
		(pad "2" smd rect
			(at 0.4 0 90)
			(size 0.45 0.45)
			(layers "F.Cu" "F.Mask" "F.Paste")
			(net "NetR40_2")
		)
	)
	(footprint "Vault:FP-0402-L_1_0_1-W_0_5_0_1-IPC_C"
		(layer "F.Cu")
		(at 202.8261 126.2162 180)
		(property "Reference" "C71"
			(at 3.271395 -4.326921 0)
			(unlocked yes)
			(layer "F.SilkS")
			(effects
				(font
					(size 0.762 0.762)
					(thickness 0.2286)
				)
			)
		)
		(property "Value" "0.1uF_25V_0402"
			(at 9.788415 2.414751 180)
			(unlocked yes)
			(layer "F.SilkS")
			(hide yes)
			(effects
				(font
					(size 0.762 0.762)
					(thickness 0.2286)
				)
			)
		)
		(sheetname "POWER")
		(sheetfile "POWER.kicad_sch")
		(duplicate_pad_numbers_are_jumpers no)
		(fp_line
			(start 0.65607 0.7)
			(end -0.65607 0.7)
			(stroke
				(width 0.2)
				(type solid)
			)
			(layer "F.SilkS")
		)
		(fp_line
			(start 0.65607 -0.7)
			(end -0.65607 -0.7)
			(stroke
				(width 0.2)
				(type solid)
			)
			(layer "F.SilkS")
		)
		(fp_line
			(start 0.75607 0.4)
			(end -0.75607 0.4)
			(stroke
				(width 0.2)
				(type solid)
			)
			(layer "F.CrtYd")
		)
		(fp_line
			(start 0.75607 -0.4)
			(end 0.75607 0.4)
			(stroke
				(width 0.2)
				(type solid)
			)
			(layer "F.CrtYd")
		)
		(fp_line
			(start 0.75607 -0.4)
			(end -0.75607 -0.4)
			(stroke
				(width 0.2)
				(type solid)
			)
			(layer "F.CrtYd")
		)
		(fp_line
			(start -0.75607 -0.4)
			(end -0.75607 0.4)
			(stroke
				(width 0.2)
				(type solid)
			)
			(layer "F.CrtYd")
		)
		(fp_line
			(start 0.75607 0.4)
			(end -0.75607 0.4)
			(stroke
				(width 0.2)
				(type solid)
			)
			(layer "F.Fab")
		)
		(fp_line
			(start 0.75607 -0.4)
			(end 0.75607 0.4)
			(stroke
				(width 0.2)
				(type solid)
			)
			(layer "F.Fab")
		)
		(fp_line
			(start 0.75607 -0.4)
			(end -0.75607 -0.4)
			(stroke
				(width 0.2)
				(type solid)
			)
			(layer "F.Fab")
		)
		(fp_line
			(start 0.5 0)
			(end -0.5 0)
			(stroke
				(width 0.1)
				(type solid)
			)
			(layer "F.Fab")
		)
		(fp_line
			(start 0 -0.5)
			(end 0 0.5)
			(stroke
				(width 0.1)
				(type solid)
			)
			(layer "F.Fab")
		)
		(fp_line
			(start -0.75607 -0.4)
			(end -0.75607 0.4)
			(stroke
				(width 0.2)
				(type solid)
			)
			(layer "F.Fab")
		)
		(fp_text user "${REFERENCE}"
			(at -0.00001 0.09601 180)
			(unlocked yes)
			(layer "F.Fab")
			(effects
				(font
					(face "Arial")
					(size 0.63 0.63)
					(thickness 0.1)
				)
				(justify left bottom)
			)
		)
		(pad "1" smd rect
			(at -0.36554 0 180)
			(size 0.58106 0.51213)
			(layers "F.Cu" "F.Mask" "F.Paste")
			(net "NetC71_1")
			(solder_mask_margin 0)
			(solder_paste_margin 0)
		)
		(pad "2" smd rect
			(at 0.36554 0 180)
			(size 0.58106 0.51213)
			(layers "F.Cu" "F.Mask" "F.Paste")
			(net "GND")
			(solder_mask_margin 0)
			(solder_paste_margin 0)
		)
	)
	(footprint "Vault:FP-MK212BG-MFG"
		(layer "F.Cu")
		(at 75.1261 65.1162 90)
		(property "Reference" "C42"
			(at 0.2286 -1.773079 90)
			(unlocked yes)
			(layer "F.SilkS")
			(effects
				(font
					(size 0.762 0.762)
					(thickness 0.2286)
				)
			)
		)
		(property "Value" "10uF"
			(at -3.240271 2.22164 0)
			(unlocked yes)
			(layer "F.SilkS")
			(hide yes)
			(effects
				(font
					(size 0.762 0.762)
					(thickness 0.2286)
				)
			)
		)
		(sheetname "GPS_IMU_SENSORS")
		(sheetfile "GPS_IMU_SENSORS.kicad_sch")
		(duplicate_pad_numbers_are_jumpers no)
		(fp_line
			(start -0.125 -0.725)
			(end 0.125 -0.725)
			(stroke
				(width 0.2)
				(type solid)
			)
			(layer "F.SilkS")
		)
		(fp_line
			(start -0.125 0.725)
			(end 0.125 0.725)
			(stroke
				(width 0.2)
				(type solid)
			)
			(layer "F.SilkS")
		)
		(fp_line
			(start 1.6 -0.825)
			(end 1.6 0.825)
			(stroke
				(width 0.2)
				(type solid)
			)
			(layer "F.CrtYd")
		)
		(fp_line
			(start -1.6 -0.825)
			(end 1.6 -0.825)
			(stroke
				(width 0.2)
				(type solid)
			)
			(layer "F.CrtYd")
		)
		(fp_line
			(start -1.6 -0.825)
			(end -1.6 0.825)
			(stroke
				(width 0.2)
				(type solid)
			)
			(layer "F.CrtYd")
		)
		(fp_line
			(start -1.6 0.825)
			(end 1.6 0.825)
			(stroke
				(width 0.2)
				(type solid)
			)
			(layer "F.CrtYd")
		)
		(fp_line
			(start 1.6 -0.825)
			(end 1.6 0.825)
			(stroke
				(width 0.2)
				(type solid)
			)
			(layer "F.Fab")
		)
		(fp_line
			(start -1.6 -0.825)
			(end 1.6 -0.825)
			(stroke
				(width 0.2)
				(type solid)
			)
			(layer "F.Fab")
		)
		(fp_line
			(start -1.6 -0.825)
			(end -1.6 0.825)
			(stroke
				(width 0.2)
				(type solid)
			)
			(layer "F.Fab")
		)
		(fp_line
			(start 0 -0.5)
			(end 0 0.5)
			(stroke
				(width 0.1)
				(type solid)
			)
			(layer "F.Fab")
		)
		(fp_line
			(start -0.5 0)
			(end 0.5 0)
			(stroke
				(width 0.1)
				(type solid)
			)
			(layer "F.Fab")
		)
		(fp_line
			(start -1.6 0.825)
			(end 1.6 0.825)
			(stroke
				(width 0.2)
				(type solid)
			)
			(layer "F.Fab")
		)
		(fp_text user "${REFERENCE}"
			(at -0.00001 0.09601 90)
			(unlocked yes)
			(layer "F.Fab")
			(effects
				(font
					(face "Arial")
					(size 0.63 0.63)
					(thickness 0.1)
				)
				(justify left bottom)
			)
		)
		(pad "1" smd rect
			(at -1 0 90)
			(size 1 1.25)
			(layers "F.Cu" "F.Mask" "F.Paste")
			(net "+5.0V")
			(solder_mask_margin 0)
			(solder_paste_margin 0)
		)
		(pad "2" smd rect
			(at 1 0 90)
			(size 1 1.25)
			(layers "F.Cu" "F.Mask" "F.Paste")
			(net "GND")
			(solder_mask_margin 0)
			(solder_paste_margin 0)
		)
	)
	(footprint "Vault:FP-A6H-2102-MFG"
		(layer "F.Cu")
		(at 170.7261 86.8162)
		(property "Reference" "SW1"
			(at 2.328605 4.126921 0)
			(unlocked yes)
			(layer "F.SilkS")
			(effects
				(font
					(size 0.762 0.762)
					(thickness 0.2286)
				)
			)
		)
		(property "Value" "A6H-2102"
			(at 3.998655 6.085071 0)
			(unlocked yes)
			(layer "F.SilkS")
			(hide yes)
			(effects
				(font
					(size 0.762 0.762)
					(thickness 0.2286)
				)
			)
		)
		(sheetname "USBUart_DipSelects")
		(sheetfile "USBUart_DipSelects.kicad_sch")
		(duplicate_pad_numbers_are_jumpers no)
		(fp_line
			(start -1.985 -2.35)
			(end -1.39 -2.35)
			(stroke
				(width 0.2)
				(type solid)
			)
			(layer "F.SilkS")
		)
		(fp_line
			(start -1.985 2.35)
			(end -1.985 -2.35)
			(stroke
				(width 0.2)
				(type solid)
			)
			(layer "F.SilkS")
		)
		(fp_line
			(start -1.985 2.35)
			(end -1.39 2.35)
			(stroke
				(width 0.2)
				(type solid)
			)
			(layer "F.SilkS")
		)
		(fp_line
			(start 1.39 -2.35)
			(end 1.985 -2.35)
			(stroke
				(width 0.2)
				(type solid)
			)
			(layer "F.SilkS")
		)
		(fp_line
			(start 1.39 2.35)
			(end 1.985 2.35)
			(stroke
				(width 0.2)
				(type solid)
			)
			(layer "F.SilkS")
		)
		(fp_line
			(start 1.985 2.35)
			(end 1.985 -2.35)
			(stroke
				(width 0.2)
				(type solid)
			)
			(layer "F.SilkS")
		)
		(fp_circle
			(center -0.635 4.275)
			(end -0.635 4.15)
			(stroke
				(width 0.25)
				(type solid)
			)
			(fill no)
			(layer "F.SilkS")
		)
		(fp_line
			(start -2.085 -3.8)
			(end 2.085 -3.8)
			(stroke
				(width 0.2)
				(type solid)
			)
			(layer "F.CrtYd")
		)
		(fp_line
			(start -2.085 3.8)
			(end -2.085 -3.8)
			(stroke
				(width 0.2)
				(type solid)
			)
			(layer "F.CrtYd")
		)
		(fp_line
			(start -2.085 3.8)
			(end 2.085 3.8)
			(stroke
				(width 0.2)
				(type solid)
			)
			(layer "F.CrtYd")
		)
		(fp_line
			(start 2.085 3.8)
			(end 2.085 -3.8)
			(stroke
				(width 0.2)
				(type solid)
			)
			(layer "F.CrtYd")
		)
		(fp_line
			(start -2.085 -3.8)
			(end 2.085 -3.8)
			(stroke
				(width 0.2)
				(type solid)
			)
			(layer "F.Fab")
		)
		(fp_line
			(start -2.085 3.8)
			(end -2.085 -3.8)
			(stroke
				(width 0.2)
				(type solid)
			)
			(layer "F.Fab")
		)
		(fp_line
			(start -2.085 3.8)
			(end 2.085 3.8)
			(stroke
				(width 0.2)
				(type solid)
			)
			(layer "F.Fab")
		)
		(fp_line
			(start -0.5 0)
			(end 0.5 0)
			(stroke
				(width 0.1)
				(type solid)
			)
			(layer "F.Fab")
		)
		(fp_line
			(start 0 0.5)
			(end 0 -0.5)
			(stroke
				(width 0.1)
				(type solid)
			)
			(layer "F.Fab")
		)
		(fp_line
			(start 2.085 3.8)
			(end 2.085 -3.8)
			(stroke
				(width 0.2)
				(type solid)
			)
			(layer "F.Fab")
		)
		(fp_text user "${REFERENCE}"
			(at -0.00001 0.09602 360)
			(unlocked yes)
			(layer "F.Fab")
			(effects
				(font
					(face "Arial")
					(size 0.63 0.63)
					(thickness 0.1)
				)
				(justify left bottom)
			)
		)
		(pad "1" smd rect
			(at -0.635 3.075)
			(size 0.76 1.25)
			(layers "F.Cu" "F.Mask" "F.Paste")
			(net "GND")
			(solder_mask_margin 0)
			(solder_paste_margin 0)
		)
		(pad "2" smd rect
			(at 0.635 3.075)
			(size 0.76 1.25)
			(layers "F.Cu" "F.Mask" "F.Paste")
			(net "GND")
			(solder_mask_margin 0)
			(solder_paste_margin 0)
		)
		(pad "3" smd rect
			(at 0.635 -3.075)
			(size 0.76 1.25)
			(layers "F.Cu" "F.Mask" "F.Paste")
			(net "DIP_SW_PPS_SEL")
			(solder_mask_margin 0)
			(solder_paste_margin 0)
		)
		(pad "4" smd rect
			(at -0.635 -3.075)
			(size 0.76 1.25)
			(layers "F.Cu" "F.Mask" "F.Paste")
			(net "DIP_SW_UART_SEL")
			(solder_mask_margin 0)
			(solder_paste_margin 0)
		)
	)
	(footprint "Resistors:RESC2012X50N"
		(layer "F.Cu")
		(at 199.31136 143.47763)
		(property "Reference" "R19"
			(at -1.28526 -1.268085 0)
			(unlocked yes)
			(layer "F.SilkS")
			(effects
				(font
					(size 0.762 0.762)
					(thickness 0.2286)
				)
				(justify left bottom)
			)
		)
		(property "Value" "CRCW080533R0FKEA"
			(at -3.0249 -6.429155 0)
			(unlocked yes)
			(layer "F.SilkS")
			(hide yes)
			(effects
				(font
					(size 0.762 0.762)
					(thickness 0.2286)
				)
				(justify left bottom)
			)
		)
		(sheetname "PCIe_JTAG")
		(sheetfile "PCIe_JTAG.kicad_sch")
		(duplicate_pad_numbers_are_jumpers no)
		(fp_line
			(start 0 0.762)
			(end 0 -0.762)
			(stroke
				(width 0.1524)
				(type solid)
			)
			(layer "F.SilkS")
		)
		(pad "1" smd rect
			(at -1 0 90)
			(size 1.45 0.95)
			(layers "F.Cu" "F.Mask" "F.Paste")
			(net "FPGA_TDO")
		)
		(pad "2" smd rect
			(at 1 0 90)
			(size 1.45 0.95)
			(layers "F.Cu" "F.Mask" "F.Paste")
			(net "NetR19_2")
		)
	)
	(footprint "Vault:CAPC1005X55X25LL05T10"
		(layer "F.Cu")
		(at 234.7261 75.0162 -90)
		(property "Reference" "C87"
			(at 0.5286 4.426931 270)
			(unlocked yes)
			(layer "F.SilkS")
			(effects
				(font
					(size 0.762 0.762)
					(thickness 0.2286)
				)
			)
		)
		(property "Value" "47pF_50V_0402"
			(at -2.656031 9.61078 180)
			(unlocked yes)
			(layer "F.SilkS")
			(hide yes)
			(effects
				(font
					(size 0.762 0.762)
					(thickness 0.2286)
				)
			)
		)
		(sheetname "USBUart_DipSelects")
		(sheetfile "USBUart_DipSelects.kicad_sch")
		(duplicate_pad_numbers_are_jumpers no)
		(pad "1" smd rect
			(at -0.39 0)
			(size 0.52 0.56)
			(layers "F.Cu" "F.Mask" "F.Paste")
			(net "GND")
		)
		(pad "2" smd rect
			(at 0.39 0)
			(size 0.52 0.56)
			(layers "F.Cu" "F.Mask" "F.Paste")
			(net "FTDI_USB_R_P")
		)
	)
	(footprint "Vault:FP-C1005-050-0_05-IPC_A"
		(layer "F.Cu")
		(at 232.13262 119.2011)
		(property "Reference" "C81"
			(at 2.522085 0.042021 0)
			(unlocked yes)
			(layer "F.SilkS")
			(effects
				(font
					(size 0.762 0.762)
					(thickness 0.2286)
				)
			)
		)
		(property "Value" "2.2uF_16V_0402"
			(at 9.509005 2.440151 0)
			(unlocked yes)
			(layer "F.SilkS")
			(hide yes)
			(effects
				(font
					(size 0.762 0.762)
					(thickness 0.2286)
				)
			)
		)
		(sheetname "POWER")
		(sheetfile "POWER.kicad_sch")
		(duplicate_pad_numbers_are_jumpers no)
		(fp_line
			(start -0.83624 -0.73624)
			(end 0.83623 -0.73624)
			(stroke
				(width 0.2)
				(type solid)
			)
			(layer "F.SilkS")
		)
		(fp_line
			(start -0.83624 0.73624)
			(end 0.83623 0.73624)
			(stroke
				(width 0.2)
				(type solid)
			)
			(layer "F.SilkS")
		)
		(fp_line
			(start -1.03624 -0.53624)
			(end 1.03623 -0.53624)
			(stroke
				(width 0.2)
				(type solid)
			)
			(layer "F.CrtYd")
		)
		(fp_line
			(start -1.03624 0.53624)
			(end -1.03624 -0.53624)
			(stroke
				(width 0.2)
				(type solid)
			)
			(layer "F.CrtYd")
		)
		(fp_line
			(start -1.03624 0.53624)
			(end 1.03623 0.53624)
			(stroke
				(width 0.2)
				(type solid)
			)
			(layer "F.CrtYd")
		)
		(fp_line
			(start 1.03623 0.53624)
			(end 1.03623 -0.53624)
			(stroke
				(width 0.2)
				(type solid)
			)
			(layer "F.CrtYd")
		)
		(fp_line
			(start -1.03624 -0.53624)
			(end 1.03623 -0.53624)
			(stroke
				(width 0.2)
				(type solid)
			)
			(layer "F.Fab")
		)
		(fp_line
			(start -1.03624 0.53624)
			(end -1.03624 -0.53624)
			(stroke
				(width 0.2)
				(type solid)
			)
			(layer "F.Fab")
		)
		(fp_line
			(start -1.03624 0.53624)
			(end 1.03623 0.53624)
			(stroke
				(width 0.2)
				(type solid)
			)
			(layer "F.Fab")
		)
		(fp_line
			(start -0.5 0)
			(end 0.5 0)
			(stroke
				(width 0.1)
				(type solid)
			)
			(layer "F.Fab")
		)
		(fp_line
			(start 0 0.5)
			(end 0 -0.5)
			(stroke
				(width 0.1)
				(type solid)
			)
			(layer "F.Fab")
		)
		(fp_line
			(start 1.03623 0.53624)
			(end 1.03623 -0.53624)
			(stroke
				(width 0.2)
				(type solid)
			)
			(layer "F.Fab")
		)
		(fp_text user "${REFERENCE}"
			(at -0.00002 0.09602 360)
			(unlocked yes)
			(layer "F.Fab")
			(effects
				(font
					(face "Arial")
					(size 0.63 0.63)
					(thickness 0.1)
				)
				(justify left bottom)
			)
		)
		(pad "1" smd rect
			(at -0.46658 0)
			(size 0.73933 0.67248)
			(layers "F.Cu" "F.Mask" "F.Paste")
			(net "+3.3V")
			(solder_mask_margin 0)
			(solder_paste_margin 0)
		)
		(pad "2" smd rect
			(at 0.46657 0)
			(size 0.73933 0.67248)
			(layers "F.Cu" "F.Mask" "F.Paste")
			(net "GND")
			(solder_mask_margin 0)
			(solder_paste_margin 0)
		)
	)
	(footprint "SA53:SolderSocket"
		(layer "F.Cu")
		(at 131.8261 138.2162 90)
		(property "Reference" "SKT1"
			(at -3.426921 1.2286 0)
			(unlocked yes)
			(layer "F.SilkS")
			(effects
				(font
					(size 0.762 0.762)
					(thickness 0.2286)
				)
			)
		)
		(property "Value" "0332-0-43-80-18-27-10-0"
			(at -2.910071 16.1362 0)
			(unlocked yes)
			(layer "F.SilkS")
			(hide yes)
			(effects
				(font
					(size 0.762 0.762)
					(thickness 0.2286)
				)
			)
		)
		(sheetname "MAC")
		(sheetfile "MAC.kicad_sch")
		(duplicate_pad_numbers_are_jumpers no)
		(pad "1" thru_hole circle
			(at 0 0 90)
			(size 2.54 2.54)
			(drill 2.0066)
			(layers "*.Cu" "*.Mask")
			(remove_unused_layers no)
			(net "MAC_TX")
			(thermal_bridge_angle 90)
		)
	)
	(footprint "Vault:RESC1005X40X25LL05T10"
		(layer "F.Cu")
		(at 127.6261 88.3162 180)
		(property "Reference" "R99"
			(at -0.6286 -0.826931 0)
			(unlocked yes)
			(layer "F.SilkS")
			(effects
				(font
					(size 0.762 0.762)
					(thickness 0.2286)
				)
			)
		)
		(property "Value" "49.9_1%_0402"
			(at -2.579871 8.823665 90)
			(unlocked yes)
			(layer "F.SilkS")
			(hide yes)
			(effects
				(font
					(size 0.762 0.762)
					(thickness 0.2286)
				)
			)
		)
		(sheetname "USBUart_DipSelects")
		(sheetfile "USBUart_DipSelects.kicad_sch")
		(duplicate_pad_numbers_are_jumpers no)
		(pad "1" smd rect
			(at -0.375 0 270)
			(size 0.45 0.5)
			(layers "F.Cu" "F.Mask" "F.Paste")
			(net "FPGA_MAC_PPS_DIFF_IN0")
		)
		(pad "2" smd rect
			(at 0.375 0 270)
			(size 0.45 0.5)
			(layers "F.Cu" "F.Mask" "F.Paste")
			(net "NetR99_2")
		)
	)
	(footprint "Vault:FP-SOD323-MFG"
		(layer "F.Cu")
		(at 220.5261 130.3162)
		(property "Reference" "D22"
			(at -0.2286 1.473069 180)
			(unlocked yes)
			(layer "F.SilkS")
			(effects
				(font
					(size 0.762 0.762)
					(thickness 0.2286)
				)
			)
		)
		(property "Value" "SD103AWS-7-F"
			(at -3.697481 8.341065 270)
			(unlocked yes)
			(layer "F.SilkS")
			(hide yes)
			(effects
				(font
					(size 0.762 0.762)
					(thickness 0.2286)
				)
			)
		)
		(sheetname "POWER")
		(sheetfile "POWER.kicad_sch")
		(duplicate_pad_numbers_are_jumpers no)
		(fp_line
			(start -0.9 -0.7)
			(end 0.9 -0.7)
			(stroke
				(width 0.2)
				(type solid)
			)
			(layer "F.SilkS")
		)
		(fp_line
			(start -0.9 -0.6)
			(end -0.9 -0.7)
			(stroke
				(width 0.2)
				(type solid)
			)
			(layer "F.SilkS")
		)
		(fp_line
			(start -0.9 0.7)
			(end -0.9 0.6)
			(stroke
				(width 0.2)
				(type solid)
			)
			(layer "F.SilkS")
		)
		(fp_line
			(start -0.9 0.7)
			(end 0.9 0.7)
			(stroke
				(width 0.2)
				(type solid)
			)
			(layer "F.SilkS")
		)
		(fp_line
			(start 0.9 -0.6)
			(end 0.9 -0.7)
			(stroke
				(width 0.2)
				(type solid)
			)
			(layer "F.SilkS")
		)
		(fp_line
			(start 0.9 0.7)
			(end 0.9 0.6)
			(stroke
				(width 0.2)
				(type solid)
			)
			(layer "F.SilkS")
		)
		(fp_circle
			(center -1.9 0)
			(end -1.9 -0.125)
			(stroke
				(width 0.25)
				(type solid)
			)
			(fill no)
			(layer "F.SilkS")
		)
		(fp_line
			(start -1.45 -0.8)
			(end 1.45 -0.8)
			(stroke
				(width 0.2)
				(type solid)
			)
			(layer "F.CrtYd")
		)
		(fp_line
			(start -1.45 0.8)
			(end -1.45 -0.8)
			(stroke
				(width 0.2)
				(type solid)
			)
			(layer "F.CrtYd")
		)
		(fp_line
			(start -1.45 0.8)
			(end 1.45 0.8)
			(stroke
				(width 0.2)
				(type solid)
			)
			(layer "F.CrtYd")
		)
		(fp_line
			(start 1.45 0.8)
			(end 1.45 -0.8)
			(stroke
				(width 0.2)
				(type solid)
			)
			(layer "F.CrtYd")
		)
		(fp_line
			(start -1.45 -0.8)
			(end 1.45 -0.8)
			(stroke
				(width 0.2)
				(type solid)
			)
			(layer "F.Fab")
		)
		(fp_line
			(start -1.45 0.8)
			(end -1.45 -0.8)
			(stroke
				(width 0.2)
				(type solid)
			)
			(layer "F.Fab")
		)
		(fp_line
			(start -1.45 0.8)
			(end 1.45 0.8)
			(stroke
				(width 0.2)
				(type solid)
			)
			(layer "F.Fab")
		)
		(fp_line
			(start -0.5 0)
			(end 0.5 0)
			(stroke
				(width 0.1)
				(type solid)
			)
			(layer "F.Fab")
		)
		(fp_line
			(start 0 0.5)
			(end 0 -0.5)
			(stroke
				(width 0.1)
				(type solid)
			)
			(layer "F.Fab")
		)
		(fp_line
			(start 1.45 0.8)
			(end 1.45 -0.8)
			(stroke
				(width 0.2)
				(type solid)
			)
			(layer "F.Fab")
		)
		(fp_text user "${REFERENCE}"
			(at -0.00001 0.10711 360)
			(unlocked yes)
			(layer "F.Fab")
			(effects
				(font
					(face "Arial")
					(size 0.63 0.63)
					(thickness 0.1)
				)
				(justify left bottom)
			)
		)
		(pad "1" smd rect
			(at -1.055 0)
			(size 0.59 0.45)
			(layers "F.Cu" "F.Mask" "F.Paste")
			(net "NetC68_1")
			(solder_mask_margin 0)
			(solder_paste_margin 0)
		)
		(pad "2" smd rect
			(at 1.055 0)
			(size 0.59 0.45)
			(layers "F.Cu" "F.Mask" "F.Paste")
			(net "P3V3_PVDD")
			(solder_mask_margin 0)
			(solder_paste_margin 0)
		)
	)
	(footprint "Vault:FP-CC0402-MFG"
		(layer "F.Cu")
		(at 233.2261 79.1162 180)
		(property "Reference" "C86"
			(at -0.2286 1.573069 0)
			(unlocked yes)
			(layer "F.SilkS")
			(effects
				(font
					(size 0.762 0.762)
					(thickness 0.2286)
				)
			)
		)
		(property "Value" "10nF_50V_0402"
			(at -2.592551 9.22982 90)
			(unlocked yes)
			(layer "F.SilkS")
			(hide yes)
			(effects
				(font
					(size 0.762 0.762)
					(thickness 0.2286)
				)
			)
		)
		(sheetname "USBUart_DipSelects")
		(sheetfile "USBUart_DipSelects.kicad_sch")
		(duplicate_pad_numbers_are_jumpers no)
		(fp_line
			(start 0.525 -0.675)
			(end -0.525 -0.675)
			(stroke
				(width 0.2)
				(type solid)
			)
			(layer "F.SilkS")
		)
		(fp_line
			(start 0.51967 0.68067)
			(end -0.53033 0.68067)
			(stroke
				(width 0.2)
				(type solid)
			)
			(layer "F.SilkS")
		)
		(fp_line
			(start 0.875 0.475)
			(end -0.875 0.475)
			(stroke
				(width 0.2)
				(type solid)
			)
			(layer "F.CrtYd")
		)
		(fp_line
			(start 0.875 -0.475)
			(end 0.875 0.475)
			(stroke
				(width 0.2)
				(type solid)
			)
			(layer "F.CrtYd")
		)
		(fp_line
			(start 0.875 -0.475)
			(end -0.875 -0.475)
			(stroke
				(width 0.2)
				(type solid)
			)
			(layer "F.CrtYd")
		)
		(fp_line
			(start -0.875 -0.475)
			(end -0.875 0.475)
			(stroke
				(width 0.2)
				(type solid)
			)
			(layer "F.CrtYd")
		)
		(fp_line
			(start 0.875 0.475)
			(end -0.875 0.475)
			(stroke
				(width 0.2)
				(type solid)
			)
			(layer "F.Fab")
		)
		(fp_line
			(start 0.875 -0.475)
			(end 0.875 0.475)
			(stroke
				(width 0.2)
				(type solid)
			)
			(layer "F.Fab")
		)
		(fp_line
			(start 0.875 -0.475)
			(end -0.875 -0.475)
			(stroke
				(width 0.2)
				(type solid)
			)
			(layer "F.Fab")
		)
		(fp_line
			(start 0.5 0)
			(end -0.5 0)
			(stroke
				(width 0.1)
				(type solid)
			)
			(layer "F.Fab")
		)
		(fp_line
			(start 0 -0.5)
			(end 0 0.5)
			(stroke
				(width 0.1)
				(type solid)
			)
			(layer "F.Fab")
		)
		(fp_line
			(start -0.875 -0.475)
			(end -0.875 0.475)
			(stroke
				(width 0.2)
				(type solid)
			)
			(layer "F.Fab")
		)
		(fp_text user "${REFERENCE}"
			(at -0.00001 0.09602 180)
			(unlocked yes)
			(layer "F.Fab")
			(effects
				(font
					(face "Arial")
					(size 0.63 0.63)
					(thickness 0.1)
				)
				(justify left bottom)
			)
		)
		(pad "1" smd rect
			(at -0.5 0 180)
			(size 0.5 0.5)
			(layers "F.Cu" "F.Mask" "F.Paste")
			(net "USB_VBUS")
			(solder_mask_margin 0)
			(solder_paste_margin 0)
		)
		(pad "2" smd rect
			(at 0.5 0 180)
			(size 0.5 0.5)
			(layers "F.Cu" "F.Mask" "F.Paste")
			(net "GND")
			(solder_mask_margin 0)
			(solder_paste_margin 0)
		)
	)
	(footprint "Vault:RESC1005X40X25LL05T10"
		(layer "F.Cu")
		(at 123.8261 86.2162 180)
		(property "Reference" "R105"
			(at 0.2714 7.273069 0)
			(unlocked yes)
			(layer "F.SilkS")
			(effects
				(font
					(size 0.762 0.762)
					(thickness 0.2286)
				)
			)
		)
		(property "Value" "DNI_49.9_1%_0402"
			(at -2.579871 11.74372 90)
			(unlocked yes)
			(layer "F.SilkS")
			(hide yes)
			(effects
				(font
					(size 0.762 0.762)
					(thickness 0.2286)
				)
			)
		)
		(sheetname "USBUart_DipSelects")
		(sheetfile "USBUart_DipSelects.kicad_sch")
		(duplicate_pad_numbers_are_jumpers no)
		(pad "1" smd rect
			(at -0.375 0 270)
			(size 0.45 0.5)
			(layers "F.Cu" "F.Mask" "F.Paste")
			(net "FPGA_MAC_PPS_OUT-")
		)
		(pad "2" smd rect
			(at 0.375 0 270)
			(size 0.45 0.5)
			(layers "F.Cu" "F.Mask" "F.Paste")
			(net "FPGA_MAC_PPSDIFF_OUT")
		)
	)
	(footprint "IS32FL3207:IS32FL3207"
		(layer "F.Cu")
		(at 89.3761 87.1162)
		(property "Reference" "U6"
			(at -2.271395 -3.723079 0)
			(unlocked yes)
			(layer "F.SilkS")
			(effects
				(font
					(size 0.762 0.762)
					(thickness 0.2286)
				)
			)
		)
		(property "Value" "IS32FL3207"
			(at 4.17596 4.662671 0)
			(unlocked yes)
			(layer "F.SilkS")
			(hide yes)
			(effects
				(font
					(size 0.762 0.762)
					(thickness 0.2286)
				)
			)
		)
		(sheetname "USER_IO_STATUS")
		(sheetfile "USER_IO_STATUS.kicad_sch")
		(duplicate_pad_numbers_are_jumpers no)
		(fp_line
			(start -2.65 -2.65)
			(end -2.05 -2.65)
			(stroke
				(width 0.2)
				(type solid)
			)
			(layer "F.SilkS")
		)
		(fp_line
			(start -2.65 -2.05)
			(end -2.65 -2.65)
			(stroke
				(width 0.2)
				(type solid)
			)
			(layer "F.SilkS")
		)
		(fp_line
			(start -2.65 2.65)
			(end -2.65 2.05)
			(stroke
				(width 0.2)
				(type solid)
			)
			(layer "F.SilkS")
		)
		(fp_line
			(start -2.65 2.65)
			(end -2.05 2.65)
			(stroke
				(width 0.2)
				(type solid)
			)
			(layer "F.SilkS")
		)
		(fp_line
			(start 2.05 -2.65)
			(end 2.65 -2.65)
			(stroke
				(width 0.2)
				(type solid)
			)
			(layer "F.SilkS")
		)
		(fp_line
			(start 2.05 2.65)
			(end 2.65 2.65)
			(stroke
				(width 0.2)
				(type solid)
			)
			(layer "F.SilkS")
		)
		(fp_line
			(start 2.65 -2.05)
			(end 2.65 -2.65)
			(stroke
				(width 0.2)
				(type solid)
			)
			(layer "F.SilkS")
		)
		(fp_line
			(start 2.65 2.65)
			(end 2.65 2.05)
			(stroke
				(width 0.2)
				(type solid)
			)
			(layer "F.SilkS")
		)
		(fp_circle
			(center -3.3 -2.5)
			(end -3.3 -2.625)
			(stroke
				(width 0.25)
				(type solid)
			)
			(fill no)
			(layer "F.SilkS")
		)
		(pad "1" smd rect
			(at -2.325 -1.5 90)
			(size 0.26 0.9)
			(layers "F.Cu" "F.Mask" "F.Paste")
			(net "NetR40_2")
		)
		(pad "2" smd rect
			(at -2.325 -1 90)
			(size 0.26 0.9)
			(layers "F.Cu" "F.Mask" "F.Paste")
			(net "NetR108_2")
		)
		(pad "3" smd rect
			(at -2.325 -0.5 90)
			(size 0.26 0.9)
			(layers "F.Cu" "F.Mask" "F.Paste")
			(net "+3.3V")
		)
		(pad "4" smd rect
			(at -2.325 0 90)
			(size 0.26 0.9)
			(layers "F.Cu" "F.Mask" "F.Paste")
			(net "GND")
		)
		(pad "5" smd rect
			(at -2.325 0.5 90)
			(size 0.26 0.9)
			(layers "F.Cu" "F.Mask" "F.Paste")
			(net "NetR41_2")
		)
		(pad "6" smd rect
			(at -2.325 1 90)
			(size 0.26 0.9)
			(layers "F.Cu" "F.Mask" "F.Paste")
			(net "SDA")
		)
		(pad "7" smd rect
			(at -2.325 1.5 90)
			(size 0.26 0.9)
			(layers "F.Cu" "F.Mask" "F.Paste")
			(net "SCL")
		)
		(pad "8" smd rect
			(at -1.5 2.325)
			(size 0.26 0.9)
			(layers "F.Cu" "F.Mask" "F.Paste")
			(net "NetD13_4")
		)
		(pad "9" smd rect
			(at -1 2.325)
			(size 0.26 0.9)
			(layers "F.Cu" "F.Mask" "F.Paste")
			(net "NetD13_3")
		)
		(pad "10" smd rect
			(at -0.5 2.325)
			(size 0.26 0.9)
			(layers "F.Cu" "F.Mask" "F.Paste")
			(net "NetD13_2")
		)
		(pad "11" smd rect
			(at 0 2.325)
			(size 0.26 0.9)
			(layers "F.Cu" "F.Mask" "F.Paste")
			(net "GND")
		)
		(pad "12" smd rect
			(at 0.5 2.325)
			(size 0.26 0.9)
			(layers "F.Cu" "F.Mask" "F.Paste")
			(net "NetD14_4")
		)
		(pad "13" smd rect
			(at 1 2.325)
			(size 0.26 0.9)
			(layers "F.Cu" "F.Mask" "F.Paste")
			(net "NetD14_3")
		)
		(pad "14" smd rect
			(at 1.5 2.325)
			(size 0.26 0.9)
			(layers "F.Cu" "F.Mask" "F.Paste")
			(net "NetD14_2")
		)
		(pad "15" smd rect
			(at 2.325 1.5 90)
			(size 0.26 0.9)
			(layers "F.Cu" "F.Mask" "F.Paste")
			(net "NetD15_4")
		)
		(pad "16" smd rect
			(at 2.325 1 90)
			(size 0.26 0.9)
			(layers "F.Cu" "F.Mask" "F.Paste")
			(net "NetD15_3")
		)
		(pad "17" smd rect
			(at 2.325 0.5 90)
			(size 0.26 0.9)
			(layers "F.Cu" "F.Mask" "F.Paste")
			(net "NetD15_2")
		)
		(pad "18" smd rect
			(at 2.325 0 90)
			(size 0.26 0.9)
			(layers "F.Cu" "F.Mask" "F.Paste")
			(net "GND")
		)
		(pad "19" smd rect
			(at 2.325 -0.5 90)
			(size 0.26 0.9)
			(layers "F.Cu" "F.Mask" "F.Paste")
			(net "NetD16_4")
		)
		(pad "20" smd rect
			(at 2.325 -1 90)
			(size 0.26 0.9)
			(layers "F.Cu" "F.Mask" "F.Paste")
			(net "NetD16_3")
		)
		(pad "21" smd rect
			(at 2.325 -1.5 90)
			(size 0.26 0.9)
			(layers "F.Cu" "F.Mask" "F.Paste")
			(net "NetD16_2")
		)
		(pad "22" smd rect
			(at 1.5 -2.325)
			(size 0.26 0.9)
			(layers "F.Cu" "F.Mask" "F.Paste")
			(net "NetD17_4")
		)
		(pad "23" smd rect
			(at 1 -2.325)
			(size 0.26 0.9)
			(layers "F.Cu" "F.Mask" "F.Paste")
			(net "NetD17_3")
		)
		(pad "24" smd rect
			(at 0.5 -2.325)
			(size 0.26 0.9)
			(layers "F.Cu" "F.Mask" "F.Paste")
			(net "NetD17_2")
		)
		(pad "25" smd rect
			(at 0 -2.325)
			(size 0.26 0.9)
			(layers "F.Cu" "F.Mask" "F.Paste")
			(net "GND")
		)
		(pad "26" smd rect
			(at -0.5 -2.325)
			(size 0.26 0.9)
			(layers "F.Cu" "F.Mask" "F.Paste")
			(net "NetD18_4")
		)
		(pad "27" smd rect
			(at -1 -2.325)
			(size 0.26 0.9)
			(layers "F.Cu" "F.Mask" "F.Paste")
			(net "NetD18_3")
		)
		(pad "28" smd rect
			(at -1.5 -2.325)
			(size 0.26 0.9)
			(layers "F.Cu" "F.Mask" "F.Paste")
			(net "NetD18_2")
		)
		(pad "29" smd rect
			(at 0 0)
			(size 3.25 3.25)
			(layers "F.Cu" "F.Mask" "F.Paste")
			(net "GND")
		)
	)
	(footprint "Vault:FP-DO-214AB_SMC_J-Bend-MFG"
		(layer "F.Cu")
		(at 206.6261 98.1162 180)
		(property "Reference" "D23"
			(at 6.208529 -0.80076 90)
			(unlocked yes)
			(layer "F.SilkS")
			(effects
				(font
					(size 0.762 0.762)
					(thickness 0.2286)
				)
			)
		)
		(property "Value" "SMDJ12A"
			(at -6.847071 2.1193 90)
			(unlocked yes)
			(layer "F.SilkS")
			(hide yes)
			(effects
				(font
					(size 0.762 0.762)
					(thickness 0.2286)
				)
			)
		)
		(sheetname "POWER")
		(sheetfile "POWER.kicad_sch")
		(duplicate_pad_numbers_are_jumpers no)
		(fp_line
			(start 3.555 3.11)
			(end -3.555 3.11)
			(stroke
				(width 0.2)
				(type solid)
			)
			(layer "F.SilkS")
		)
		(fp_line
			(start 3.555 2.025)
			(end 3.555 3.11)
			(stroke
				(width 0.2)
				(type solid)
			)
			(layer "F.SilkS")
		)
		(fp_line
			(start 3.555 -3.11)
			(end 3.555 -2.025)
			(stroke
				(width 0.2)
				(type solid)
			)
			(layer "F.SilkS")
		)
		(fp_line
			(start 3.555 -3.11)
			(end -3.555 -3.11)
			(stroke
				(width 0.2)
				(type solid)
			)
			(layer "F.SilkS")
		)
		(fp_line
			(start -3.555 2.025)
			(end -3.555 3.11)
			(stroke
				(width 0.2)
				(type solid)
			)
			(layer "F.SilkS")
		)
		(fp_line
			(start -3.555 -3.11)
			(end -3.555 -2.025)
			(stroke
				(width 0.2)
				(type solid)
			)
			(layer "F.SilkS")
		)
		(fp_circle
			(center -5.05 0)
			(end -5.05 0.125)
			(stroke
				(width 0.25)
				(type solid)
			)
			(fill no)
			(layer "F.SilkS")
		)
		(fp_line
			(start 4.6 3.21)
			(end -4.6 3.21)
			(stroke
				(width 0.2)
				(type solid)
			)
			(layer "F.CrtYd")
		)
		(fp_line
			(start 4.6 -3.21)
			(end 4.6 3.21)
			(stroke
				(width 0.2)
				(type solid)
			)
			(layer "F.CrtYd")
		)
		(fp_line
			(start 4.6 -3.21)
			(end -4.6 -3.21)
			(stroke
				(width 0.2)
				(type solid)
			)
			(layer "F.CrtYd")
		)
		(fp_line
			(start -4.6 -3.21)
			(end -4.6 3.21)
			(stroke
				(width 0.2)
				(type solid)
			)
			(layer "F.CrtYd")
		)
		(fp_line
			(start 4.6 3.21)
			(end -4.6 3.21)
			(stroke
				(width 0.2)
				(type solid)
			)
			(layer "F.Fab")
		)
		(fp_line
			(start 4.6 -3.21)
			(end 4.6 3.21)
			(stroke
				(width 0.2)
				(type solid)
			)
			(layer "F.Fab")
		)
		(fp_line
			(start 4.6 -3.21)
			(end -4.6 -3.21)
			(stroke
				(width 0.2)
				(type solid)
			)
			(layer "F.Fab")
		)
		(fp_line
			(start 0.5 0)
			(end -0.5 0)
			(stroke
				(width 0.1)
				(type solid)
			)
			(layer "F.Fab")
		)
		(fp_line
			(start 0 -0.5)
			(end 0 0.5)
			(stroke
				(width 0.1)
				(type solid)
			)
			(layer "F.Fab")
		)
		(fp_line
			(start -4.6 -3.21)
			(end -4.6 3.21)
			(stroke
				(width 0.2)
				(type solid)
			)
			(layer "F.Fab")
		)
		(fp_text user "${REFERENCE}"
			(at -0.00001 0.09601 180)
			(unlocked yes)
			(layer "F.Fab")
			(effects
				(font
					(face "Arial")
					(size 0.63 0.63)
					(thickness 0.1)
				)
				(justify left bottom)
			)
		)
		(pad "1" smd rect
			(at -3.3 0 180)
			(size 2.4 3.3)
			(layers "F.Cu" "F.Mask" "F.Paste")
			(net "+12V_SENS")
			(solder_mask_margin 0)
			(solder_paste_margin 0)
		)
		(pad "2" smd rect
			(at 3.3 0 180)
			(size 2.4 3.3)
			(layers "F.Cu" "F.Mask" "F.Paste")
			(net "GND")
			(solder_mask_margin 0)
			(solder_paste_margin 0)
		)
	)
	(footprint "Vault:RESC1005X40X25LL05T10"
		(layer "F.Cu")
		(at 125.1261 84.1162)
		(property "Reference" "R96"
			(at 0.0286 -2.773069 0)
			(unlocked yes)
			(layer "F.SilkS")
			(effects
				(font
					(size 0.762 0.762)
					(thickness 0.2286)
				)
			)
		)
		(property "Value" "49.9_1%_0402"
			(at -2.579871 8.823665 270)
			(unlocked yes)
			(layer "F.SilkS")
			(hide yes)
			(effects
				(font
					(size 0.762 0.762)
					(thickness 0.2286)
				)
			)
		)
		(sheetname "USBUart_DipSelects")
		(sheetfile "USBUart_DipSelects.kicad_sch")
		(duplicate_pad_numbers_are_jumpers no)
		(pad "1" smd rect
			(at -0.375 0 90)
			(size 0.45 0.5)
			(layers "F.Cu" "F.Mask" "F.Paste")
			(net "MAC_PPS_OUT")
		)
		(pad "2" smd rect
			(at 0.375 0 90)
			(size 0.45 0.5)
			(layers "F.Cu" "F.Mask" "F.Paste")
			(net "NetR96_2")
		)
	)
	(footprint "Vault:FP-T495D107K016ATE125-MFG"
		(layer "F.Cu")
		(at 219.9261 103.7162 180)
		(property "Reference" "C10"
			(at -4.3 -0.993345 0)
			(unlocked yes)
			(layer "F.SilkS")
			(effects
				(font
					(size 0.762 0.762)
					(thickness 0.2286)
				)
				(justify left bottom)
			)
		)
		(property "Value" "100uF_16V_2917"
			(at 2.5927 -16.320035 0)
			(unlocked yes)
			(layer "F.SilkS")
			(hide yes)
			(effects
				(font
					(size 0.762 0.762)
					(thickness 0.2286)
				)
				(justify left bottom)
			)
		)
		(sheetname "POWER")
		(sheetfile "POWER.kicad_sch")
		(duplicate_pad_numbers_are_jumpers no)
		(fp_line
			(start 5 0)
			(end 4.4 0)
			(stroke
				(width 0.2)
				(type solid)
			)
			(layer "F.SilkS")
		)
		(fp_line
			(start 4.7 -0.3)
			(end 4.7 0.3)
			(stroke
				(width 0.2)
				(type solid)
			)
			(layer "F.SilkS")
		)
		(fp_line
			(start 3.8 2.3)
			(end -3.8 2.3)
			(stroke
				(width 0.2)
				(type solid)
			)
			(layer "F.SilkS")
		)
		(fp_line
			(start 3.8 1.54)
			(end 3.8 2.3)
			(stroke
				(width 0.2)
				(type solid)
			)
			(layer "F.SilkS")
		)
		(fp_line
			(start 3.8 -2.3)
			(end 3.8 -1.54)
			(stroke
				(width 0.2)
				(type solid)
			)
			(layer "F.SilkS")
		)
		(fp_line
			(start 3.8 -2.3)
			(end -3.8 -2.3)
			(stroke
				(width 0.2)
				(type solid)
			)
			(layer "F.SilkS")
		)
		(fp_line
			(start -3.8 1.54)
			(end -3.8 2.3)
			(stroke
				(width 0.2)
				(type solid)
			)
			(layer "F.SilkS")
		)
		(fp_line
			(start -3.8 -2.3)
			(end -3.8 -1.54)
			(stroke
				(width 0.2)
				(type solid)
			)
			(layer "F.SilkS")
		)
		(fp_line
			(start 4.105 2.4)
			(end -4.105 2.4)
			(stroke
				(width 0.2)
				(type solid)
			)
			(layer "F.CrtYd")
		)
		(fp_line
			(start 4.105 -2.4)
			(end 4.105 2.4)
			(stroke
				(width 0.2)
				(type solid)
			)
			(layer "F.CrtYd")
		)
		(fp_line
			(start 4.105 -2.4)
			(end -4.105 -2.4)
			(stroke
				(width 0.2)
				(type solid)
			)
			(layer "F.CrtYd")
		)
		(fp_line
			(start -4.105 -2.4)
			(end -4.105 2.4)
			(stroke
				(width 0.2)
				(type solid)
			)
			(layer "F.CrtYd")
		)
		(fp_line
			(start 4.105 2.4)
			(end -4.105 2.4)
			(stroke
				(width 0.2)
				(type solid)
			)
			(layer "F.Fab")
		)
		(fp_line
			(start 4.105 -2.4)
			(end 4.105 2.4)
			(stroke
				(width 0.2)
				(type solid)
			)
			(layer "F.Fab")
		)
		(fp_line
			(start 4.105 -2.4)
			(end -4.105 -2.4)
			(stroke
				(width 0.2)
				(type solid)
			)
			(layer "F.Fab")
		)
		(fp_line
			(start 0.5 0)
			(end -0.5 0)
			(stroke
				(width 0.1)
				(type solid)
			)
			(layer "F.Fab")
		)
		(fp_line
			(start 0 -0.5)
			(end 0 0.5)
			(stroke
				(width 0.1)
				(type solid)
			)
			(layer "F.Fab")
		)
		(fp_line
			(start -4.105 -2.4)
			(end -4.105 2.4)
			(stroke
				(width 0.2)
				(type solid)
			)
			(layer "F.Fab")
		)
		(fp_text user "${REFERENCE}"
			(at 0 0.28425 180)
			(unlocked yes)
			(layer "F.Fab")
			(effects
				(font
					(face "Arial")
					(size 0.63 0.63)
					(thickness 0.1)
				)
				(justify left bottom)
			)
		)
		(pad "1" smd rect
			(at -3.01 0 180)
			(size 1.99 2.33)
			(layers "F.Cu" "F.Mask" "F.Paste")
			(net "GND")
			(solder_mask_margin 0)
			(solder_paste_margin 0)
		)
		(pad "2" smd rect
			(at 3.01 0 180)
			(size 1.99 2.33)
			(layers "F.Cu" "F.Mask" "F.Paste")
			(net "+12V")
			(solder_mask_margin 0)
			(solder_paste_margin 0)
		)
	)
	(footprint "Vault:CAPC1608X87X45ML20T05"
		(layer "F.Cu")
		(at 80.3761 98.8662 -90)
		(property "Reference" "C26"
			(at 2.7714 -0.026931 90)
			(unlocked yes)
			(layer "F.SilkS")
			(effects
				(font
					(size 0.762 0.762)
					(thickness 0.2286)
				)
			)
		)
		(property "Value" "0.1uF"
			(at 2.069025 2.630671 270)
			(unlocked yes)
			(layer "F.SilkS")
			(hide yes)
			(effects
				(font
					(size 0.762 0.762)
					(thickness 0.2286)
				)
			)
		)
		(sheetname "USER_IO")
		(sheetfile "USER_IO.kicad_sch")
		(duplicate_pad_numbers_are_jumpers no)
		(pad "1" smd rect
			(at -0.7 0)
			(size 1.1 1.05)
			(layers "F.Cu" "F.Mask" "F.Paste")
			(net "+3.3V")
		)
		(pad "2" smd rect
			(at 0.7 0)
			(size 1.1 1.05)
			(layers "F.Cu" "F.Mask" "F.Paste")
			(net "GND")
		)
	)
	(footprint "Vault:RESC1005X40X25NL05T10"
		(layer "F.Cu")
		(at 206.9261 105.8162 90)
		(property "Reference" "R61"
			(at 2.428605 0.226921 90)
			(unlocked yes)
			(layer "F.SilkS")
			(effects
				(font
					(size 0.762 0.762)
					(thickness 0.2286)
				)
			)
		)
		(property "Value" "2.49K_1%_0402"
			(at -2.732271 9.53462 0)
			(unlocked yes)
			(layer "F.SilkS")
			(hide yes)
			(effects
				(font
					(size 0.762 0.762)
					(thickness 0.2286)
				)
			)
		)
		(sheetname "POWER")
		(sheetfile "POWER.kicad_sch")
		(duplicate_pad_numbers_are_jumpers no)
		(pad "1" smd rect
			(at -0.425 0 180)
			(size 0.55 0.6)
			(layers "F.Cu" "F.Mask" "F.Paste")
			(net "P5V_FB")
		)
		(pad "2" smd rect
			(at 0.425 0 180)
			(size 0.55 0.6)
			(layers "F.Cu" "F.Mask" "F.Paste")
			(net "P5V_SENSE")
		)
	)
	(footprint "Vault:FP-LTST-C191TBKT-MFG"
		(layer "F.Cu")
		(at 73.3761 52.1162 90)
		(property "Reference" "D10"
			(at -6.5214 0.026921 90)
			(unlocked yes)
			(layer "F.SilkS")
			(effects
				(font
					(size 0.762 0.762)
					(thickness 0.2286)
				)
			)
		)
		(property "Value" "BLUE"
			(at 1.2818 2.452871 90)
			(unlocked yes)
			(layer "F.SilkS")
			(hide yes)
			(effects
				(font
					(size 0.762 0.762)
					(thickness 0.2286)
				)
			)
		)
		(sheetname "USER_IO_STATUS")
		(sheetfile "USER_IO_STATUS.kicad_sch")
		(duplicate_pad_numbers_are_jumpers no)
		(fp_line
			(start -0.85 -0.8)
			(end 0.85 -0.8)
			(stroke
				(width 0.2)
				(type solid)
			)
			(layer "F.SilkS")
		)
		(fp_line
			(start -0.85 0.8)
			(end 0.85 0.8)
			(stroke
				(width 0.2)
				(type solid)
			)
			(layer "F.SilkS")
		)
		(fp_circle
			(center -1.75 0)
			(end -1.625 0)
			(stroke
				(width 0.25)
				(type solid)
			)
			(fill no)
			(layer "F.SilkS")
		)
		(fp_line
			(start 1.25 -0.55)
			(end 1.25 0.55)
			(stroke
				(width 0.2)
				(type solid)
			)
			(layer "F.CrtYd")
		)
		(fp_line
			(start -1.25 -0.55)
			(end 1.25 -0.55)
			(stroke
				(width 0.2)
				(type solid)
			)
			(layer "F.CrtYd")
		)
		(fp_line
			(start -1.25 -0.55)
			(end -1.25 0.55)
			(stroke
				(width 0.2)
				(type solid)
			)
			(layer "F.CrtYd")
		)
		(fp_line
			(start -1.25 0.55)
			(end 1.25 0.55)
			(stroke
				(width 0.2)
				(type solid)
			)
			(layer "F.CrtYd")
		)
		(fp_line
			(start 1.25 -0.55)
			(end 1.25 0.55)
			(stroke
				(width 0.2)
				(type solid)
			)
			(layer "F.Fab")
		)
		(fp_line
			(start -1.25 -0.55)
			(end 1.25 -0.55)
			(stroke
				(width 0.2)
				(type solid)
			)
			(layer "F.Fab")
		)
		(fp_line
			(start -1.25 -0.55)
			(end -1.25 0.55)
			(stroke
				(width 0.2)
				(type solid)
			)
			(layer "F.Fab")
		)
		(fp_line
			(start 0 -0.5)
			(end 0 0.5)
			(stroke
				(width 0.1)
				(type solid)
			)
			(layer "F.Fab")
		)
		(fp_line
			(start -0.5 0)
			(end 0.5 0)
			(stroke
				(width 0.1)
				(type solid)
			)
			(layer "F.Fab")
		)
		(fp_line
			(start -1.25 0.55)
			(end 1.25 0.55)
			(stroke
				(width 0.2)
				(type solid)
			)
			(layer "F.Fab")
		)
		(pad "1" smd rect
			(at -0.75 0 90)
			(size 0.8 0.8)
			(layers "F.Cu" "F.Mask" "F.Paste")
			(net "NetD10_1")
			(solder_mask_margin 0)
			(solder_paste_margin 0)
		)
		(pad "2" smd rect
			(at 0.75 0 90)
			(size 0.8 0.8)
			(layers "F.Cu" "F.Mask" "F.Paste")
			(net "+3.3V")
			(solder_mask_margin 0)
			(solder_paste_margin 0)
		)
	)
	(footprint "FPGA_CONN:SingleFPGAConn"
		(layer "F.Cu")
		(at 197.33851 104.56486 180)
		(property "Reference" "J34"
			(at 1.54101 -22.624409 180)
			(unlocked yes)
			(layer "F.SilkS")
			(effects
				(font
					(size 0.762 0.762)
					(thickness 0.2286)
				)
			)
		)
		(property "Value" "Single FPGA Conn"
			(at 9.25452 3.621231 180)
			(unlocked yes)
			(layer "F.SilkS")
			(hide yes)
			(effects
				(font
					(size 0.762 0.762)
					(thickness 0.2286)
				)
			)
		)
		(sheetname "FPGA")
		(sheetfile "FPGA.kicad_sch")
		(duplicate_pad_numbers_are_jumpers no)
		(fp_line
			(start 2 0.70003)
			(end 1.40005 1.24994)
			(stroke
				(width 0.15011)
				(type solid)
			)
			(layer "F.SilkS")
		)
		(fp_line
			(start 2 0.03302)
			(end 2 0.70003)
			(stroke
				(width 0.15011)
				(type solid)
			)
			(layer "F.SilkS")
		)
		(fp_line
			(start 2 -20.69998)
			(end 2 -20.03298)
			(stroke
				(width 0.15011)
				(type solid)
			)
			(layer "F.SilkS")
		)
		(fp_line
			(start 2 -20.69998)
			(end 1.40005 -21.24989)
			(stroke
				(width 0.15011)
				(type solid)
			)
			(layer "F.SilkS")
		)
		(fp_line
			(start 1.40005 1.24994)
			(end -1.40005 1.24994)
			(stroke
				(width 0.15011)
				(type solid)
			)
			(layer "F.SilkS")
		)
		(fp_line
			(start 1.40005 -21.24989)
			(end -1.40005 -21.24989)
			(stroke
				(width 0.15011)
				(type solid)
			)
			(layer "F.SilkS")
		)
		(fp_line
			(start -1.40005 0.70003)
			(end -1.40005 1.24994)
			(stroke
				(width 0.15011)
				(type solid)
			)
			(layer "F.SilkS")
		)
		(fp_line
			(start -1.40005 0.70003)
			(end -2 0.70003)
			(stroke
				(width 0.15011)
				(type solid)
			)
			(layer "F.SilkS")
		)
		(fp_line
			(start -1.40005 -20.69998)
			(end -2 -20.69998)
			(stroke
				(width 0.15011)
				(type solid)
			)
			(layer "F.SilkS")
		)
		(fp_line
			(start -1.40005 -21.24989)
			(end -1.40005 -20.69998)
			(stroke
				(width 0.15011)
				(type solid)
			)
			(layer "F.SilkS")
		)
		(fp_line
			(start -2 0.03302)
			(end -2 0.70003)
			(stroke
				(width 0.15011)
				(type solid)
			)
			(layer "F.SilkS")
		)
		(fp_line
			(start -2 -20.69998)
			(end -2 -20.03298)
			(stroke
				(width 0.15011)
				(type solid)
			)
			(layer "F.SilkS")
		)
		(fp_circle
			(center 3.5052 -0.22453)
			(end 3.5052 -0.02438)
			(stroke
				(width 0.40005)
				(type solid)
			)
			(fill no)
			(layer "F.SilkS")
		)
		(pad "1" smd rect
			(at 2.02489 -0.24993 180)
			(size 1.54991 0.24994)
			(layers "F.Cu" "F.Mask" "F.Paste")
			(net "+5.0V")
		)
		(pad "2" smd rect
			(at -2.02489 -0.24993 180)
			(size 1.54991 0.24994)
			(layers "F.Cu" "F.Mask" "F.Paste")
			(net "+5.0V")
		)
		(pad "3" smd rect
			(at 2.02489 -0.75006 180)
			(size 1.54991 0.24994)
			(layers "F.Cu" "F.Mask" "F.Paste")
			(net "+5.0V")
		)
		(pad "4" smd rect
			(at -2.02489 -0.75006 180)
			(size 1.54991 0.24994)
			(layers "F.Cu" "F.Mask" "F.Paste")
			(net "+5.0V")
		)
		(pad "5" smd rect
			(at 2.02489 -1.24993 180)
			(size 1.54991 0.24994)
			(layers "F.Cu" "F.Mask" "F.Paste")
			(net "+5.0V")
		)
		(pad "6" smd rect
			(at -2.02489 -1.24993 180)
			(size 1.54991 0.24994)
			(layers "F.Cu" "F.Mask" "F.Paste")
			(net "+5.0V")
		)
		(pad "7" smd rect
			(at 2.02489 -1.75006 180)
			(size 1.54991 0.24994)
			(layers "F.Cu" "F.Mask" "F.Paste")
			(net "+5.0V")
		)
		(pad "8" smd rect
			(at -2.02489 -1.75006 180)
			(size 1.54991 0.24994)
			(layers "F.Cu" "F.Mask" "F.Paste")
			(net "+5.0V")
		)
		(pad "9" smd rect
			(at 2.02489 -2.24993 180)
			(size 1.54991 0.24994)
			(layers "F.Cu" "F.Mask" "F.Paste")
			(net "GND")
		)
		(pad "10" smd rect
			(at -2.02489 -2.24993 180)
			(size 1.54991 0.24994)
			(layers "F.Cu" "F.Mask" "F.Paste")
			(net "GND")
		)
		(pad "11" smd rect
			(at 2.02489 -2.75006 180)
			(size 1.54991 0.24994)
			(layers "F.Cu" "F.Mask" "F.Paste")
		)
		(pad "12" smd rect
			(at -2.02489 -2.75006 180)
			(size 1.54991 0.24994)
			(layers "F.Cu" "F.Mask" "F.Paste")
		)
		(pad "13" smd rect
			(at 2.02489 -3.24993 180)
			(size 1.54991 0.24994)
			(layers "F.Cu" "F.Mask" "F.Paste")
		)
		(pad "14" smd rect
			(at -2.02489 -3.24993 180)
			(size 1.54991 0.24994)
			(layers "F.Cu" "F.Mask" "F.Paste")
		)
		(pad "15" smd rect
			(at 2.02489 -3.75005 180)
			(size 1.54991 0.24994)
			(layers "F.Cu" "F.Mask" "F.Paste")
		)
		(pad "16" smd rect
			(at -2.02489 -3.75005 180)
			(size 1.54991 0.24994)
			(layers "F.Cu" "F.Mask" "F.Paste")
		)
		(pad "17" smd rect
			(at 2.02489 -4.24993 180)
			(size 1.54991 0.24994)
			(layers "F.Cu" "F.Mask" "F.Paste")
		)
		(pad "18" smd rect
			(at -2.02489 -4.24993 180)
			(size 1.54991 0.24994)
			(layers "F.Cu" "F.Mask" "F.Paste")
		)
		(pad "19" smd rect
			(at 2.02489 -4.75005 180)
			(size 1.54991 0.24994)
			(layers "F.Cu" "F.Mask" "F.Paste")
			(net "GND")
		)
		(pad "20" smd rect
			(at -2.02489 -4.75005 180)
			(size 1.54991 0.24994)
			(layers "F.Cu" "F.Mask" "F.Paste")
			(net "GND")
		)
		(pad "21" smd rect
			(at 2.02489 -5.24992 180)
			(size 1.54991 0.24994)
			(layers "F.Cu" "F.Mask" "F.Paste")
		)
		(pad "22" smd rect
			(at -2.02489 -5.24992 180)
			(size 1.54991 0.24994)
			(layers "F.Cu" "F.Mask" "F.Paste")
			(net "GPS1_RST")
		)
		(pad "23" smd rect
			(at 2.02489 -5.75005 180)
			(size 1.54991 0.24994)
			(layers "F.Cu" "F.Mask" "F.Paste")
		)
		(pad "24" smd rect
			(at -2.02489 -5.75005 180)
			(size 1.54991 0.24994)
			(layers "F.Cu" "F.Mask" "F.Paste")
		)
		(pad "25" smd rect
			(at 2.02489 -6.24992 180)
			(size 1.54991 0.24994)
			(layers "F.Cu" "F.Mask" "F.Paste")
		)
		(pad "26" smd rect
			(at -2.02489 -6.24992 180)
			(size 1.54991 0.24994)
			(layers "F.Cu" "F.Mask" "F.Paste")
		)
		(pad "27" smd rect
			(at 2.02489 -6.75005 180)
			(size 1.54991 0.24994)
			(layers "F.Cu" "F.Mask" "F.Paste")
		)
		(pad "28" smd rect
			(at -2.02489 -6.75005 180)
			(size 1.54991 0.24994)
			(layers "F.Cu" "F.Mask" "F.Paste")
		)
		(pad "29" smd rect
			(at 2.02489 -7.24992 180)
			(size 1.54991 0.24994)
			(layers "F.Cu" "F.Mask" "F.Paste")
			(net "GND")
		)
		(pad "30" smd rect
			(at -2.02489 -7.24992 180)
			(size 1.54991 0.24994)
			(layers "F.Cu" "F.Mask" "F.Paste")
			(net "GND")
		)
		(pad "31" smd rect
			(at 2.02489 -7.75005 180)
			(size 1.54991 0.24994)
			(layers "F.Cu" "F.Mask" "F.Paste")
		)
		(pad "32" smd rect
			(at -2.02489 -7.75005 180)
			(size 1.54991 0.24994)
			(layers "F.Cu" "F.Mask" "F.Paste")
			(net "GPS1_TP1")
		)
		(pad "33" smd rect
			(at 2.02489 -8.24992 180)
			(size 1.54991 0.24994)
			(layers "F.Cu" "F.Mask" "F.Paste")
		)
		(pad "34" smd rect
			(at -2.02489 -8.24992 180)
			(size 1.54991 0.24994)
			(layers "F.Cu" "F.Mask" "F.Paste")
			(net "GPS1_TP2")
		)
		(pad "35" smd rect
			(at 2.02489 -8.75004 180)
			(size 1.54991 0.24994)
			(layers "F.Cu" "F.Mask" "F.Paste")
		)
		(pad "36" smd rect
			(at -2.02489 -8.75004 180)
			(size 1.54991 0.24994)
			(layers "F.Cu" "F.Mask" "F.Paste")
		)
		(pad "37" smd rect
			(at 2.02489 -9.24992 180)
			(size 1.54991 0.24994)
			(layers "F.Cu" "F.Mask" "F.Paste")
		)
		(pad "38" smd rect
			(at -2.02489 -9.24992 180)
			(size 1.54991 0.24994)
			(layers "F.Cu" "F.Mask" "F.Paste")
		)
		(pad "39" smd rect
			(at 2.02489 -9.75004 180)
			(size 1.54991 0.24994)
			(layers "F.Cu" "F.Mask" "F.Paste")
			(net "GND")
		)
		(pad "40" smd rect
			(at -2.02489 -9.75004 180)
			(size 1.54991 0.24994)
			(layers "F.Cu" "F.Mask" "F.Paste")
			(net "GND")
		)
		(pad "41" smd rect
			(at 2.02489 -10.24991 180)
			(size 1.54991 0.24994)
			(layers "F.Cu" "F.Mask" "F.Paste")
		)
		(pad "42" smd rect
			(at -2.02489 -10.24991 180)
			(size 1.54991 0.24994)
			(layers "F.Cu" "F.Mask" "F.Paste")
		)
		(pad "43" smd rect
			(at 2.02489 -10.75004 180)
			(size 1.54991 0.24994)
			(layers "F.Cu" "F.Mask" "F.Paste")
		)
		(pad "44" smd rect
			(at -2.02489 -10.75004 180)
			(size 1.54991 0.24994)
			(layers "F.Cu" "F.Mask" "F.Paste")
			(net "EXT_EEPROM_WP")
		)
		(pad "45" smd rect
			(at 2.02489 -11.24991 180)
			(size 1.54991 0.24994)
			(layers "F.Cu" "F.Mask" "F.Paste")
		)
		(pad "46" smd rect
			(at -2.02489 -11.24991 180)
			(size 1.54991 0.24994)
			(layers "F.Cu" "F.Mask" "F.Paste")
		)
		(pad "47" smd rect
			(at 2.02489 -11.75004 180)
			(size 1.54991 0.24994)
			(layers "F.Cu" "F.Mask" "F.Paste")
		)
		(pad "48" smd rect
			(at -2.02489 -11.75004 180)
			(size 1.54991 0.24994)
			(layers "F.Cu" "F.Mask" "F.Paste")
		)
		(pad "49" smd rect
			(at 2.02489 -12.24991 180)
			(size 1.54991 0.24994)
			(layers "F.Cu" "F.Mask" "F.Paste")
			(net "GND")
		)
		(pad "50" smd rect
			(at -2.02489 -12.24991 180)
			(size 1.54991 0.24994)
			(layers "F.Cu" "F.Mask" "F.Paste")
			(net "GND")
		)
		(pad "51" smd rect
			(at 2.02489 -12.75004 180)
			(size 1.54991 0.24994)
			(layers "F.Cu" "F.Mask" "F.Paste")
		)
		(pad "52" smd rect
			(at -2.02489 -12.75004 180)
			(size 1.54991 0.24994)
			(layers "F.Cu" "F.Mask" "F.Paste")
		)
		(pad "53" smd rect
			(at 2.02489 -13.24991 180)
			(size 1.54991 0.24994)
			(layers "F.Cu" "F.Mask" "F.Paste")
		)
		(pad "54" smd rect
			(at -2.02489 -13.24991 180)
			(size 1.54991 0.24994)
			(layers "F.Cu" "F.Mask" "F.Paste")
		)
		(pad "55" smd rect
			(at 2.02489 -13.75003 180)
			(size 1.54991 0.24994)
			(layers "F.Cu" "F.Mask" "F.Paste")
		)
		(pad "56" smd rect
			(at -2.02489 -13.75003 180)
			(size 1.54991 0.24994)
			(layers "F.Cu" "F.Mask" "F.Paste")
		)
		(pad "57" smd rect
			(at 2.02489 -14.24991 180)
			(size 1.54991 0.24994)
			(layers "F.Cu" "F.Mask" "F.Paste")
		)
		(pad "58" smd rect
			(at -2.02489 -14.24991 180)
			(size 1.54991 0.24994)
			(layers "F.Cu" "F.Mask" "F.Paste")
		)
		(pad "59" smd rect
			(at 2.02489 -14.75003 180)
			(size 1.54991 0.24994)
			(layers "F.Cu" "F.Mask" "F.Paste")
			(net "GND")
		)
		(pad "60" smd rect
			(at -2.02489 -14.75003 180)
			(size 1.54991 0.24994)
			(layers "F.Cu" "F.Mask" "F.Paste")
			(net "GND")
		)
		(pad "61" smd rect
			(at 2.02489 -15.2499 180)
			(size 1.54991 0.24994)
			(layers "F.Cu" "F.Mask" "F.Paste")
		)
		(pad "62" smd rect
			(at -2.02489 -15.2499 180)
			(size 1.54991 0.24994)
			(layers "F.Cu" "F.Mask" "F.Paste")
		)
		(pad "63" smd rect
			(at 2.02489 -15.75003 180)
			(size 1.54991 0.24994)
			(layers "F.Cu" "F.Mask" "F.Paste")
		)
		(pad "64" smd rect
			(at -2.02489 -15.75003 180)
			(size 1.54991 0.24994)
			(layers "F.Cu" "F.Mask" "F.Paste")
		)
		(pad "65" smd rect
			(at 2.02489 -16.2499 180)
			(size 1.54991 0.24994)
			(layers "F.Cu" "F.Mask" "F.Paste")
		)
		(pad "66" smd rect
			(at -2.02489 -16.2499 180)
			(size 1.54991 0.24994)
			(layers "F.Cu" "F.Mask" "F.Paste")
		)
		(pad "67" smd rect
			(at 2.02489 -16.75003 180)
			(size 1.54991 0.24994)
			(layers "F.Cu" "F.Mask" "F.Paste")
			(net "KEY2")
		)
		(pad "68" smd rect
			(at -2.02489 -16.75003 180)
			(size 1.54991 0.24994)
			(layers "F.Cu" "F.Mask" "F.Paste")
		)
		(pad "69" smd rect
			(at 2.02489 -17.2499 180)
			(size 1.54991 0.24994)
			(layers "F.Cu" "F.Mask" "F.Paste")
			(net "GND")
		)
		(pad "70" smd rect
			(at -2.02489 -17.2499 180)
			(size 1.54991 0.24994)
			(layers "F.Cu" "F.Mask" "F.Paste")
			(net "GND")
		)
		(pad "71" smd rect
			(at 2.02489 -17.75003 180)
			(size 1.54991 0.24994)
			(layers "F.Cu" "F.Mask" "F.Paste")
			(net "LED4")
		)
		(pad "72" smd rect
			(at -2.02489 -17.75003 180)
			(size 1.54991 0.24994)
			(layers "F.Cu" "F.Mask" "F.Paste")
		)
		(pad "73" smd rect
			(at 2.02489 -18.2499 180)
			(size 1.54991 0.24994)
			(layers "F.Cu" "F.Mask" "F.Paste")
			(net "LED3")
		)
		(pad "74" smd rect
			(at -2.02489 -18.2499 180)
			(size 1.54991 0.24994)
			(layers "F.Cu" "F.Mask" "F.Paste")
		)
		(pad "75" smd rect
			(at 2.02489 -18.75002 180)
			(size 1.54991 0.24994)
			(layers "F.Cu" "F.Mask" "F.Paste")
			(net "LED2")
		)
		(pad "76" smd rect
			(at -2.02489 -18.75002 180)
			(size 1.54991 0.24994)
			(layers "F.Cu" "F.Mask" "F.Paste")
		)
		(pad "77" smd rect
			(at 2.02489 -19.2499 180)
			(size 1.54991 0.24994)
			(layers "F.Cu" "F.Mask" "F.Paste")
			(net "LED1")
		)
		(pad "78" smd rect
			(at -2.02489 -19.2499 180)
			(size 1.54991 0.24994)
			(layers "F.Cu" "F.Mask" "F.Paste")
		)
		(pad "79" smd rect
			(at 2.02489 -19.75002 180)
			(size 1.54991 0.24994)
			(layers "F.Cu" "F.Mask" "F.Paste")
		)
		(pad "80" smd rect
			(at -2.02489 -19.75002 180)
			(size 1.54991 0.24994)
			(layers "F.Cu" "F.Mask" "F.Paste")
		)
		(pad "81" smd rect
			(at 0.01135 1.17626 180)
			(size 1.70002 1.35001)
			(layers "F.Cu" "F.Mask" "F.Paste")
		)
		(pad "82" thru_hole circle
			(at 0 0 180)
			(size 0.55016 0.55016)
			(drill 0.55016)
			(layers "*.Cu" "*.Mask")
			(remove_unused_layers no)
			(thermal_bridge_angle 90)
		)
		(pad "83" thru_hole circle
			(at 0 -19.99996 180)
			(size 0.55016 0.55016)
			(drill 0.55016)
			(layers "*.Cu" "*.Mask")
			(remove_unused_layers no)
			(thermal_bridge_angle 90)
		)
		(pad "84" smd rect
			(at 0.01135 -21.17374 180)
			(size 1.70002 1.35001)
			(layers "F.Cu" "F.Mask" "F.Paste")
		)
	)
	(footprint "SA53:SolderSocket"
		(layer "F.Cu")
		(at 128.7781 138.2162 90)
		(property "Reference" "SKT8"
			(at -3.426921 0.8766 0)
			(unlocked yes)
			(layer "F.SilkS")
			(effects
				(font
					(size 0.762 0.762)
					(thickness 0.2286)
				)
			)
		)
		(property "Value" "0332-0-43-80-18-27-10-0"
			(at -2.910071 16.1362 0)
			(unlocked yes)
			(layer "F.SilkS")
			(hide yes)
			(effects
				(font
					(size 0.762 0.762)
					(thickness 0.2286)
				)
			)
		)
		(sheetname "MAC")
		(sheetfile "MAC.kicad_sch")
		(duplicate_pad_numbers_are_jumpers no)
		(pad "1" thru_hole circle
			(at 0 0 90)
			(size 2.54 2.54)
			(drill 2.0066)
			(layers "*.Cu" "*.Mask")
			(remove_unused_layers no)
			(net "MAC_PPS_IN")
			(thermal_bridge_angle 90)
		)
	)
	(footprint "SamacSys:SOP50P310X90-8N"
		(layer "F.Cu")
		(at 82.3761 122.3662 180)
		(property "Reference" "U11"
			(at 0.153605 2.026921 180)
			(unlocked yes)
			(layer "F.SilkS")
			(effects
				(font
					(size 0.762 0.762)
					(thickness 0.2286)
				)
			)
		)
		(property "Value" "NC7WV125K8X"
			(at 6.207715 2.884671 180)
			(unlocked yes)
			(layer "F.SilkS")
			(hide yes)
			(effects
				(font
					(size 0.762 0.762)
					(thickness 0.2286)
				)
			)
		)
		(sheetname "USER_IO")
		(sheetfile "USER_IO.kicad_sch")
		(duplicate_pad_numbers_are_jumpers no)
		(fp_line
			(start 0.8 1)
			(end -0.8 1)
			(stroke
				(width 0.2)
				(type solid)
			)
			(layer "F.SilkS")
		)
		(fp_line
			(start 0.8 -1)
			(end 0.8 1)
			(stroke
				(width 0.2)
				(type solid)
			)
			(layer "F.SilkS")
		)
		(fp_line
			(start 0.8 -1)
			(end -0.8 -1)
			(stroke
				(width 0.2)
				(type solid)
			)
			(layer "F.SilkS")
		)
		(fp_line
			(start -0.8 -1)
			(end -0.8 1)
			(stroke
				(width 0.2)
				(type solid)
			)
			(layer "F.SilkS")
		)
		(fp_line
			(start -1.15 -1.25)
			(end -2 -1.25)
			(stroke
				(width 0.2)
				(type solid)
			)
			(layer "F.SilkS")
		)
		(pad "1" smd rect
			(at -1.575 -0.75 180)
			(size 0.85 0.3)
			(layers "F.Cu" "F.Mask" "F.Paste")
			(net "ANT3_IO_OUT")
		)
		(pad "2" smd rect
			(at -1.575 -0.25 180)
			(size 0.85 0.3)
			(layers "F.Cu" "F.Mask" "F.Paste")
			(net "ANT3_OUT")
		)
		(pad "3" smd rect
			(at -1.575 0.25 180)
			(size 0.85 0.3)
			(layers "F.Cu" "F.Mask" "F.Paste")
			(net "ANT3_IN")
		)
		(pad "4" smd rect
			(at -1.575 0.75 180)
			(size 0.85 0.3)
			(layers "F.Cu" "F.Mask" "F.Paste")
			(net "GND")
		)
		(pad "5" smd rect
			(at 1.575 0.75 180)
			(size 0.85 0.3)
			(layers "F.Cu" "F.Mask" "F.Paste")
			(net "NetR28_1")
		)
		(pad "6" smd rect
			(at 1.575 0.25 180)
			(size 0.85 0.3)
			(layers "F.Cu" "F.Mask" "F.Paste")
			(net "NetR28_1")
		)
		(pad "7" smd rect
			(at 1.575 -0.25 180)
			(size 0.85 0.3)
			(layers "F.Cu" "F.Mask" "F.Paste")
			(net "ANT3_IO_IN")
		)
		(pad "8" smd rect
			(at 1.575 -0.75 180)
			(size 0.85 0.3)
			(layers "F.Cu" "F.Mask" "F.Paste")
			(net "+3.3V")
		)
	)
	(footprint "Vault:FP-BLM18-0_15-t0_8-IPC_A"
		(layer "F.Cu")
		(at 233.9261 81.5162 -90)
		(property "Reference" "FB1"
			(at 2.128605 -1.673069 270)
			(unlocked yes)
			(layer "F.SilkS")
			(effects
				(font
					(size 0.762 0.762)
					(thickness 0.2286)
				)
			)
		)
		(property "Value" "600ohm_1.3A_0603"
			(at 10.14352 2.744961 270)
			(unlocked yes)
			(layer "F.SilkS")
			(hide yes)
			(effects
				(font
					(size 0.762 0.762)
					(thickness 0.2286)
				)
			)
		)
		(sheetname "USBUart_DipSelects")
		(sheetfile "USBUart_DipSelects.kicad_sch")
		(duplicate_pad_numbers_are_jumpers no)
		(fp_line
			(start 1.42911 0.92911)
			(end -1.42911 0.92911)
			(stroke
				(width 0.2)
				(type solid)
			)
			(layer "F.SilkS")
		)
		(fp_line
			(start 1.42911 -0.92911)
			(end -1.42911 -0.92911)
			(stroke
				(width 0.2)
				(type solid)
			)
			(layer "F.SilkS")
		)
		(fp_line
			(start -1.92911 1.02911)
			(end -1.92911 -1.02911)
			(stroke
				(width 0.2)
				(type solid)
			)
			(layer "F.CrtYd")
		)
		(fp_line
			(start 1.92911 1.02911)
			(end -1.92911 1.02911)
			(stroke
				(width 0.2)
				(type solid)
			)
			(layer "F.CrtYd")
		)
		(fp_line
			(start 1.92911 1.02911)
			(end 1.92911 -1.02911)
			(stroke
				(width 0.2)
				(type solid)
			)
			(layer "F.CrtYd")
		)
		(fp_line
			(start 1.92911 -1.02911)
			(end -1.92911 -1.02911)
			(stroke
				(width 0.2)
				(type solid)
			)
			(layer "F.CrtYd")
		)
		(fp_line
			(start -1.92911 1.02911)
			(end -1.92911 -1.02911)
			(stroke
				(width 0.2)
				(type solid)
			)
			(layer "F.Fab")
		)
		(fp_line
			(start 1.92911 1.02911)
			(end -1.92911 1.02911)
			(stroke
				(width 0.2)
				(type solid)
			)
			(layer "F.Fab")
		)
		(fp_line
			(start 1.92911 1.02911)
			(end 1.92911 -1.02911)
			(stroke
				(width 0.2)
				(type solid)
			)
			(layer "F.Fab")
		)
		(fp_line
			(start 0 0.5)
			(end 0 -0.5)
			(stroke
				(width 0.1)
				(type solid)
			)
			(layer "F.Fab")
		)
		(fp_line
			(start 0.5 0)
			(end -0.5 0)
			(stroke
				(width 0.1)
				(type solid)
			)
			(layer "F.Fab")
		)
		(fp_line
			(start 1.92911 -1.02911)
			(end -1.92911 -1.02911)
			(stroke
				(width 0.2)
				(type solid)
			)
			(layer "F.Fab")
		)
		(fp_text user "${REFERENCE}"
			(at -0.00001 0.10711 270)
			(unlocked yes)
			(layer "F.Fab")
			(effects
				(font
					(face "Arial")
					(size 0.63 0.63)
					(thickness 0.1)
				)
				(justify left bottom)
			)
		)
		(pad "1" smd rect
			(at -0.77608 0 270)
			(size 1.30606 1.05822)
			(layers "F.Cu" "F.Mask" "F.Paste")
			(net "USB_VBUS")
			(solder_mask_margin 0)
			(solder_paste_margin 0)
		)
		(pad "2" smd rect
			(at 0.77608 0 270)
			(size 1.30606 1.05822)
			(layers "F.Cu" "F.Mask" "F.Paste")
			(net "FTDI_VBUS")
			(solder_mask_margin 0)
			(solder_paste_margin 0)
		)
	)
	(footprint "Vault:RESC1005X40X25LL05T10"
		(layer "F.Cu")
		(at 122.8261 84.4162 90)
		(property "Reference" "R104"
			(at -2.0714 -0.073079 90)
			(unlocked yes)
			(layer "F.SilkS")
			(effects
				(font
					(size 0.762 0.762)
					(thickness 0.2286)
				)
			)
		)
		(property "Value" "DNI_49.9_1%_0402"
			(at -2.579871 11.74372 0)
			(unlocked yes)
			(layer "F.SilkS")
			(hide yes)
			(effects
				(font
					(size 0.762 0.762)
					(thickness 0.2286)
				)
			)
		)
		(sheetname "USBUart_DipSelects")
		(sheetfile "USBUart_DipSelects.kicad_sch")
		(duplicate_pad_numbers_are_jumpers no)
		(pad "1" smd rect
			(at -0.375 0 180)
			(size 0.45 0.5)
			(layers "F.Cu" "F.Mask" "F.Paste")
			(net "FPGA_MAC_PPS_OUT-")
		)
		(pad "2" smd rect
			(at 0.375 0 180)
			(size 0.45 0.5)
			(layers "F.Cu" "F.Mask" "F.Paste")
			(net "MAC_PPS_OUT")
		)
	)
	(footprint "Vault:RESC1608X55X30NL15T15"
		(layer "F.Cu")
		(at 84.3761 125.8662 -90)
		(property "Reference" "R16"
			(at 2.7714 -0.026931 90)
			(unlocked yes)
			(layer "F.SilkS")
			(effects
				(font
					(size 0.762 0.762)
					(thickness 0.2286)
				)
			)
		)
		(property "Value" "4.7K"
			(at 0.558471 -4.82535 0)
			(unlocked yes)
			(layer "F.SilkS")
			(hide yes)
			(effects
				(font
					(size 0.762 0.762)
					(thickness 0.2286)
				)
			)
		)
		(sheetname "USER_IO")
		(sheetfile "USER_IO.kicad_sch")
		(duplicate_pad_numbers_are_jumpers no)
		(pad "1" smd rect
			(at -0.75 0)
			(size 0.95 0.95)
			(layers "F.Cu" "F.Mask" "F.Paste")
			(net "ANT3_IO_OUT")
		)
		(pad "2" smd rect
			(at 0.75 0)
			(size 0.95 0.95)
			(layers "F.Cu" "F.Mask" "F.Paste")
			(net "+3.3V")
		)
	)
	(footprint "Vault:RESC1005X40X25LL05T10"
		(layer "F.Cu")
		(at 128.6261 81.7162 180)
		(property "Reference" "R106"
			(at -0.8286 1.173069 0)
			(unlocked yes)
			(layer "F.SilkS")
			(effects
				(font
					(size 0.762 0.762)
					(thickness 0.2286)
				)
			)
		)
		(property "Value" "DNI_49.9_1%_0402"
			(at -2.579871 11.74372 90)
			(unlocked yes)
			(layer "F.SilkS")
			(hide yes)
			(effects
				(font
					(size 0.762 0.762)
					(thickness 0.2286)
				)
			)
		)
		(sheetname "USBUart_DipSelects")
		(sheetfile "USBUart_DipSelects.kicad_sch")
		(duplicate_pad_numbers_are_jumpers no)
		(pad "1" smd rect
			(at -0.375 0 270)
			(size 0.45 0.5)
			(layers "F.Cu" "F.Mask" "F.Paste")
			(net "FPGA_MAC_PPS_IN0-")
		)
		(pad "2" smd rect
			(at 0.375 0 270)
			(size 0.45 0.5)
			(layers "F.Cu" "F.Mask" "F.Paste")
			(net "MAC_PPS_IN")
		)
	)
	(footprint "Vault:TECO-1909763-1_V"
		(layer "F.Cu")
		(at 74.3761 121.8662 -90)
		(property "Reference" "J3"
			(at -2.973069 1.271395 0)
			(unlocked yes)
			(layer "F.SilkS")
			(effects
				(font
					(size 0.762 0.762)
					(thickness 0.2286)
				)
			)
		)
		(property "Value" "1909763-1"
			(at 4.582685 3.722871 270)
			(unlocked yes)
			(layer "F.SilkS")
			(hide yes)
			(effects
				(font
					(size 0.762 0.762)
					(thickness 0.2286)
				)
			)
		)
		(sheetname "USER_IO")
		(sheetfile "USER_IO.kicad_sch")
		(duplicate_pad_numbers_are_jumpers no)
		(fp_line
			(start 0.55 -1.3)
			(end -0.55 -1.3)
			(stroke
				(width 0.2)
				(type solid)
			)
			(layer "F.SilkS")
		)
		(fp_circle
			(center -1.778 1.65)
			(end -1.903 1.65)
			(stroke
				(width 0.25)
				(type solid)
			)
			(fill no)
			(layer "F.SilkS")
		)
		(pad "1" smd rect
			(at -1.475 0 270)
			(size 1.05 2.2)
			(layers "F.Cu" "F.Mask" "F.Paste")
			(net "GND")
		)
		(pad "2" smd rect
			(at 0 1.525 270)
			(size 1 1.05)
			(layers "F.Cu" "F.Mask" "F.Paste")
			(net "NetAN3_1")
		)
		(pad "3" smd rect
			(at 1.475 0 270)
			(size 1.05 2.2)
			(layers "F.Cu" "F.Mask" "F.Paste")
			(net "GND")
		)
	)
	(footprint "Vault:FP-T495D107K016ATE125-MFG"
		(layer "F.Cu")
		(at 226.5261 119.7162)
		(property "Reference" "C79"
			(at 2.9286 -2.973069 0)
			(unlocked yes)
			(layer "F.SilkS")
			(effects
				(font
					(size 0.762 0.762)
					(thickness 0.2286)
				)
			)
		)
		(property "Value" "100uF_16V_2917"
			(at -5.818351 8.010455 270)
			(unlocked yes)
			(layer "F.SilkS")
			(hide yes)
			(effects
				(font
					(size 0.762 0.762)
					(thickness 0.2286)
				)
			)
		)
		(sheetname "POWER")
		(sheetfile "POWER.kicad_sch")
		(duplicate_pad_numbers_are_jumpers no)
		(fp_line
			(start -3.8 -2.3)
			(end 3.8 -2.3)
			(stroke
				(width 0.2)
				(type solid)
			)
			(layer "F.SilkS")
		)
		(fp_line
			(start -3.8 -1.54)
			(end -3.8 -2.3)
			(stroke
				(width 0.2)
				(type solid)
			)
			(layer "F.SilkS")
		)
		(fp_line
			(start -3.8 2.3)
			(end -3.8 1.54)
			(stroke
				(width 0.2)
				(type solid)
			)
			(layer "F.SilkS")
		)
		(fp_line
			(start -3.8 2.3)
			(end 3.8 2.3)
			(stroke
				(width 0.2)
				(type solid)
			)
			(layer "F.SilkS")
		)
		(fp_line
			(start 3.8 -1.54)
			(end 3.8 -2.3)
			(stroke
				(width 0.2)
				(type solid)
			)
			(layer "F.SilkS")
		)
		(fp_line
			(start 3.8 2.3)
			(end 3.8 1.54)
			(stroke
				(width 0.2)
				(type solid)
			)
			(layer "F.SilkS")
		)
		(fp_line
			(start 4.4 0)
			(end 5 0)
			(stroke
				(width 0.2)
				(type solid)
			)
			(layer "F.SilkS")
		)
		(fp_line
			(start 4.7 0.3)
			(end 4.7 -0.3)
			(stroke
				(width 0.2)
				(type solid)
			)
			(layer "F.SilkS")
		)
		(fp_line
			(start -4.105 -2.4)
			(end 4.105 -2.4)
			(stroke
				(width 0.2)
				(type solid)
			)
			(layer "F.CrtYd")
		)
		(fp_line
			(start -4.105 2.4)
			(end -4.105 -2.4)
			(stroke
				(width 0.2)
				(type solid)
			)
			(layer "F.CrtYd")
		)
		(fp_line
			(start -4.105 2.4)
			(end 4.105 2.4)
			(stroke
				(width 0.2)
				(type solid)
			)
			(layer "F.CrtYd")
		)
		(fp_line
			(start 4.105 2.4)
			(end 4.105 -2.4)
			(stroke
				(width 0.2)
				(type solid)
			)
			(layer "F.CrtYd")
		)
		(fp_line
			(start -4.105 -2.4)
			(end 4.105 -2.4)
			(stroke
				(width 0.2)
				(type solid)
			)
			(layer "F.Fab")
		)
		(fp_line
			(start -4.105 2.4)
			(end -4.105 -2.4)
			(stroke
				(width 0.2)
				(type solid)
			)
			(layer "F.Fab")
		)
		(fp_line
			(start -4.105 2.4)
			(end 4.105 2.4)
			(stroke
				(width 0.2)
				(type solid)
			)
			(layer "F.Fab")
		)
		(fp_line
			(start -0.5 0)
			(end 0.5 0)
			(stroke
				(width 0.1)
				(type solid)
			)
			(layer "F.Fab")
		)
		(fp_line
			(start 0 0.5)
			(end 0 -0.5)
			(stroke
				(width 0.1)
				(type solid)
			)
			(layer "F.Fab")
		)
		(fp_line
			(start 4.105 2.4)
			(end 4.105 -2.4)
			(stroke
				(width 0.2)
				(type solid)
			)
			(layer "F.Fab")
		)
		(fp_text user "${REFERENCE}"
			(at 0 0.28425 360)
			(unlocked yes)
			(layer "F.Fab")
			(effects
				(font
					(face "Arial")
					(size 0.63 0.63)
					(thickness 0.1)
				)
				(justify left bottom)
			)
		)
		(pad "1" smd rect
			(at -3.01 0)
			(size 1.99 2.33)
			(layers "F.Cu" "F.Mask" "F.Paste")
			(net "GND")
			(solder_mask_margin 0)
			(solder_paste_margin 0)
		)
		(pad "2" smd rect
			(at 3.01 0)
			(size 1.99 2.33)
			(layers "F.Cu" "F.Mask" "F.Paste")
			(net "+3.3V")
			(solder_mask_margin 0)
			(solder_paste_margin 0)
		)
	)
	(footprint "GNSS:GNSS Header 16-pin"
		(layer "F.Cu")
		(at 80.1536 74.3286)
		(property "Reference" "J6"
			(at 5.285479 3.491555 270)
			(unlocked yes)
			(layer "F.SilkS")
			(effects
				(font
					(size 0.762 0.762)
					(thickness 0.2286)
				)
			)
		)
		(property "Value" "GNSS Header 16-pin"
			(at 6.740165 4.840511 0)
			(unlocked yes)
			(layer "F.SilkS")
			(hide yes)
			(effects
				(font
					(size 0.762 0.762)
					(thickness 0.2286)
				)
			)
		)
		(sheetname "GPS_IMU_SENSORS")
		(sheetfile "GPS_IMU_SENSORS.kicad_sch")
		(duplicate_pad_numbers_are_jumpers no)
		(fp_line
			(start -0.5 -7.5)
			(end 8.5 -7.5)
			(stroke
				(width 0.0254)
				(type solid)
			)
			(layer "F.SilkS")
		)
		(fp_line
			(start -0.5 0.5)
			(end -0.5 -7.5)
			(stroke
				(width 0.0254)
				(type solid)
			)
			(layer "F.SilkS")
		)
		(fp_line
			(start -0.5 0.5)
			(end 8.5 0.5)
			(stroke
				(width 0.0254)
				(type solid)
			)
			(layer "F.SilkS")
		)
		(fp_line
			(start 8.5 0.5)
			(end 8.5 -7.5)
			(stroke
				(width 0.0254)
				(type solid)
			)
			(layer "F.SilkS")
		)
		(fp_circle
			(center 0 -0.5)
			(end 0 -0.5254)
			(stroke
				(width 0.508)
				(type solid)
			)
			(fill no)
			(layer "F.SilkS")
		)
		(fp_text user "Orig 2x4"
			(at 9.610805 -0.2286 90)
			(unlocked yes)
			(layer "F.SilkS")
			(effects
				(font
					(size 0.762 0.762)
					(thickness 0.2286)
				)
				(justify left bottom)
			)
		)
		(pad "0" thru_hole circle
			(at 4 -13.49998 270)
			(size 0 0)
			(drill 0.76)
			(layers "*.Cu" "*.Mask")
			(remove_unused_layers no)
			(thermal_bridge_angle 90)
		)
		(pad "0" thru_hole circle
			(at 4 -1.5 270)
			(size 0 0)
			(drill 0.76)
			(layers "*.Cu" "*.Mask")
			(remove_unused_layers no)
			(thermal_bridge_angle 90)
		)
		(pad "1" smd rect
			(at 1.7775 -0.5 270)
			(size 1.12 2.105)
			(layers "F.Cu" "F.Mask" "F.Paste")
			(net "+5.0V")
		)
		(pad "2" smd rect
			(at 6.2225 -0.5 270)
			(size 1.12 2.105)
			(layers "F.Cu" "F.Mask" "F.Paste")
			(net "+3.3V")
		)
		(pad "3" smd rect
			(at 1.7775 -2.5 270)
			(size 1.12 2.105)
			(layers "F.Cu" "F.Mask" "F.Paste")
			(net "GPS1_TX")
		)
		(pad "4" smd rect
			(at 6.2225 -2.5 270)
			(size 1.12 2.105)
			(layers "F.Cu" "F.Mask" "F.Paste")
			(net "GPS1_RST")
		)
		(pad "5" smd rect
			(at 1.7775 -4.5 270)
			(size 1.12 2.105)
			(layers "F.Cu" "F.Mask" "F.Paste")
			(net "GPS1_RX")
		)
		(pad "6" smd rect
			(at 6.2225 -4.5 270)
			(size 1.12 2.105)
			(layers "F.Cu" "F.Mask" "F.Paste")
			(net "GPS1_TP1")
		)
		(pad "7" smd rect
			(at 1.7775 -6.5 270)
			(size 1.12 2.105)
			(layers "F.Cu" "F.Mask" "F.Paste")
			(net "GPS1_TP2")
		)
		(pad "8" smd rect
			(at 6.2225 -6.5 270)
			(size 1.12 2.105)
			(layers "F.Cu" "F.Mask" "F.Paste")
			(net "GND")
		)
		(pad "9" smd rect
			(at 1.7775 -8.50001 270)
			(size 1.12 2.105)
			(layers "F.Cu" "F.Mask" "F.Paste")
			(net "+5.0V")
		)
		(pad "10" smd rect
			(at 6.2225 -8.50001 270)
			(size 1.12 2.105)
			(layers "F.Cu" "F.Mask" "F.Paste")
			(net "+3.3V")
		)
		(pad "11" smd rect
			(at 1.7775 -10.50001 270)
			(size 1.12 2.105)
			(layers "F.Cu" "F.Mask" "F.Paste")
			(net "GPS1_PIN11")
		)
		(pad "12" smd rect
			(at 6.2225 -10.50001 270)
			(size 1.12 2.105)
			(layers "F.Cu" "F.Mask" "F.Paste")
			(net "GPS1_PIN12")
		)
		(pad "13" smd rect
			(at 1.7775 -12.5 270)
			(size 1.12 2.105)
			(layers "F.Cu" "F.Mask" "F.Paste")
			(net "GPS1_PIN13")
		)
		(pad "14" smd rect
			(at 6.2225 -12.5 270)
			(size 1.12 2.105)
			(layers "F.Cu" "F.Mask" "F.Paste")
			(net "GPS1_PIN14")
		)
		(pad "15" smd rect
			(at 1.7775 -14.5 270)
			(size 1.12 2.105)
			(layers "F.Cu" "F.Mask" "F.Paste")
			(net "GPS1_PIN15")
		)
		(pad "16" smd rect
			(at 6.2225 -14.5 270)
			(size 1.12 2.105)
			(layers "F.Cu" "F.Mask" "F.Paste")
			(net "GND")
		)
	)
	(footprint "Vault:CAPC1608X87X45ML20T05"
		(layer "F.Cu")
		(at 176.8761 87.0786 -90)
		(property "Reference" "C25"
			(at -2.4338 -0.023069 270)
			(unlocked yes)
			(layer "F.SilkS")
			(effects
				(font
					(size 0.762 0.762)
					(thickness 0.2286)
				)
			)
		)
		(property "Value" "0.1uF"
			(at 2.069035 2.630671 270)
			(unlocked yes)
			(layer "F.SilkS")
			(hide yes)
			(effects
				(font
					(size 0.762 0.762)
					(thickness 0.2286)
				)
			)
		)
		(sheetname "GPS_IMU_SENSORS")
		(sheetfile "GPS_IMU_SENSORS.kicad_sch")
		(duplicate_pad_numbers_are_jumpers no)
		(pad "1" smd rect
			(at -0.7 0)
			(size 1.1 1.05)
			(layers "F.Cu" "F.Mask" "F.Paste")
			(net "GND")
		)
		(pad "2" smd rect
			(at 0.7 0)
			(size 1.1 1.05)
			(layers "F.Cu" "F.Mask" "F.Paste")
			(net "+3.3V")
		)
	)
	(footprint "Vault:RESC1005X40X25ML05T10"
		(layer "F.Cu")
		(at 202.8511 127.5162)
		(property "Reference" "R74"
			(at -3.1964 4.226921 0)
			(unlocked yes)
			(layer "F.SilkS")
			(effects
				(font
					(size 0.762 0.762)
					(thickness 0.2286)
				)
			)
		)
		(property "Value" "2.21_1%_0402"
			(at -2.884681 8.544315 270)
			(unlocked yes)
			(layer "F.SilkS")
			(hide yes)
			(effects
				(font
					(size 0.762 0.762)
					(thickness 0.2286)
				)
			)
		)
		(sheetname "POWER")
		(sheetfile "POWER.kicad_sch")
		(duplicate_pad_numbers_are_jumpers no)
		(pad "1" smd rect
			(at -0.475 0 90)
			(size 0.65 0.7)
			(layers "F.Cu" "F.Mask" "F.Paste")
			(net "+12V")
		)
		(pad "2" smd rect
			(at 0.475 0 90)
			(size 0.65 0.7)
			(layers "F.Cu" "F.Mask" "F.Paste")
			(net "NetC71_1")
		)
	)
	(footprint "MIC24052YJL-TR:QFN28_5X6_MCH"
		(layer "F.Cu")
		(at 208.8261 124.2162 90)
		(property "Reference" "U18"
			(at 3.673079 1.1286 0)
			(unlocked yes)
			(layer "F.SilkS")
			(effects
				(font
					(size 0.762 0.762)
					(thickness 0.2286)
				)
			)
		)
		(property "Value" "MIC24052YJL-TR"
			(at 7.146775 5.297671 90)
			(unlocked yes)
			(layer "F.SilkS")
			(hide yes)
			(effects
				(font
					(size 0.762 0.762)
					(thickness 0.2286)
				)
			)
		)
		(sheetname "POWER")
		(sheetfile "POWER.kicad_sch")
		(duplicate_pad_numbers_are_jumpers no)
		(fp_line
			(start 2.9083 -3.4036)
			(end 2.9083 -2.56018)
			(stroke
				(width 0.1524)
				(type solid)
			)
			(layer "F.SilkS")
		)
		(fp_line
			(start 1.92049 -3.4036)
			(end 2.9083 -3.4036)
			(stroke
				(width 0.1524)
				(type solid)
			)
			(layer "F.SilkS")
		)
		(fp_line
			(start -2.9083 -3.4036)
			(end -1.92049 -3.4036)
			(stroke
				(width 0.1524)
				(type solid)
			)
			(layer "F.SilkS")
		)
		(fp_line
			(start -2.9083 -3.4036)
			(end -2.9083 -2.56018)
			(stroke
				(width 0.1524)
				(type solid)
			)
			(layer "F.SilkS")
		)
		(fp_line
			(start 2.9083 2.56018)
			(end 2.9083 3.4036)
			(stroke
				(width 0.1524)
				(type solid)
			)
			(layer "F.SilkS")
		)
		(fp_line
			(start -2.9083 2.56018)
			(end -2.9083 3.4036)
			(stroke
				(width 0.1524)
				(type solid)
			)
			(layer "F.SilkS")
		)
		(fp_line
			(start 1.92049 3.4036)
			(end 2.9083 3.4036)
			(stroke
				(width 0.1524)
				(type solid)
			)
			(layer "F.SilkS")
		)
		(fp_line
			(start -2.9083 3.4036)
			(end -1.92049 3.4036)
			(stroke
				(width 0.1524)
				(type solid)
			)
			(layer "F.SilkS")
		)
		(fp_text user "*"
			(at -3.5557 -2.190425 90)
			(unlocked yes)
			(layer "F.SilkS")
			(effects
				(font
					(size 1.27 1.27)
					(thickness 0.0762)
				)
				(justify left bottom)
			)
		)
		(pad "1" smd rect
			(at -2.4 -2.275)
			(size 0.3 0.4)
			(layers "F.Cu" "F.Mask" "F.Paste")
			(net "P3V3_PVDD")
			(solder_mask_margin 0)
			(solder_paste_margin -0.15)
		)
		(pad "2" smd rect
			(at -2.4 -1.625)
			(size 0.3 0.4)
			(layers "F.Cu" "F.Mask" "F.Paste")
			(net "GND")
			(solder_mask_margin 0)
			(solder_paste_margin -0.15)
		)
		(pad "3" smd rect
			(at -2.4 -0.975)
			(size 0.3 0.4)
			(layers "F.Cu" "F.Mask" "F.Paste")
			(solder_mask_margin 0)
			(solder_paste_margin -0.15)
		)
		(pad "4" smd rect
			(at -2.4 -0.325)
			(size 0.3 0.4)
			(layers "F.Cu" "F.Mask" "F.Paste")
			(net "NetL2_1")
			(solder_mask_margin 0)
			(solder_paste_margin -0.15)
		)
		(pad "5" smd rect
			(at -2.4 0.325)
			(size 0.3 0.4)
			(layers "F.Cu" "F.Mask" "F.Paste")
			(net "GND")
			(solder_mask_margin 0)
			(solder_paste_margin -0.15)
		)
		(pad "6" smd rect
			(at -2.4 0.975)
			(size 0.3 0.4)
			(layers "F.Cu" "F.Mask" "F.Paste")
			(net "GND")
			(solder_mask_margin 0)
			(solder_paste_margin -0.15)
		)
		(pad "7" smd rect
			(at -2.4 1.625)
			(size 0.3 0.4)
			(layers "F.Cu" "F.Mask" "F.Paste")
			(net "GND")
			(solder_mask_margin 0)
			(solder_paste_margin -0.15)
		)
		(pad "8" smd rect
			(at -2.4 2.275)
			(size 0.3 0.4)
			(layers "F.Cu" "F.Mask" "F.Paste")
			(net "GND")
			(solder_mask_margin 0)
			(solder_paste_margin -0.15)
		)
		(pad "9" smd rect
			(at -1.625 2.9 270)
			(size 0.3 0.4)
			(layers "F.Cu" "F.Mask" "F.Paste")
			(net "NetL2_1")
			(solder_mask_margin 0)
			(solder_paste_margin -0.15)
		)
		(pad "10" smd rect
			(at -0.975 2.9 270)
			(size 0.3 0.4)
			(layers "F.Cu" "F.Mask" "F.Paste")
			(net "NetL2_1")
			(solder_mask_margin 0)
			(solder_paste_margin -0.15)
		)
		(pad "11" smd rect
			(at -0.325 2.9 270)
			(size 0.3 0.4)
			(layers "F.Cu" "F.Mask" "F.Paste")
			(net "NetL2_1")
			(solder_mask_margin 0)
			(solder_paste_margin -0.15)
		)
		(pad "12" smd rect
			(at 0.325 2.9 270)
			(size 0.3 0.4)
			(layers "F.Cu" "F.Mask" "F.Paste")
			(net "NetL2_1")
			(solder_mask_margin 0)
			(solder_paste_margin -0.15)
		)
		(pad "13" smd rect
			(at 0.975 2.9 270)
			(size 0.3 0.4)
			(layers "F.Cu" "F.Mask" "F.Paste")
			(net "+12V")
			(solder_mask_margin 0)
			(solder_paste_margin -0.15)
		)
		(pad "14" smd rect
			(at 1.625 2.9 270)
			(size 0.3 0.4)
			(layers "F.Cu" "F.Mask" "F.Paste")
			(net "+12V")
			(solder_mask_margin 0)
			(solder_paste_margin -0.15)
		)
		(pad "15" smd rect
			(at 2.4 2.275)
			(size 0.3 0.4)
			(layers "F.Cu" "F.Mask" "F.Paste")
			(net "+12V")
			(solder_mask_margin 0)
			(solder_paste_margin -0.15)
		)
		(pad "16" smd rect
			(at 2.4 1.625)
			(size 0.3 0.4)
			(layers "F.Cu" "F.Mask" "F.Paste")
			(net "+12V")
			(solder_mask_margin 0)
			(solder_paste_margin -0.15)
		)
		(pad "17" smd rect
			(at 2.4 0.975)
			(size 0.3 0.4)
			(layers "F.Cu" "F.Mask" "F.Paste")
			(net "+12V")
			(solder_mask_margin 0)
			(solder_paste_margin -0.15)
		)
		(pad "18" smd rect
			(at 2.4 0.325)
			(size 0.3 0.4)
			(layers "F.Cu" "F.Mask" "F.Paste")
			(net "+12V")
			(solder_mask_margin 0)
			(solder_paste_margin -0.15)
		)
		(pad "19" smd rect
			(at 2.4 -0.325)
			(size 0.3 0.4)
			(layers "F.Cu" "F.Mask" "F.Paste")
			(net "+12V")
			(solder_mask_margin 0)
			(solder_paste_margin -0.15)
		)
		(pad "20" smd rect
			(at 2.4 -0.975)
			(size 0.3 0.4)
			(layers "F.Cu" "F.Mask" "F.Paste")
			(net "NetR69_1")
			(solder_mask_margin 0)
			(solder_paste_margin -0.15)
		)
		(pad "21" smd rect
			(at 2.4 -1.625)
			(size 0.3 0.4)
			(layers "F.Cu" "F.Mask" "F.Paste")
			(net "GND")
			(solder_mask_margin 0)
			(solder_paste_margin -0.15)
		)
		(pad "22" smd rect
			(at 2.4 -2.275)
			(size 0.3 0.4)
			(layers "F.Cu" "F.Mask" "F.Paste")
			(net "NetC68_2")
			(solder_mask_margin 0)
			(solder_paste_margin -0.15)
		)
		(pad "23" smd rect
			(at 1.625 -2.9 270)
			(size 0.3 0.4)
			(layers "F.Cu" "F.Mask" "F.Paste")
			(net "GND")
			(solder_mask_margin 0)
			(solder_paste_margin -0.15)
		)
		(pad "24" smd rect
			(at 0.975 -2.9 270)
			(size 0.3 0.4)
			(layers "F.Cu" "F.Mask" "F.Paste")
			(net "P3V3_FB")
			(solder_mask_margin 0)
			(solder_paste_margin -0.15)
		)
		(pad "25" smd rect
			(at 0.325 -2.9 270)
			(size 0.3 0.4)
			(layers "F.Cu" "F.Mask" "F.Paste")
			(net "NetR68_2")
			(solder_mask_margin 0)
			(solder_paste_margin -0.15)
		)
		(pad "26" smd rect
			(at -0.325 -2.9 270)
			(size 0.3 0.4)
			(layers "F.Cu" "F.Mask" "F.Paste")
			(net "NetR67_2")
			(solder_mask_margin 0)
			(solder_paste_margin -0.15)
		)
		(pad "27" smd rect
			(at -0.975 -2.9 270)
			(size 0.3 0.4)
			(layers "F.Cu" "F.Mask" "F.Paste")
			(net "NetC71_1")
			(solder_mask_margin 0)
			(solder_paste_margin -0.15)
		)
		(pad "28" smd rect
			(at -1.625 -2.9 270)
			(size 0.3 0.4)
			(layers "F.Cu" "F.Mask" "F.Paste")
			(net "P3V3_VDD")
			(solder_mask_margin 0)
			(solder_paste_margin -0.15)
		)
		(pad "29" smd rect
			(at 0 -1.55 90)
			(size 3.69999 1.6)
			(layers "F.Cu" "F.Mask" "F.Paste")
			(net "GND")
			(solder_mask_margin 0)
			(solder_paste_margin -0.8)
		)
		(pad "30" smd rect
			(at -0.5 1.015 90)
			(size 2.2 2.82999)
			(layers "F.Cu" "F.Mask" "F.Paste")
			(net "NetL2_1")
			(solder_mask_margin 0)
			(solder_paste_margin 0)
		)
		(pad "31" smd rect
			(at 1.4 1.015 90)
			(size 0.9 2.82999)
			(layers "F.Cu" "F.Mask" "F.Paste")
		)
	)
	(footprint "Vault:FP-SML-LX0603IW-TR-MFG"
		(layer "F.Cu")
		(at 174.0261 88.0162 -90)
		(property "Reference" "D24"
			(at 0.4286 -1.573069 270)
			(unlocked yes)
			(layer "F.SilkS")
			(effects
				(font
					(size 0.762 0.762)
					(thickness 0.2286)
				)
			)
		)
		(property "Value" "SML-LX0603IW-TR"
			(at -3.519671 10.677135 180)
			(unlocked yes)
			(layer "F.SilkS")
			(hide yes)
			(effects
				(font
					(size 0.762 0.762)
					(thickness 0.2286)
				)
			)
		)
		(sheetname "USBUart_DipSelects")
		(sheetfile "USBUart_DipSelects.kicad_sch")
		(duplicate_pad_numbers_are_jumpers no)
		(fp_line
			(start 0.77933 0.73)
			(end -0.82067 0.73)
			(stroke
				(width 0.2)
				(type solid)
			)
			(layer "F.SilkS")
		)
		(fp_line
			(start 0.8 -0.75)
			(end -0.8 -0.75)
			(stroke
				(width 0.2)
				(type solid)
			)
			(layer "F.SilkS")
		)
		(fp_circle
			(center -1.725 0)
			(end -1.85 0)
			(stroke
				(width 0.25)
				(type solid)
			)
			(fill no)
			(layer "F.SilkS")
		)
		(fp_line
			(start -1.25 0.625)
			(end -1.25 -0.625)
			(stroke
				(width 0.2)
				(type solid)
			)
			(layer "F.CrtYd")
		)
		(fp_line
			(start 1.25 0.625)
			(end -1.25 0.625)
			(stroke
				(width 0.2)
				(type solid)
			)
			(layer "F.CrtYd")
		)
		(fp_line
			(start 1.25 0.625)
			(end 1.25 -0.625)
			(stroke
				(width 0.2)
				(type solid)
			)
			(layer "F.CrtYd")
		)
		(fp_line
			(start 1.25 -0.625)
			(end -1.25 -0.625)
			(stroke
				(width 0.2)
				(type solid)
			)
			(layer "F.CrtYd")
		)
		(fp_line
			(start -1.25 0.625)
			(end -1.25 -0.625)
			(stroke
				(width 0.2)
				(type solid)
			)
			(layer "F.Fab")
		)
		(fp_line
			(start 1.25 0.625)
			(end -1.25 0.625)
			(stroke
				(width 0.2)
				(type solid)
			)
			(layer "F.Fab")
		)
		(fp_line
			(start 1.25 0.625)
			(end 1.25 -0.625)
			(stroke
				(width 0.2)
				(type solid)
			)
			(layer "F.Fab")
		)
		(fp_line
			(start 0 0.5)
			(end 0 -0.5)
			(stroke
				(width 0.1)
				(type solid)
			)
			(layer "F.Fab")
		)
		(fp_line
			(start 0.5 0)
			(end -0.5 0)
			(stroke
				(width 0.1)
				(type solid)
			)
			(layer "F.Fab")
		)
		(fp_line
			(start 1.25 -0.625)
			(end -1.25 -0.625)
			(stroke
				(width 0.2)
				(type solid)
			)
			(layer "F.Fab")
		)
		(fp_text user "${REFERENCE}"
			(at 0 0.29535 270)
			(unlocked yes)
			(layer "F.Fab")
			(effects
				(font
					(face "Arial")
					(size 0.63 0.63)
					(thickness 0.1)
				)
				(justify left bottom)
			)
		)
		(pad "1" smd rect
			(at -0.75 0 270)
			(size 0.8 0.8)
			(layers "F.Cu" "F.Mask" "F.Paste")
			(net "NetD24_1")
			(solder_mask_margin 0)
			(solder_paste_margin 0)
		)
		(pad "2" smd rect
			(at 0.75 0 270)
			(size 0.8 0.8)
			(layers "F.Cu" "F.Mask" "F.Paste")
			(net "+3.3V")
			(solder_mask_margin 0)
			(solder_paste_margin 0)
		)
	)
	(footprint "Vault:RESC1005X40X25NL05T05"
		(layer "F.Cu")
		(at 208.9261 77.5162)
		(property "Reference" "R91"
			(at -0.371395 -1.173069 0)
			(unlocked yes)
			(layer "F.SilkS")
			(effects
				(font
					(size 0.762 0.762)
					(thickness 0.2286)
				)
			)
		)
		(property "Value" "27_1%_0402"
			(at -2.732271 7.37632 270)
			(unlocked yes)
			(layer "F.SilkS")
			(hide yes)
			(effects
				(font
					(size 0.762 0.762)
					(thickness 0.2286)
				)
			)
		)
		(sheetname "USBUart_DipSelects")
		(sheetfile "USBUart_DipSelects.kicad_sch")
		(duplicate_pad_numbers_are_jumpers no)
		(pad "1" smd rect
			(at -0.45 0 90)
			(size 0.55 0.55)
			(layers "F.Cu" "F.Mask" "F.Paste")
			(net "GPS2_TX_FPGA")
		)
		(pad "2" smd rect
			(at 0.45 0 90)
			(size 0.55 0.55)
			(layers "F.Cu" "F.Mask" "F.Paste")
			(net "NetR91_2")
		)
	)
	(footprint "SA53:SolderSocket"
		(layer "F.Cu")
		(at 99.3261 135.5162 90)
		(property "Reference" "SKT5"
			(at -6.626931 0.3286 0)
			(unlocked yes)
			(layer "F.SilkS")
			(effects
				(font
					(size 0.762 0.762)
					(thickness 0.2286)
				)
			)
		)
		(property "Value" "0332-0-43-80-18-27-10-0"
			(at -2.910071 16.1362 0)
			(unlocked yes)
			(layer "F.SilkS")
			(hide yes)
			(effects
				(font
					(size 0.762 0.762)
					(thickness 0.2286)
				)
			)
		)
		(sheetname "MAC")
		(sheetfile "MAC.kicad_sch")
		(duplicate_pad_numbers_are_jumpers no)
		(pad "1" thru_hole circle
			(at 0 0 90)
			(size 2.54 2.54)
			(drill 2.0066)
			(layers "*.Cu" "*.Mask")
			(remove_unused_layers no)
			(net "MAC_RF_OUT")
			(thermal_bridge_angle 90)
		)
	)
	(footprint "Vault:CAPC1005X56X25NL10T15"
		(layer "F.Cu")
		(at 226.6261 112.4162 90)
		(property "Reference" "C21"
			(at -1.3 -0.493345 270)
			(unlocked yes)
			(layer "F.SilkS")
			(effects
				(font
					(size 0.762 0.762)
					(thickness 0.2286)
				)
				(justify left bottom)
			)
		)
		(property "Value" "0.1uF_0402"
			(at 5.060155 26.4395 0)
			(unlocked yes)
			(layer "F.SilkS")
			(hide yes)
			(effects
				(font
					(size 0.762 0.762)
					(thickness 0.2286)
				)
				(justify left bottom)
			)
		)
		(sheetname "POWER")
		(sheetfile "POWER.kicad_sch")
		(duplicate_pad_numbers_are_jumpers no)
		(pad "1" smd rect
			(at -0.44 0 180)
			(size 0.64 0.68)
			(layers "F.Cu" "F.Mask" "F.Paste")
			(net "GND")
		)
		(pad "2" smd rect
			(at 0.44 0 180)
			(size 0.64 0.68)
			(layers "F.Cu" "F.Mask" "F.Paste")
			(net "+3.3V")
		)
	)
	(footprint "Vault:FP-STPS5L60S-MFG"
		(layer "F.Cu")
		(at 214.5261 89.2162 90)
		(property "Reference" "D12"
			(at -0.3286 3.973069 270)
			(unlocked yes)
			(layer "F.SilkS")
			(effects
				(font
					(size 0.762 0.762)
					(thickness 0.2286)
				)
			)
		)
		(property "Value" "STPS5L60S"
			(at -6.491471 3.76976 0)
			(unlocked yes)
			(layer "F.SilkS")
			(hide yes)
			(effects
				(font
					(size 0.762 0.762)
					(thickness 0.2286)
				)
			)
		)
		(sheetname "POWER")
		(sheetfile "POWER.kicad_sch")
		(duplicate_pad_numbers_are_jumpers no)
		(fp_line
			(start 3.575 -3.125)
			(end 3.575 -2.025)
			(stroke
				(width 0.2)
				(type solid)
			)
			(layer "F.SilkS")
		)
		(fp_line
			(start -3.575 -3.125)
			(end 3.575 -3.125)
			(stroke
				(width 0.2)
				(type solid)
			)
			(layer "F.SilkS")
		)
		(fp_line
			(start -3.575 -3.125)
			(end -3.575 -2.025)
			(stroke
				(width 0.2)
				(type solid)
			)
			(layer "F.SilkS")
		)
		(fp_line
			(start 3.575 2.025)
			(end 3.575 3.125)
			(stroke
				(width 0.2)
				(type solid)
			)
			(layer "F.SilkS")
		)
		(fp_line
			(start -3.575 2.025)
			(end -3.575 3.125)
			(stroke
				(width 0.2)
				(type solid)
			)
			(layer "F.SilkS")
		)
		(fp_line
			(start -3.575 3.125)
			(end 3.575 3.125)
			(stroke
				(width 0.2)
				(type solid)
			)
			(layer "F.SilkS")
		)
		(fp_circle
			(center -4.7 -0.025)
			(end -4.575 -0.025)
			(stroke
				(width 0.25)
				(type solid)
			)
			(fill no)
			(layer "F.SilkS")
		)
		(fp_line
			(start 4.195 -3.225)
			(end 4.195 3.225)
			(stroke
				(width 0.2)
				(type solid)
			)
			(layer "F.CrtYd")
		)
		(fp_line
			(start -4.195 -3.225)
			(end 4.195 -3.225)
			(stroke
				(width 0.2)
				(type solid)
			)
			(layer "F.CrtYd")
		)
		(fp_line
			(start -4.195 -3.225)
			(end -4.195 3.225)
			(stroke
				(width 0.2)
				(type solid)
			)
			(layer "F.CrtYd")
		)
		(fp_line
			(start -4.195 3.225)
			(end 4.195 3.225)
			(stroke
				(width 0.2)
				(type solid)
			)
			(layer "F.CrtYd")
		)
		(fp_line
			(start 4.195 -3.225)
			(end 4.195 3.225)
			(stroke
				(width 0.2)
				(type solid)
			)
			(layer "F.Fab")
		)
		(fp_line
			(start -4.195 -3.225)
			(end 4.195 -3.225)
			(stroke
				(width 0.2)
				(type solid)
			)
			(layer "F.Fab")
		)
		(fp_line
			(start -4.195 -3.225)
			(end -4.195 3.225)
			(stroke
				(width 0.2)
				(type solid)
			)
			(layer "F.Fab")
		)
		(fp_line
			(start 0 -0.5)
			(end 0 0.5)
			(stroke
				(width 0.1)
				(type solid)
			)
			(layer "F.Fab")
		)
		(fp_line
			(start -0.5 0)
			(end 0.5 0)
			(stroke
				(width 0.1)
				(type solid)
			)
			(layer "F.Fab")
		)
		(fp_line
			(start -4.195 3.225)
			(end 4.195 3.225)
			(stroke
				(width 0.2)
				(type solid)
			)
			(layer "F.Fab")
		)
		(fp_text user "${REFERENCE}"
			(at -0.00002 0.10711 90)
			(unlocked yes)
			(layer "F.Fab")
			(effects
				(font
					(face "Arial")
					(size 0.63 0.63)
					(thickness 0.1)
				)
				(justify left bottom)
			)
		)
		(pad "1" smd rect
			(at -3.325 0 90)
			(size 1.54 3.14)
			(layers "F.Cu" "F.Mask" "F.Paste")
			(net "NetD12_1")
			(solder_mask_margin 0)
			(solder_paste_margin 0)
		)
		(pad "2" smd rect
			(at 3.325 0 90)
			(size 1.54 3.14)
			(layers "F.Cu" "F.Mask" "F.Paste")
			(net "NetD12_2")
			(solder_mask_margin 0)
			(solder_paste_margin 0)
		)
	)
	(footprint "Vault:RESC1608X55X30NL15T15"
		(layer "F.Cu")
		(at 82.3761 125.8662 -90)
		(property "Reference" "R17"
			(at 2.7714 -0.026921 90)
			(unlocked yes)
			(layer "F.SilkS")
			(effects
				(font
					(size 0.762 0.762)
					(thickness 0.2286)
				)
			)
		)
		(property "Value" "4.7K"
			(at -2.884671 3.18659 180)
			(unlocked yes)
			(layer "F.SilkS")
			(hide yes)
			(effects
				(font
					(size 0.762 0.762)
					(thickness 0.2286)
				)
			)
		)
		(sheetname "USER_IO")
		(sheetfile "USER_IO.kicad_sch")
		(duplicate_pad_numbers_are_jumpers no)
		(pad "1" smd rect
			(at -0.75 0)
			(size 0.95 0.95)
			(layers "F.Cu" "F.Mask" "F.Paste")
			(net "ANT3_IO_IN")
		)
		(pad "2" smd rect
			(at 0.75 0)
			(size 0.95 0.95)
			(layers "F.Cu" "F.Mask" "F.Paste")
			(net "+3.3V")
		)
	)
	(footprint "SA53:SolderSocket"
		(layer "F.Cu")
		(at 137.8261 138.2162 90)
		(property "Reference" "SKT4"
			(at -3.426921 3.0286 0)
			(unlocked yes)
			(layer "F.SilkS")
			(effects
				(font
					(size 0.762 0.762)
					(thickness 0.2286)
				)
			)
		)
		(property "Value" "0332-0-43-80-18-27-10-0"
			(at -2.910071 16.1362 0)
			(unlocked yes)
			(layer "F.SilkS")
			(hide yes)
			(effects
				(font
					(size 0.762 0.762)
					(thickness 0.2286)
				)
			)
		)
		(sheetname "MAC")
		(sheetfile "MAC.kicad_sch")
		(duplicate_pad_numbers_are_jumpers no)
		(pad "1" thru_hole circle
			(at 0 0 90)
			(size 2.54 2.54)
			(drill 2.0066)
			(layers "*.Cu" "*.Mask")
			(remove_unused_layers no)
			(net "MAC_BITE")
			(thermal_bridge_angle 90)
		)
	)
	(footprint "Vault:RESC3216X89X64NL25T25"
		(layer "F.Cu")
		(at 225.9261 107.4162 90)
		(property "Reference" "R8"
			(at 1.7 1.206655 270)
			(unlocked yes)
			(layer "F.SilkS")
			(effects
				(font
					(size 0.762 0.762)
					(thickness 0.2286)
				)
				(justify left bottom)
			)
		)
		(property "Value" "2mOhm_1%_1206"
			(at -6.763245 16.2553 0)
			(unlocked yes)
			(layer "F.SilkS")
			(hide yes)
			(effects
				(font
					(size 0.762 0.762)
					(thickness 0.2286)
				)
				(justify left bottom)
			)
		)
		(sheetname "POWER")
		(sheetfile "POWER.kicad_sch")
		(duplicate_pad_numbers_are_jumpers no)
		(fp_line
			(start -0.2 -0.825)
			(end 0.2 -0.825)
			(stroke
				(width 0.2)
				(type solid)
			)
			(layer "F.SilkS")
		)
		(fp_line
			(start -0.2 0.825)
			(end 0.2 0.825)
			(stroke
				(width 0.2)
				(type solid)
			)
			(layer "F.SilkS")
		)
		(pad "1" smd rect
			(at -1.325 0 180)
			(size 1.85 1.5)
			(layers "F.Cu" "F.Mask" "F.Paste")
			(net "P5V_SENSE")
		)
		(pad "2" smd rect
			(at 1.325 0 180)
			(size 1.85 1.5)
			(layers "F.Cu" "F.Mask" "F.Paste")
			(net "+5.0V")
		)
	)
	(footprint "Vault:RESC1608X55X30NL15T15"
		(layer "F.Cu")
		(at 71.6261 55.6162 90)
		(property "Reference" "R36"
			(at -5.7714 -0.223079 90)
			(unlocked yes)
			(layer "F.SilkS")
			(effects
				(font
					(size 0.762 0.762)
					(thickness 0.2286)
				)
			)
		)
		(property "Value" "200 OHM"
			(at -2.935471 4.78626 0)
			(unlocked yes)
			(layer "F.SilkS")
			(hide yes)
			(effects
				(font
					(size 0.762 0.762)
					(thickness 0.2286)
				)
			)
		)
		(sheetname "USER_IO_STATUS")
		(sheetfile "USER_IO_STATUS.kicad_sch")
		(duplicate_pad_numbers_are_jumpers no)
		(pad "1" smd rect
			(at -0.675 0 180)
			(size 0.95 0.8)
			(layers "F.Cu" "F.Mask" "F.Paste")
			(net "LED2")
		)
		(pad "2" smd rect
			(at 0.675 0 180)
			(size 0.95 0.8)
			(layers "F.Cu" "F.Mask" "F.Paste")
			(net "NetD9_1")
		)
	)
	(footprint "Vault:FP-0603-L_1_6_0_2-W_0_8_0-MFG"
		(layer "F.Cu")
		(at 226.5261 130.0162 -90)
		(property "Reference" "C85"
			(at -0.2286 1.573079 90)
			(unlocked yes)
			(layer "F.SilkS")
			(effects
				(font
					(size 0.762 0.762)
					(thickness 0.2286)
				)
			)
		)
		(property "Value" "10uF_16V_0603"
			(at -2.871951 8.95046 180)
			(unlocked yes)
			(layer "F.SilkS")
			(hide yes)
			(effects
				(font
					(size 0.762 0.762)
					(thickness 0.2286)
				)
			)
		)
		(sheetname "POWER")
		(sheetfile "POWER.kicad_sch")
		(duplicate_pad_numbers_are_jumpers no)
		(fp_line
			(start 0.9 0.825)
			(end -0.9 0.825)
			(stroke
				(width 0.2)
				(type solid)
			)
			(layer "F.SilkS")
		)
		(fp_line
			(start 0.9 -0.825)
			(end -0.9 -0.825)
			(stroke
				(width 0.2)
				(type solid)
			)
			(layer "F.SilkS")
		)
		(fp_line
			(start -1.15 0.6)
			(end -1.15 -0.6)
			(stroke
				(width 0.2)
				(type solid)
			)
			(layer "F.CrtYd")
		)
		(fp_line
			(start 1.15 0.6)
			(end -1.15 0.6)
			(stroke
				(width 0.2)
				(type solid)
			)
			(layer "F.CrtYd")
		)
		(fp_line
			(start 1.15 0.6)
			(end 1.15 -0.6)
			(stroke
				(width 0.2)
				(type solid)
			)
			(layer "F.CrtYd")
		)
		(fp_line
			(start 1.15 -0.6)
			(end -1.15 -0.6)
			(stroke
				(width 0.2)
				(type solid)
			)
			(layer "F.CrtYd")
		)
		(fp_line
			(start -1.15 0.6)
			(end -1.15 -0.6)
			(stroke
				(width 0.2)
				(type solid)
			)
			(layer "F.Fab")
		)
		(fp_line
			(start 1.15 0.6)
			(end -1.15 0.6)
			(stroke
				(width 0.2)
				(type solid)
			)
			(layer "F.Fab")
		)
		(fp_line
			(start 1.15 0.6)
			(end 1.15 -0.6)
			(stroke
				(width 0.2)
				(type solid)
			)
			(layer "F.Fab")
		)
		(fp_line
			(start 0 0.5)
			(end 0 -0.5)
			(stroke
				(width 0.1)
				(type solid)
			)
			(layer "F.Fab")
		)
		(fp_line
			(start 0.5 0)
			(end -0.5 0)
			(stroke
				(width 0.1)
				(type solid)
			)
			(layer "F.Fab")
		)
		(fp_line
			(start 1.15 -0.6)
			(end -1.15 -0.6)
			(stroke
				(width 0.2)
				(type solid)
			)
			(layer "F.Fab")
		)
		(fp_text user "${REFERENCE}"
			(at -0.00001 0.09602 270)
			(unlocked yes)
			(layer "F.Fab")
			(effects
				(font
					(face "Arial")
					(size 0.63 0.63)
					(thickness 0.1)
				)
				(justify left bottom)
			)
		)
		(pad "1" smd rect
			(at -0.7 0 270)
			(size 0.7 0.7)
			(layers "F.Cu" "F.Mask" "F.Paste")
			(net "+3.3V")
			(solder_mask_margin 0)
			(solder_paste_margin 0)
		)
		(pad "2" smd rect
			(at 0.7 0 270)
			(size 0.7 0.7)
			(layers "F.Cu" "F.Mask" "F.Paste")
			(net "GND")
			(solder_mask_margin 0)
			(solder_paste_margin 0)
		)
	)
	(footprint "Vault:FP-MK212BG-MFG"
		(layer "F.Cu")
		(at 94.3761 74.4286 -90)
		(property "Reference" "C58"
			(at 4.4 -0.843345 90)
			(unlocked yes)
			(layer "F.SilkS")
			(effects
				(font
					(size 0.762 0.762)
					(thickness 0.2286)
				)
				(justify left bottom)
			)
		)
		(property "Value" "10uF"
			(at 5.233445 1.5875 0)
			(unlocked yes)
			(layer "F.SilkS")
			(hide yes)
			(effects
				(font
					(size 0.762 0.762)
					(thickness 0.2286)
				)
				(justify left bottom)
			)
		)
		(sheetname "GPS_IMU_SENSORS")
		(sheetfile "GPS_IMU_SENSORS.kicad_sch")
		(duplicate_pad_numbers_are_jumpers no)
		(fp_line
			(start 0.125 0.725)
			(end -0.125 0.725)
			(stroke
				(width 0.2)
				(type solid)
			)
			(layer "F.SilkS")
		)
		(fp_line
			(start 0.125 -0.725)
			(end -0.125 -0.725)
			(stroke
				(width 0.2)
				(type solid)
			)
			(layer "F.SilkS")
		)
		(fp_line
			(start -1.6 0.825)
			(end -1.6 -0.825)
			(stroke
				(width 0.2)
				(type solid)
			)
			(layer "F.CrtYd")
		)
		(fp_line
			(start 1.6 0.825)
			(end -1.6 0.825)
			(stroke
				(width 0.2)
				(type solid)
			)
			(layer "F.CrtYd")
		)
		(fp_line
			(start 1.6 0.825)
			(end 1.6 -0.825)
			(stroke
				(width 0.2)
				(type solid)
			)
			(layer "F.CrtYd")
		)
		(fp_line
			(start 1.6 -0.825)
			(end -1.6 -0.825)
			(stroke
				(width 0.2)
				(type solid)
			)
			(layer "F.CrtYd")
		)
		(fp_line
			(start -1.6 0.825)
			(end -1.6 -0.825)
			(stroke
				(width 0.2)
				(type solid)
			)
			(layer "F.Fab")
		)
		(fp_line
			(start 1.6 0.825)
			(end -1.6 0.825)
			(stroke
				(width 0.2)
				(type solid)
			)
			(layer "F.Fab")
		)
		(fp_line
			(start 1.6 0.825)
			(end 1.6 -0.825)
			(stroke
				(width 0.2)
				(type solid)
			)
			(layer "F.Fab")
		)
		(fp_line
			(start 0 0.5)
			(end 0 -0.5)
			(stroke
				(width 0.1)
				(type solid)
			)
			(layer "F.Fab")
		)
		(fp_line
			(start 0.5 0)
			(end -0.5 0)
			(stroke
				(width 0.1)
				(type solid)
			)
			(layer "F.Fab")
		)
		(fp_line
			(start 1.6 -0.825)
			(end -1.6 -0.825)
			(stroke
				(width 0.2)
				(type solid)
			)
			(layer "F.Fab")
		)
		(fp_text user "${REFERENCE}"
			(at -0.00001 0.09602 270)
			(unlocked yes)
			(layer "F.Fab")
			(effects
				(font
					(face "Arial")
					(size 0.63 0.63)
					(thickness 0.1)
				)
				(justify left bottom)
			)
		)
		(pad "1" smd rect
			(at -1 0 270)
			(size 1 1.25)
			(layers "F.Cu" "F.Mask" "F.Paste")
			(net "+3.3V")
			(solder_mask_margin 0)
			(solder_paste_margin 0)
		)
		(pad "2" smd rect
			(at 1 0 270)
			(size 1 1.25)
			(layers "F.Cu" "F.Mask" "F.Paste")
			(net "GND")
			(solder_mask_margin 0)
			(solder_paste_margin 0)
		)
	)
	(footprint "Vault:FP-0402-L_1_0_1-W_0_5_0_1-IPC_C"
		(layer "F.Cu")
		(at 239.3261 71.9162)
		(property "Reference" "C89"
			(at -1.8714 0.226921 0)
			(unlocked yes)
			(layer "F.SilkS")
			(effects
				(font
					(size 0.762 0.762)
					(thickness 0.2286)
				)
			)
		)
		(property "Value" "0.1uF_25V_0402"
			(at -2.465551 9.839215 270)
			(unlocked yes)
			(layer "F.SilkS")
			(hide yes)
			(effects
				(font
					(size 0.762 0.762)
					(thickness 0.2286)
				)
			)
		)
		(sheetname "USBUart_DipSelects")
		(sheetfile "USBUart_DipSelects.kicad_sch")
		(duplicate_pad_numbers_are_jumpers no)
		(fp_line
			(start -0.65607 -0.7)
			(end 0.65607 -0.7)
			(stroke
				(width 0.2)
				(type solid)
			)
			(layer "F.SilkS")
		)
		(fp_line
			(start -0.65607 0.7)
			(end 0.65607 0.7)
			(stroke
				(width 0.2)
				(type solid)
			)
			(layer "F.SilkS")
		)
		(fp_line
			(start -0.75607 -0.4)
			(end 0.75607 -0.4)
			(stroke
				(width 0.2)
				(type solid)
			)
			(layer "F.CrtYd")
		)
		(fp_line
			(start -0.75607 0.4)
			(end -0.75607 -0.4)
			(stroke
				(width 0.2)
				(type solid)
			)
			(layer "F.CrtYd")
		)
		(fp_line
			(start -0.75607 0.4)
			(end 0.75607 0.4)
			(stroke
				(width 0.2)
				(type solid)
			)
			(layer "F.CrtYd")
		)
		(fp_line
			(start 0.75607 0.4)
			(end 0.75607 -0.4)
			(stroke
				(width 0.2)
				(type solid)
			)
			(layer "F.CrtYd")
		)
		(fp_line
			(start -0.75607 -0.4)
			(end 0.75607 -0.4)
			(stroke
				(width 0.2)
				(type solid)
			)
			(layer "F.Fab")
		)
		(fp_line
			(start -0.75607 0.4)
			(end -0.75607 -0.4)
			(stroke
				(width 0.2)
				(type solid)
			)
			(layer "F.Fab")
		)
		(fp_line
			(start -0.75607 0.4)
			(end 0.75607 0.4)
			(stroke
				(width 0.2)
				(type solid)
			)
			(layer "F.Fab")
		)
		(fp_line
			(start -0.5 0)
			(end 0.5 0)
			(stroke
				(width 0.1)
				(type solid)
			)
			(layer "F.Fab")
		)
		(fp_line
			(start 0 0.5)
			(end 0 -0.5)
			(stroke
				(width 0.1)
				(type solid)
			)
			(layer "F.Fab")
		)
		(fp_line
			(start 0.75607 0.4)
			(end 0.75607 -0.4)
			(stroke
				(width 0.2)
				(type solid)
			)
			(layer "F.Fab")
		)
		(fp_text user "${REFERENCE}"
			(at -0.00001 0.09602 360)
			(unlocked yes)
			(layer "F.Fab")
			(effects
				(font
					(face "Arial")
					(size 0.63 0.63)
					(thickness 0.1)
				)
				(justify left bottom)
			)
		)
		(pad "1" smd rect
			(at -0.36554 0)
			(size 0.58106 0.51213)
			(layers "F.Cu" "F.Mask" "F.Paste")
			(net "FTDI_VBUS")
			(solder_mask_margin 0)
			(solder_paste_margin 0)
		)
		(pad "2" smd rect
			(at 0.36554 0)
			(size 0.58106 0.51213)
			(layers "F.Cu" "F.Mask" "F.Paste")
			(net "GND")
			(solder_mask_margin 0)
			(solder_paste_margin 0)
		)
	)
	(footprint "Vault:FP-D0008A-MFG"
		(layer "F.Cu")
		(at 233.1261 113.1162 180)
		(property "Reference" "U17"
			(at -2.8714 -3.273069 180)
			(unlocked yes)
			(layer "F.SilkS")
			(effects
				(font
					(size 0.762 0.762)
					(thickness 0.2286)
				)
			)
		)
		(property "Value" "INA219BIDR"
			(at 3.16004 4.408671 180)
			(unlocked yes)
			(layer "F.SilkS")
			(hide yes)
			(effects
				(font
					(size 0.762 0.762)
					(thickness 0.2286)
				)
			)
		)
		(sheetname "POWER")
		(sheetfile "POWER.kicad_sch")
		(duplicate_pad_numbers_are_jumpers no)
		(fp_line
			(start 1.5 2.5)
			(end -1.5 2.5)
			(stroke
				(width 0.2)
				(type solid)
			)
			(layer "F.SilkS")
		)
		(fp_line
			(start 1.5 -2.5)
			(end 1.5 2.5)
			(stroke
				(width 0.2)
				(type solid)
			)
			(layer "F.SilkS")
		)
		(fp_line
			(start 1.5 -2.5)
			(end -1.5 -2.5)
			(stroke
				(width 0.2)
				(type solid)
			)
			(layer "F.SilkS")
		)
		(fp_line
			(start -1.5 -2.5)
			(end -1.5 2.5)
			(stroke
				(width 0.2)
				(type solid)
			)
			(layer "F.SilkS")
		)
		(fp_circle
			(center -0.725 -1.725)
			(end -0.725 -1.475)
			(stroke
				(width 0.5)
				(type solid)
			)
			(fill no)
			(layer "F.SilkS")
		)
		(fp_circle
			(center -4.05 -1.905)
			(end -4.05 -1.78)
			(stroke
				(width 0.25)
				(type solid)
			)
			(fill no)
			(layer "F.SilkS")
		)
		(fp_line
			(start 3.575 2.75)
			(end -3.575 2.75)
			(stroke
				(width 0.2)
				(type solid)
			)
			(layer "F.CrtYd")
		)
		(fp_line
			(start 3.575 -2.75)
			(end 3.575 2.75)
			(stroke
				(width 0.2)
				(type solid)
			)
			(layer "F.CrtYd")
		)
		(fp_line
			(start 3.575 -2.75)
			(end -3.575 -2.75)
			(stroke
				(width 0.2)
				(type solid)
			)
			(layer "F.CrtYd")
		)
		(fp_line
			(start -3.575 -2.75)
			(end -3.575 2.75)
			(stroke
				(width 0.2)
				(type solid)
			)
			(layer "F.CrtYd")
		)
		(fp_line
			(start 3.575 2.75)
			(end -3.575 2.75)
			(stroke
				(width 0.2)
				(type solid)
			)
			(layer "F.Fab")
		)
		(fp_line
			(start 3.575 -2.75)
			(end 3.575 2.75)
			(stroke
				(width 0.2)
				(type solid)
			)
			(layer "F.Fab")
		)
		(fp_line
			(start 3.575 -2.75)
			(end -3.575 -2.75)
			(stroke
				(width 0.2)
				(type solid)
			)
			(layer "F.Fab")
		)
		(fp_line
			(start 0.5 0)
			(end -0.5 0)
			(stroke
				(width 0.1)
				(type solid)
			)
			(layer "F.Fab")
		)
		(fp_line
			(start 0 -0.5)
			(end 0 0.5)
			(stroke
				(width 0.1)
				(type solid)
			)
			(layer "F.Fab")
		)
		(fp_line
			(start -3.575 -2.75)
			(end -3.575 2.75)
			(stroke
				(width 0.2)
				(type solid)
			)
			(layer "F.Fab")
		)
		(fp_text user "${REFERENCE}"
			(at -0.00001 0.09601 180)
			(unlocked yes)
			(layer "F.Fab")
			(effects
				(font
					(face "Arial")
					(size 0.63 0.63)
					(thickness 0.1)
				)
				(justify left bottom)
			)
		)
		(pad "1" smd roundrect
			(at -2.7 -1.905 180)
			(size 1.55 0.6)
			(layers "F.Cu" "F.Mask" "F.Paste")
			(roundrect_rratio 0.085)
			(net "NetR66_1")
			(solder_mask_margin 0)
			(solder_paste_margin 0)
		)
		(pad "2" smd roundrect
			(at -2.7 -0.635 180)
			(size 1.55 0.6)
			(layers "F.Cu" "F.Mask" "F.Paste")
			(roundrect_rratio 0.085)
			(net "NetR65_1")
			(solder_mask_margin 0)
			(solder_paste_margin 0)
		)
		(pad "3" smd roundrect
			(at -2.7 0.635 180)
			(size 1.55 0.6)
			(layers "F.Cu" "F.Mask" "F.Paste")
			(roundrect_rratio 0.085)
			(net "SDA")
			(solder_mask_margin 0)
			(solder_paste_margin 0)
		)
		(pad "4" smd roundrect
			(at -2.7 1.905 180)
			(size 1.55 0.6)
			(layers "F.Cu" "F.Mask" "F.Paste")
			(roundrect_rratio 0.085)
			(net "SCL")
			(solder_mask_margin 0)
			(solder_paste_margin 0)
		)
		(pad "5" smd roundrect
			(at 2.7 1.905 180)
			(size 1.55 0.6)
			(layers "F.Cu" "F.Mask" "F.Paste")
			(roundrect_rratio 0.085)
			(net "+3.3V")
			(solder_mask_margin 0)
			(solder_paste_margin 0)
		)
		(pad "6" smd roundrect
			(at 2.7 0.635 180)
			(size 1.55 0.6)
			(layers "F.Cu" "F.Mask" "F.Paste")
			(roundrect_rratio 0.085)
			(net "GND")
			(solder_mask_margin 0)
			(solder_paste_margin 0)
		)
		(pad "7" smd roundrect
			(at 2.7 -0.635 180)
			(size 1.55 0.6)
			(layers "F.Cu" "F.Mask" "F.Paste")
			(roundrect_rratio 0.085)
			(net "+5.0V")
			(solder_mask_margin 0)
			(solder_paste_margin 0)
		)
		(pad "8" smd roundrect
			(at 2.7 -1.905 180)
			(size 1.55 0.6)
			(layers "F.Cu" "F.Mask" "F.Paste")
			(roundrect_rratio 0.085)
			(net "P5V_SENSE")
			(solder_mask_margin 0)
			(solder_paste_margin 0)
		)
	)
	(footprint "Vault:FP-D0008A-MFG"
		(layer "F.Cu")
		(at 231.1261 131.3162 180)
		(property "Reference" "U19"
			(at -0.2286 3.373079 0)
			(unlocked yes)
			(layer "F.SilkS")
			(effects
				(font
					(size 0.762 0.762)
					(thickness 0.2286)
				)
			)
		)
		(property "Value" "INA219BIDR"
			(at 3.16005 4.408671 180)
			(unlocked yes)
			(layer "F.SilkS")
			(hide yes)
			(effects
				(font
					(size 0.762 0.762)
					(thickness 0.2286)
				)
			)
		)
		(sheetname "POWER")
		(sheetfile "POWER.kicad_sch")
		(duplicate_pad_numbers_are_jumpers no)
		(fp_line
			(start 1.5 2.5)
			(end -1.5 2.5)
			(stroke
				(width 0.2)
				(type solid)
			)
			(layer "F.SilkS")
		)
		(fp_line
			(start 1.5 -2.5)
			(end 1.5 2.5)
			(stroke
				(width 0.2)
				(type solid)
			)
			(layer "F.SilkS")
		)
		(fp_line
			(start 1.5 -2.5)
			(end -1.5 -2.5)
			(stroke
				(width 0.2)
				(type solid)
			)
			(layer "F.SilkS")
		)
		(fp_line
			(start -1.5 -2.5)
			(end -1.5 2.5)
			(stroke
				(width 0.2)
				(type solid)
			)
			(layer "F.SilkS")
		)
		(fp_circle
			(center -0.725 -1.725)
			(end -0.725 -1.475)
			(stroke
				(width 0.5)
				(type solid)
			)
			(fill no)
			(layer "F.SilkS")
		)
		(fp_circle
			(center -4.05 -1.905)
			(end -4.05 -1.78)
			(stroke
				(width 0.25)
				(type solid)
			)
			(fill no)
			(layer "F.SilkS")
		)
		(fp_line
			(start 3.575 2.75)
			(end -3.575 2.75)
			(stroke
				(width 0.2)
				(type solid)
			)
			(layer "F.CrtYd")
		)
		(fp_line
			(start 3.575 -2.75)
			(end 3.575 2.75)
			(stroke
				(width 0.2)
				(type solid)
			)
			(layer "F.CrtYd")
		)
		(fp_line
			(start 3.575 -2.75)
			(end -3.575 -2.75)
			(stroke
				(width 0.2)
				(type solid)
			)
			(layer "F.CrtYd")
		)
		(fp_line
			(start -3.575 -2.75)
			(end -3.575 2.75)
			(stroke
				(width 0.2)
				(type solid)
			)
			(layer "F.CrtYd")
		)
		(fp_line
			(start 3.575 2.75)
			(end -3.575 2.75)
			(stroke
				(width 0.2)
				(type solid)
			)
			(layer "F.Fab")
		)
		(fp_line
			(start 3.575 -2.75)
			(end 3.575 2.75)
			(stroke
				(width 0.2)
				(type solid)
			)
			(layer "F.Fab")
		)
		(fp_line
			(start 3.575 -2.75)
			(end -3.575 -2.75)
			(stroke
				(width 0.2)
				(type solid)
			)
			(layer "F.Fab")
		)
		(fp_line
			(start 0.5 0)
			(end -0.49999 0)
			(stroke
				(width 0.1)
				(type solid)
			)
			(layer "F.Fab")
		)
		(fp_line
			(start 0 -0.5)
			(end 0 0.5)
			(stroke
				(width 0.1)
				(type solid)
			)
			(layer "F.Fab")
		)
		(fp_line
			(start -3.575 -2.75)
			(end -3.575 2.75)
			(stroke
				(width 0.2)
				(type solid)
			)
			(layer "F.Fab")
		)
		(fp_text user "${REFERENCE}"
			(at 0 0.09601 180)
			(unlocked yes)
			(layer "F.Fab")
			(effects
				(font
					(face "Arial")
					(size 0.63 0.63)
					(thickness 0.1)
				)
				(justify left bottom)
			)
		)
		(pad "1" smd roundrect
			(at -2.7 -1.905 180)
			(size 1.55 0.6)
			(layers "F.Cu" "F.Mask" "F.Paste")
			(roundrect_rratio 0.085)
			(net "NetR80_1")
			(solder_mask_margin 0)
			(solder_paste_margin 0)
		)
		(pad "2" smd roundrect
			(at -2.7 -0.635 180)
			(size 1.55 0.6)
			(layers "F.Cu" "F.Mask" "F.Paste")
			(roundrect_rratio 0.085)
			(net "NetR79_1")
			(solder_mask_margin 0)
			(solder_paste_margin 0)
		)
		(pad "3" smd roundrect
			(at -2.7 0.635 180)
			(size 1.55 0.6)
			(layers "F.Cu" "F.Mask" "F.Paste")
			(roundrect_rratio 0.085)
			(net "SDA")
			(solder_mask_margin 0)
			(solder_paste_margin 0)
		)
		(pad "4" smd roundrect
			(at -2.7 1.905 180)
			(size 1.55 0.6)
			(layers "F.Cu" "F.Mask" "F.Paste")
			(roundrect_rratio 0.085)
			(net "SCL")
			(solder_mask_margin 0)
			(solder_paste_margin 0)
		)
		(pad "5" smd roundrect
			(at 2.7 1.905 180)
			(size 1.55 0.6)
			(layers "F.Cu" "F.Mask" "F.Paste")
			(roundrect_rratio 0.085)
			(net "+3.3V")
			(solder_mask_margin 0)
			(solder_paste_margin 0)
		)
		(pad "6" smd roundrect
			(at 2.7 0.635 180)
			(size 1.55 0.6)
			(layers "F.Cu" "F.Mask" "F.Paste")
			(roundrect_rratio 0.085)
			(net "GND")
			(solder_mask_margin 0)
			(solder_paste_margin 0)
		)
		(pad "7" smd roundrect
			(at 2.7 -0.635 180)
			(size 1.55 0.6)
			(layers "F.Cu" "F.Mask" "F.Paste")
			(roundrect_rratio 0.085)
			(net "+3.3V")
			(solder_mask_margin 0)
			(solder_paste_margin 0)
		)
		(pad "8" smd roundrect
			(at 2.7 -1.905 180)
			(size 1.55 0.6)
			(layers "F.Cu" "F.Mask" "F.Paste")
			(roundrect_rratio 0.085)
			(net "P3V3_SENSE")
			(solder_mask_margin 0)
			(solder_paste_margin 0)
		)
	)
	(footprint "Vault:FP-C0603C105K3PACTU-MFG"
		(layer "F.Cu")
		(at 82.3761 86.9662 -90)
		(property "Reference" "C38"
			(at -0.3286 2.973069 90)
			(unlocked yes)
			(layer "F.SilkS")
			(effects
				(font
					(size 0.762 0.762)
					(thickness 0.2286)
				)
			)
		)
		(property "Value" "1uF"
			(at -2.859281 1.45988 180)
			(unlocked yes)
			(layer "F.SilkS")
			(hide yes)
			(effects
				(font
					(size 0.762 0.762)
					(thickness 0.2286)
				)
			)
		)
		(sheetname "USER_IO_STATUS")
		(sheetfile "USER_IO_STATUS.kicad_sch")
		(duplicate_pad_numbers_are_jumpers no)
		(fp_line
			(start 0.875 0.825)
			(end -0.875 0.825)
			(stroke
				(width 0.2)
				(type solid)
			)
			(layer "F.SilkS")
		)
		(fp_line
			(start 0.875 -0.825)
			(end -0.875 -0.825)
			(stroke
				(width 0.2)
				(type solid)
			)
			(layer "F.SilkS")
		)
		(fp_line
			(start -1.2 0.6)
			(end -1.2 -0.6)
			(stroke
				(width 0.2)
				(type solid)
			)
			(layer "F.CrtYd")
		)
		(fp_line
			(start 1.2 0.6)
			(end -1.2 0.6)
			(stroke
				(width 0.2)
				(type solid)
			)
			(layer "F.CrtYd")
		)
		(fp_line
			(start 1.2 0.6)
			(end 1.2 -0.6)
			(stroke
				(width 0.2)
				(type solid)
			)
			(layer "F.CrtYd")
		)
		(fp_line
			(start 1.2 -0.6)
			(end -1.2 -0.6)
			(stroke
				(width 0.2)
				(type solid)
			)
			(layer "F.CrtYd")
		)
		(fp_line
			(start -1.2 0.6)
			(end -1.2 -0.6)
			(stroke
				(width 0.2)
				(type solid)
			)
			(layer "F.Fab")
		)
		(fp_line
			(start 1.2 0.6)
			(end -1.2 0.6)
			(stroke
				(width 0.2)
				(type solid)
			)
			(layer "F.Fab")
		)
		(fp_line
			(start 1.2 0.6)
			(end 1.2 -0.6)
			(stroke
				(width 0.2)
				(type solid)
			)
			(layer "F.Fab")
		)
		(fp_line
			(start 0 0.5)
			(end 0 -0.5)
			(stroke
				(width 0.1)
				(type solid)
			)
			(layer "F.Fab")
		)
		(fp_line
			(start 0.5 0)
			(end -0.5 0)
			(stroke
				(width 0.1)
				(type solid)
			)
			(layer "F.Fab")
		)
		(fp_line
			(start 1.2 -0.6)
			(end -1.2 -0.6)
			(stroke
				(width 0.2)
				(type solid)
			)
			(layer "F.Fab")
		)
		(pad "1" smd rect
			(at -0.6 0 270)
			(size 0.75 0.9)
			(layers "F.Cu" "F.Mask" "F.Paste")
			(net "+3.3V")
			(solder_mask_margin 0)
			(solder_paste_margin 0)
		)
		(pad "2" smd rect
			(at 0.6 0 270)
			(size 0.75 0.9)
			(layers "F.Cu" "F.Mask" "F.Paste")
			(net "GND")
			(solder_mask_margin 0)
			(solder_paste_margin 0)
		)
	)
	(footprint "Passives:SOT65P210X110-3N"
		(layer "F.Cu")
		(at 195.08636 143.47763)
		(property "Reference" "D6"
			(at -3.16026 -1.068085 0)
			(unlocked yes)
			(layer "F.SilkS")
			(effects
				(font
					(size 0.762 0.762)
					(thickness 0.2286)
				)
				(justify left bottom)
			)
		)
		(property "Value" "BAT54SW"
			(at -4.0249 -1.823555 0)
			(unlocked yes)
			(layer "F.SilkS")
			(hide yes)
			(effects
				(font
					(size 0.762 0.762)
					(thickness 0.2286)
				)
				(justify left bottom)
			)
		)
		(sheetname "PCIe_JTAG")
		(sheetfile "PCIe_JTAG.kicad_sch")
		(duplicate_pad_numbers_are_jumpers no)
		(fp_line
			(start -0.325 -1.1)
			(end 0.675 -1.1)
			(stroke
				(width 0.2)
				(type solid)
			)
			(layer "F.SilkS")
		)
		(fp_line
			(start -0.325 1.1)
			(end 0.675 1.1)
			(stroke
				(width 0.2)
				(type solid)
			)
			(layer "F.SilkS")
		)
		(fp_line
			(start 0.675 -0.65)
			(end 0.675 -1.1)
			(stroke
				(width 0.2)
				(type solid)
			)
			(layer "F.SilkS")
		)
		(fp_line
			(start 0.675 1.1)
			(end 0.675 0.65)
			(stroke
				(width 0.2)
				(type solid)
			)
			(layer "F.SilkS")
		)
		(fp_circle
			(center -1.125 -1.45)
			(end -1.125 -1.575)
			(stroke
				(width 0.25)
				(type solid)
			)
			(fill no)
			(layer "F.SilkS")
		)
		(pad "1" smd rect
			(at -1.125 -0.65 90)
			(size 0.5 0.9)
			(layers "F.Cu" "F.Mask" "F.Paste")
			(net "GND")
		)
		(pad "2" smd rect
			(at -1.125 0.65 90)
			(size 0.5 0.9)
			(layers "F.Cu" "F.Mask" "F.Paste")
			(net "+3.3V")
		)
		(pad "3" smd rect
			(at 1.125 0 90)
			(size 0.5 0.9)
			(layers "F.Cu" "F.Mask" "F.Paste")
			(net "FPGA_TDO")
		)
	)
	(footprint "Vault:FP-RC0603-0_55-MFG"
		(layer "F.Cu")
		(at 83.4261 83.1162)
		(property "Reference" "R40"
			(at -0.2286 1.473069 180)
			(unlocked yes)
			(layer "F.SilkS")
			(effects
				(font
					(size 0.762 0.762)
					(thickness 0.2286)
				)
			)
		)
		(property "Value" "DNI_100k"
			(at -2.998991 2.37408 270)
			(unlocked yes)
			(layer "F.SilkS")
			(hide yes)
			(effects
				(font
					(size 0.762 0.762)
					(thickness 0.2286)
				)
			)
		)
		(sheetname "USER_IO_STATUS")
		(sheetfile "USER_IO_STATUS.kicad_sch")
		(duplicate_pad_numbers_are_jumpers no)
		(fp_line
			(start -0.025 -0.45)
			(end 0.025 -0.45)
			(stroke
				(width 0.2)
				(type solid)
			)
			(layer "F.SilkS")
		)
		(fp_line
			(start -0.025 0.45)
			(end 0.025 0.45)
			(stroke
				(width 0.2)
				(type solid)
			)
			(layer "F.SilkS")
		)
		(fp_line
			(start -1.4 -0.55)
			(end 1.4 -0.55)
			(stroke
				(width 0.2)
				(type solid)
			)
			(layer "F.CrtYd")
		)
		(fp_line
			(start -1.4 0.55)
			(end -1.4 -0.55)
			(stroke
				(width 0.2)
				(type solid)
			)
			(layer "F.CrtYd")
		)
		(fp_line
			(start -1.4 0.55)
			(end 1.4 0.55)
			(stroke
				(width 0.2)
				(type solid)
			)
			(layer "F.CrtYd")
		)
		(fp_line
			(start 1.4 0.55)
			(end 1.4 -0.55)
			(stroke
				(width 0.2)
				(type solid)
			)
			(layer "F.CrtYd")
		)
		(fp_line
			(start -1.4 -0.55)
			(end 1.4 -0.55)
			(stroke
				(width 0.2)
				(type solid)
			)
			(layer "F.Fab")
		)
		(fp_line
			(start -1.4 0.55)
			(end -1.4 -0.55)
			(stroke
				(width 0.2)
				(type solid)
			)
			(layer "F.Fab")
		)
		(fp_line
			(start -1.4 0.55)
			(end 1.4 0.55)
			(stroke
				(width 0.2)
				(type solid)
			)
			(layer "F.Fab")
		)
		(fp_line
			(start -0.5 0)
			(end 0.5 0)
			(stroke
				(width 0.1)
				(type solid)
			)
			(layer "F.Fab")
		)
		(fp_line
			(start 0 0.5)
			(end 0 -0.5)
			(stroke
				(width 0.1)
				(type solid)
			)
			(layer "F.Fab")
		)
		(fp_line
			(start 1.4 0.55)
			(end 1.4 -0.55)
			(stroke
				(width 0.2)
				(type solid)
			)
			(layer "F.Fab")
		)
		(pad "1" smd rect
			(at -0.85 0)
			(size 0.9 0.8)
			(layers "F.Cu" "F.Mask" "F.Paste")
			(net "GND")
			(solder_mask_margin 0)
			(solder_paste_margin 0)
		)
		(pad "2" smd rect
			(at 0.85 0)
			(size 0.9 0.8)
			(layers "F.Cu" "F.Mask" "F.Paste")
			(net "NetR40_2")
			(solder_mask_margin 0)
			(solder_paste_margin 0)
		)
	)
	(footprint "Resistors:RESC2012X50N"
		(layer "F.Cu")
		(at 229.5261 142.1162 -90)
		(property "Reference" "R20"
			(at -1.2 -1.506655 270)
			(unlocked yes)
			(layer "F.SilkS")
			(effects
				(font
					(size 0.762 0.762)
					(thickness 0.2286)
				)
				(justify left bottom)
			)
		)
		(property "Value" "CRCW080533R0FKEA"
			(at -8.029165 -4.5751 0)
			(unlocked yes)
			(layer "F.SilkS")
			(hide yes)
			(effects
				(font
					(size 0.762 0.762)
					(thickness 0.2286)
				)
				(justify left bottom)
			)
		)
		(sheetname "PCIe_JTAG")
		(sheetfile "PCIe_JTAG.kicad_sch")
		(duplicate_pad_numbers_are_jumpers no)
		(fp_line
			(start 0 0.762)
			(end 0 -0.762)
			(stroke
				(width 0.1524)
				(type solid)
			)
			(layer "F.SilkS")
		)
		(pad "1" smd rect
			(at -1 0)
			(size 1.45 0.95)
			(layers "F.Cu" "F.Mask" "F.Paste")
			(net "FPGA_TMS")
		)
		(pad "2" smd rect
			(at 1 0)
			(size 1.45 0.95)
			(layers "F.Cu" "F.Mask" "F.Paste")
			(net "NetR20_2")
		)
	)
	(footprint "Vault:RESC1005X40X25LL05T05"
		(layer "F.Cu")
		(at 186.3261 82.8162 180)
		(property "Reference" "R52"
			(at 1.1714 1.673079 0)
			(unlocked yes)
			(layer "F.SilkS")
			(effects
				(font
					(size 0.762 0.762)
					(thickness 0.2286)
				)
			)
		)
		(property "Value" "4.7K_0402"
			(at -3.024391 2.374045 90)
			(unlocked yes)
			(layer "F.SilkS")
			(hide yes)
			(effects
				(font
					(size 0.762 0.762)
					(thickness 0.2286)
				)
			)
		)
		(sheetname "GPS_IMU_SENSORS")
		(sheetfile "GPS_IMU_SENSORS.kicad_sch")
		(duplicate_pad_numbers_are_jumpers no)
		(pad "1" smd rect
			(at -0.4 0 270)
			(size 0.45 0.45)
			(layers "F.Cu" "F.Mask" "F.Paste")
			(net "NetR52_1")
		)
		(pad "2" smd rect
			(at 0.4 0 270)
			(size 0.45 0.45)
			(layers "F.Cu" "F.Mask" "F.Paste")
			(net "+3.3V")
		)
	)
	(footprint "Vault:FP-CL180-IPC_C"
		(layer "F.Cu")
		(at 213.3261 115.4162 180)
		(property "Reference" "C7"
			(at 3 0.393345 180)
			(unlocked yes)
			(layer "F.SilkS")
			(effects
				(font
					(size 0.762 0.762)
					(thickness 0.2286)
				)
				(justify left bottom)
			)
		)
		(property "Value" "DNI_1nF_50V_0402"
			(at 11.1911 -12.037845 0)
			(unlocked yes)
			(layer "F.SilkS")
			(hide yes)
			(effects
				(font
					(size 0.762 0.762)
					(thickness 0.2286)
				)
				(justify left bottom)
			)
		)
		(sheetname "POWER")
		(sheetfile "POWER.kicad_sch")
		(duplicate_pad_numbers_are_jumpers no)
		(fp_line
			(start 0.63624 0.675)
			(end -0.63624 0.675)
			(stroke
				(width 0.2)
				(type solid)
			)
			(layer "F.SilkS")
		)
		(fp_line
			(start 0.63624 -0.675)
			(end -0.63624 -0.675)
			(stroke
				(width 0.2)
				(type solid)
			)
			(layer "F.SilkS")
		)
		(fp_line
			(start 0.73624 0.375)
			(end -0.73624 0.375)
			(stroke
				(width 0.2)
				(type solid)
			)
			(layer "F.CrtYd")
		)
		(fp_line
			(start 0.73624 -0.375)
			(end 0.73624 0.375)
			(stroke
				(width 0.2)
				(type solid)
			)
			(layer "F.CrtYd")
		)
		(fp_line
			(start 0.73624 -0.375)
			(end -0.73624 -0.375)
			(stroke
				(width 0.2)
				(type solid)
			)
			(layer "F.CrtYd")
		)
		(fp_line
			(start -0.73624 -0.375)
			(end -0.73624 0.375)
			(stroke
				(width 0.2)
				(type solid)
			)
			(layer "F.CrtYd")
		)
		(fp_line
			(start 0.73624 0.375)
			(end -0.73624 0.375)
			(stroke
				(width 0.2)
				(type solid)
			)
			(layer "F.Fab")
		)
		(fp_line
			(start 0.73624 -0.375)
			(end 0.73624 0.375)
			(stroke
				(width 0.2)
				(type solid)
			)
			(layer "F.Fab")
		)
		(fp_line
			(start 0.73624 -0.375)
			(end -0.73624 -0.375)
			(stroke
				(width 0.2)
				(type solid)
			)
			(layer "F.Fab")
		)
		(fp_line
			(start 0.5 0)
			(end -0.5 0)
			(stroke
				(width 0.1)
				(type solid)
			)
			(layer "F.Fab")
		)
		(fp_line
			(start 0.5 0)
			(end -0.5 0)
			(stroke
				(width 0.1)
				(type solid)
			)
			(layer "F.Fab")
		)
		(fp_line
			(start 0 -0.5)
			(end 0 0.5)
			(stroke
				(width 0.1)
				(type solid)
			)
			(layer "F.Fab")
		)
		(fp_line
			(start 0 -0.5)
			(end 0 0.5)
			(stroke
				(width 0.1)
				(type solid)
			)
			(layer "F.Fab")
		)
		(fp_line
			(start -0.73624 -0.375)
			(end -0.73624 0.375)
			(stroke
				(width 0.2)
				(type solid)
			)
			(layer "F.Fab")
		)
		(fp_text user "${REFERENCE}"
			(at 0.00001 0.28425 180)
			(unlocked yes)
			(layer "F.Fab")
			(effects
				(font
					(face "Arial")
					(size 0.63 0.63)
					(thickness 0.1)
				)
				(justify left bottom)
			)
		)
		(pad "1" smd rect
			(at -0.37856 0 180)
			(size 0.51535 0.47247)
			(layers "F.Cu" "F.Mask" "F.Paste")
			(net "NetC7_1")
			(solder_mask_margin 0)
			(solder_paste_margin 0)
		)
		(pad "2" smd rect
			(at 0.37857 0 180)
			(size 0.51535 0.47247)
			(layers "F.Cu" "F.Mask" "F.Paste")
			(net "GND")
			(solder_mask_margin 0)
			(solder_paste_margin 0)
		)
	)
	(footprint "Vault:CAPC1608X87X45ML20T05"
		(layer "F.Cu")
		(at 130.8761 83.5786)
		(property "Reference" "C23"
			(at 1.8786 -2.335469 0)
			(unlocked yes)
			(layer "F.SilkS")
			(effects
				(font
					(size 0.762 0.762)
					(thickness 0.2286)
				)
			)
		)
		(property "Value" "0.1uF"
			(at 2.069035 2.630671 0)
			(unlocked yes)
			(layer "F.SilkS")
			(hide yes)
			(effects
				(font
					(size 0.762 0.762)
					(thickness 0.2286)
				)
			)
		)
		(sheetname "MAC")
		(sheetfile "MAC.kicad_sch")
		(duplicate_pad_numbers_are_jumpers no)
		(pad "1" smd rect
			(at -0.7 0 90)
			(size 1.1 1.05)
			(layers "F.Cu" "F.Mask" "F.Paste")
			(net "GND")
		)
		(pad "2" smd rect
			(at 0.7 0 90)
			(size 1.1 1.05)
			(layers "F.Cu" "F.Mask" "F.Paste")
			(net "+3.3V")
		)
	)
	(footprint "Vault:FP-CC0603-DA-MFG"
		(layer "F.Cu")
		(at 219.8261 114.4162 180)
		(property "Reference" "C3"
			(at -1.2 -1.593345 0)
			(unlocked yes)
			(layer "F.SilkS")
			(effects
				(font
					(size 0.762 0.762)
					(thickness 0.2286)
				)
				(justify left bottom)
			)
		)
		(property "Value" "0.1uF_50V_0603"
			(at -0.7365 8.683155 0)
			(unlocked yes)
			(layer "F.SilkS")
			(hide yes)
			(effects
				(font
					(size 0.762 0.762)
					(thickness 0.2286)
				)
				(justify left bottom)
			)
		)
		(sheetname "POWER")
		(sheetfile "POWER.kicad_sch")
		(duplicate_pad_numbers_are_jumpers no)
		(fp_line
			(start 0.85 0.85)
			(end -0.85 0.85)
			(stroke
				(width 0.2)
				(type solid)
			)
			(layer "F.SilkS")
		)
		(fp_line
			(start 0.85 -0.85)
			(end -0.85 -0.85)
			(stroke
				(width 0.2)
				(type solid)
			)
			(layer "F.SilkS")
		)
		(fp_line
			(start 1.35 0.75)
			(end -1.35 0.75)
			(stroke
				(width 0.2)
				(type solid)
			)
			(layer "F.CrtYd")
		)
		(fp_line
			(start 1.35 -0.75)
			(end 1.35 0.75)
			(stroke
				(width 0.2)
				(type solid)
			)
			(layer "F.CrtYd")
		)
		(fp_line
			(start 1.35 -0.75)
			(end -1.35 -0.75)
			(stroke
				(width 0.2)
				(type solid)
			)
			(layer "F.CrtYd")
		)
		(fp_line
			(start -1.35 -0.75)
			(end -1.35 0.75)
			(stroke
				(width 0.2)
				(type solid)
			)
			(layer "F.CrtYd")
		)
		(fp_line
			(start 1.35 0.75)
			(end -1.35 0.75)
			(stroke
				(width 0.2)
				(type solid)
			)
			(layer "F.Fab")
		)
		(fp_line
			(start 1.35 -0.75)
			(end 1.35 0.75)
			(stroke
				(width 0.2)
				(type solid)
			)
			(layer "F.Fab")
		)
		(fp_line
			(start 1.35 -0.75)
			(end -1.35 -0.75)
			(stroke
				(width 0.2)
				(type solid)
			)
			(layer "F.Fab")
		)
		(fp_line
			(start 0.5 0)
			(end -0.5 0)
			(stroke
				(width 0.1)
				(type solid)
			)
			(layer "F.Fab")
		)
		(fp_line
			(start 0 -0.5)
			(end 0 0.5)
			(stroke
				(width 0.1)
				(type solid)
			)
			(layer "F.Fab")
		)
		(fp_line
			(start -1.35 -0.75)
			(end -1.35 0.75)
			(stroke
				(width 0.2)
				(type solid)
			)
			(layer "F.Fab")
		)
		(fp_text user "${REFERENCE}"
			(at -0.00001 0.09602 180)
			(unlocked yes)
			(layer "F.Fab")
			(effects
				(font
					(face "Arial")
					(size 0.63 0.63)
					(thickness 0.1)
				)
				(justify left bottom)
			)
		)
		(pad "1" smd rect
			(at -0.75 0 180)
			(size 0.8 0.9)
			(layers "F.Cu" "F.Mask" "F.Paste")
			(net "NetC3_1")
			(solder_mask_margin 0)
			(solder_paste_margin 0)
		)
		(pad "2" smd rect
			(at 0.75 0 180)
			(size 0.8 0.9)
			(layers "F.Cu" "F.Mask" "F.Paste")
			(net "NetC3_2")
			(solder_mask_margin 0)
			(solder_paste_margin 0)
		)
	)
	(footprint "Vault:CAPC1005X56X25NL10T15"
		(layer "F.Cu")
		(at 191.1261 89.0162 180)
		(property "Reference" "C66"
			(at -2.2286 -0.326931 0)
			(unlocked yes)
			(layer "F.SilkS")
			(effects
				(font
					(size 0.762 0.762)
					(thickness 0.2286)
				)
			)
		)
		(property "Value" "0.1uF_0402"
			(at 2.06903 2.567191 180)
			(unlocked yes)
			(layer "F.SilkS")
			(hide yes)
			(effects
				(font
					(size 0.762 0.762)
					(thickness 0.2286)
				)
			)
		)
		(sheetname "GPS_IMU_SENSORS")
		(sheetfile "GPS_IMU_SENSORS.kicad_sch")
		(duplicate_pad_numbers_are_jumpers no)
		(pad "1" smd rect
			(at -0.44 0 270)
			(size 0.64 0.68)
			(layers "F.Cu" "F.Mask" "F.Paste")
			(net "GND")
		)
		(pad "2" smd rect
			(at 0.44 0 270)
			(size 0.64 0.68)
			(layers "F.Cu" "F.Mask" "F.Paste")
			(net "+3.3V")
		)
	)
	(footprint "FPGA_CONN:SingleFPGAConn"
		(layer "F.Cu")
		(at 182.5759 133.49995 90)
		(property "Reference" "J37"
			(at -0.39436 -23.455129 90)
			(unlocked yes)
			(layer "F.SilkS")
			(effects
				(font
					(size 0.762 0.762)
					(thickness 0.2286)
				)
			)
		)
		(property "Value" "Single FPGA Conn"
			(at 9.25452 3.621231 90)
			(unlocked yes)
			(layer "F.SilkS")
			(hide yes)
			(effects
				(font
					(size 0.762 0.762)
					(thickness 0.2286)
				)
			)
		)
		(sheetname "FPGA")
		(sheetfile "FPGA.kicad_sch")
		(duplicate_pad_numbers_are_jumpers no)
		(fp_line
			(start 1.40004 -21.2499)
			(end 1.99999 -20.69999)
			(stroke
				(width 0.15011)
				(type solid)
			)
			(layer "F.SilkS")
		)
		(fp_line
			(start -1.40005 -21.2499)
			(end 1.40004 -21.2499)
			(stroke
				(width 0.15011)
				(type solid)
			)
			(layer "F.SilkS")
		)
		(fp_line
			(start -1.40005 -21.2499)
			(end -1.40005 -20.69999)
			(stroke
				(width 0.15011)
				(type solid)
			)
			(layer "F.SilkS")
		)
		(fp_line
			(start 1.99999 -20.69999)
			(end 1.99999 -20.03298)
			(stroke
				(width 0.15011)
				(type solid)
			)
			(layer "F.SilkS")
		)
		(fp_line
			(start -2 -20.69999)
			(end -1.40005 -20.69999)
			(stroke
				(width 0.15011)
				(type solid)
			)
			(layer "F.SilkS")
		)
		(fp_line
			(start -2 -20.69999)
			(end -2 -20.03298)
			(stroke
				(width 0.15011)
				(type solid)
			)
			(layer "F.SilkS")
		)
		(fp_line
			(start 1.99999 0.03302)
			(end 1.99999 0.70002)
			(stroke
				(width 0.15011)
				(type solid)
			)
			(layer "F.SilkS")
		)
		(fp_line
			(start -2 0.03302)
			(end -2 0.70002)
			(stroke
				(width 0.15011)
				(type solid)
			)
			(layer "F.SilkS")
		)
		(fp_line
			(start 1.99999 0.70002)
			(end 1.40004 1.24993)
			(stroke
				(width 0.15011)
				(type solid)
			)
			(layer "F.SilkS")
		)
		(fp_line
			(start -1.40005 0.70002)
			(end -1.40005 1.24993)
			(stroke
				(width 0.15011)
				(type solid)
			)
			(layer "F.SilkS")
		)
		(fp_line
			(start -2 0.70002)
			(end -1.40005 0.70002)
			(stroke
				(width 0.15011)
				(type solid)
			)
			(layer "F.SilkS")
		)
		(fp_line
			(start -1.40005 1.24993)
			(end 1.40004 1.24993)
			(stroke
				(width 0.15011)
				(type solid)
			)
			(layer "F.SilkS")
		)
		(fp_circle
			(center 3.5052 -0.22454)
			(end 3.70535 -0.22454)
			(stroke
				(width 0.40005)
				(type solid)
			)
			(fill no)
			(layer "F.SilkS")
		)
		(pad "1" smd rect
			(at 2.02488 -0.24994 90)
			(size 1.54991 0.24994)
			(layers "F.Cu" "F.Mask" "F.Paste")
		)
		(pad "2" smd rect
			(at -2.02489 -0.24994 90)
			(size 1.54991 0.24994)
			(layers "F.Cu" "F.Mask" "F.Paste")
		)
		(pad "3" smd rect
			(at 2.02488 -0.75006 90)
			(size 1.54991 0.24994)
			(layers "F.Cu" "F.Mask" "F.Paste")
		)
		(pad "4" smd rect
			(at -2.02489 -0.75006 90)
			(size 1.54991 0.24994)
			(layers "F.Cu" "F.Mask" "F.Paste")
		)
		(pad "5" smd rect
			(at 2.02488 -1.24994 90)
			(size 1.54991 0.24994)
			(layers "F.Cu" "F.Mask" "F.Paste")
		)
		(pad "6" smd rect
			(at -2.02489 -1.24994 90)
			(size 1.54991 0.24994)
			(layers "F.Cu" "F.Mask" "F.Paste")
		)
		(pad "7" smd rect
			(at 2.02488 -1.75006 90)
			(size 1.54991 0.24994)
			(layers "F.Cu" "F.Mask" "F.Paste")
		)
		(pad "8" smd rect
			(at -2.02489 -1.75006 90)
			(size 1.54991 0.24994)
			(layers "F.Cu" "F.Mask" "F.Paste")
		)
		(pad "9" smd rect
			(at 2.02488 -2.24993 90)
			(size 1.54991 0.24994)
			(layers "F.Cu" "F.Mask" "F.Paste")
			(net "GND")
		)
		(pad "10" smd rect
			(at -2.02489 -2.24993 90)
			(size 1.54991 0.24994)
			(layers "F.Cu" "F.Mask" "F.Paste")
			(net "GND")
		)
		(pad "11" smd rect
			(at 2.02488 -2.75006 90)
			(size 1.54991 0.24994)
			(layers "F.Cu" "F.Mask" "F.Paste")
		)
		(pad "12" smd rect
			(at -2.02489 -2.75006 90)
			(size 1.54991 0.24994)
			(layers "F.Cu" "F.Mask" "F.Paste")
			(net "PCIE_TX2_P")
		)
		(pad "13" smd rect
			(at 2.02488 -3.24993 90)
			(size 1.54991 0.24994)
			(layers "F.Cu" "F.Mask" "F.Paste")
		)
		(pad "14" smd rect
			(at -2.02489 -3.24993 90)
			(size 1.54991 0.24994)
			(layers "F.Cu" "F.Mask" "F.Paste")
			(net "PCIE_TX2_N")
		)
		(pad "15" smd rect
			(at 2.02488 -3.75006 90)
			(size 1.54991 0.24994)
			(layers "F.Cu" "F.Mask" "F.Paste")
			(net "GND")
		)
		(pad "16" smd rect
			(at -2.02489 -3.75006 90)
			(size 1.54991 0.24994)
			(layers "F.Cu" "F.Mask" "F.Paste")
		)
		(pad "17" smd rect
			(at 2.02488 -4.24993 90)
			(size 1.54991 0.24994)
			(layers "F.Cu" "F.Mask" "F.Paste")
			(net "PCIE_TX3_P")
		)
		(pad "18" smd rect
			(at -2.02489 -4.24993 90)
			(size 1.54991 0.24994)
			(layers "F.Cu" "F.Mask" "F.Paste")
			(net "PCIE_RX2_P")
		)
		(pad "19" smd rect
			(at 2.02488 -4.75006 90)
			(size 1.54991 0.24994)
			(layers "F.Cu" "F.Mask" "F.Paste")
			(net "PCIE_TX3_N")
		)
		(pad "20" smd rect
			(at -2.02489 -4.75006 90)
			(size 1.54991 0.24994)
			(layers "F.Cu" "F.Mask" "F.Paste")
			(net "PCIE_RX2_N")
		)
		(pad "21" smd rect
			(at 2.02488 -5.24993 90)
			(size 1.54991 0.24994)
			(layers "F.Cu" "F.Mask" "F.Paste")
			(net "GND")
		)
		(pad "22" smd rect
			(at -2.02489 -5.24993 90)
			(size 1.54991 0.24994)
			(layers "F.Cu" "F.Mask" "F.Paste")
		)
		(pad "23" smd rect
			(at 2.02488 -5.75005 90)
			(size 1.54991 0.24994)
			(layers "F.Cu" "F.Mask" "F.Paste")
			(net "PCIE_RX3_P")
		)
		(pad "24" smd rect
			(at -2.02489 -5.75005 90)
			(size 1.54991 0.24994)
			(layers "F.Cu" "F.Mask" "F.Paste")
			(net "PCIE_TX1_P")
		)
		(pad "25" smd rect
			(at 2.02488 -6.24993 90)
			(size 1.54991 0.24994)
			(layers "F.Cu" "F.Mask" "F.Paste")
			(net "PCIE_RX3_N")
		)
		(pad "26" smd rect
			(at -2.02489 -6.24993 90)
			(size 1.54991 0.24994)
			(layers "F.Cu" "F.Mask" "F.Paste")
			(net "PCIE_TX1_N")
		)
		(pad "27" smd rect
			(at 2.02488 -6.75005 90)
			(size 1.54991 0.24994)
			(layers "F.Cu" "F.Mask" "F.Paste")
			(net "GND")
		)
		(pad "28" smd rect
			(at -2.02489 -6.75005 90)
			(size 1.54991 0.24994)
			(layers "F.Cu" "F.Mask" "F.Paste")
		)
		(pad "29" smd rect
			(at 2.02488 -7.24992 90)
			(size 1.54991 0.24994)
			(layers "F.Cu" "F.Mask" "F.Paste")
			(net "PCIE_TX0_P")
		)
		(pad "30" smd rect
			(at -2.02489 -7.24992 90)
			(size 1.54991 0.24994)
			(layers "F.Cu" "F.Mask" "F.Paste")
			(net "PCIE_RX1_P")
		)
		(pad "31" smd rect
			(at 2.02488 -7.75005 90)
			(size 1.54991 0.24994)
			(layers "F.Cu" "F.Mask" "F.Paste")
			(net "PCIE_TX0_N")
		)
		(pad "32" smd rect
			(at -2.02489 -7.75005 90)
			(size 1.54991 0.24994)
			(layers "F.Cu" "F.Mask" "F.Paste")
			(net "PCIE_RX1_N")
		)
		(pad "33" smd rect
			(at 2.02488 -8.24992 90)
			(size 1.54991 0.24994)
			(layers "F.Cu" "F.Mask" "F.Paste")
			(net "GND")
		)
		(pad "34" smd rect
			(at -2.02489 -8.24992 90)
			(size 1.54991 0.24994)
			(layers "F.Cu" "F.Mask" "F.Paste")
		)
		(pad "35" smd rect
			(at 2.02488 -8.75005 90)
			(size 1.54991 0.24994)
			(layers "F.Cu" "F.Mask" "F.Paste")
			(net "PCIE_RX0_P")
		)
		(pad "36" smd rect
			(at -2.02489 -8.75005 90)
			(size 1.54991 0.24994)
			(layers "F.Cu" "F.Mask" "F.Paste")
			(net "PCIE_CLK_P")
		)
		(pad "37" smd rect
			(at 2.02488 -9.24992 90)
			(size 1.54991 0.24994)
			(layers "F.Cu" "F.Mask" "F.Paste")
			(net "PCIE_RX0_N")
		)
		(pad "38" smd rect
			(at -2.02489 -9.24992 90)
			(size 1.54991 0.24994)
			(layers "F.Cu" "F.Mask" "F.Paste")
			(net "PCIE_CLK_N")
		)
		(pad "39" smd rect
			(at 2.02488 -9.75005 90)
			(size 1.54991 0.24994)
			(layers "F.Cu" "F.Mask" "F.Paste")
			(net "GND")
		)
		(pad "40" smd rect
			(at -2.02489 -9.75005 90)
			(size 1.54991 0.24994)
			(layers "F.Cu" "F.Mask" "F.Paste")
			(net "GND")
		)
		(pad "41" smd rect
			(at 2.02488 -10.24992 90)
			(size 1.54991 0.24994)
			(layers "F.Cu" "F.Mask" "F.Paste")
		)
		(pad "42" smd rect
			(at -2.02489 -10.24992 90)
			(size 1.54991 0.24994)
			(layers "F.Cu" "F.Mask" "F.Paste")
		)
		(pad "43" smd rect
			(at 2.02488 -10.75004 90)
			(size 1.54991 0.24994)
			(layers "F.Cu" "F.Mask" "F.Paste")
		)
		(pad "44" smd rect
			(at -2.02489 -10.75004 90)
			(size 1.54991 0.24994)
			(layers "F.Cu" "F.Mask" "F.Paste")
		)
		(pad "45" smd rect
			(at 2.02488 -11.24992 90)
			(size 1.54991 0.24994)
			(layers "F.Cu" "F.Mask" "F.Paste")
		)
		(pad "46" smd rect
			(at -2.02489 -11.24992 90)
			(size 1.54991 0.24994)
			(layers "F.Cu" "F.Mask" "F.Paste")
		)
		(pad "47" smd rect
			(at 2.02488 -11.75004 90)
			(size 1.54991 0.24994)
			(layers "F.Cu" "F.Mask" "F.Paste")
		)
		(pad "48" smd rect
			(at -2.02489 -11.75004 90)
			(size 1.54991 0.24994)
			(layers "F.Cu" "F.Mask" "F.Paste")
		)
		(pad "49" smd rect
			(at 2.02488 -12.24991 90)
			(size 1.54991 0.24994)
			(layers "F.Cu" "F.Mask" "F.Paste")
			(net "GND")
		)
		(pad "50" smd rect
			(at -2.02489 -12.24991 90)
			(size 1.54991 0.24994)
			(layers "F.Cu" "F.Mask" "F.Paste")
			(net "GND")
		)
		(pad "51" smd rect
			(at 2.02488 -12.75004 90)
			(size 1.54991 0.24994)
			(layers "F.Cu" "F.Mask" "F.Paste")
		)
		(pad "52" smd rect
			(at -2.02489 -12.75004 90)
			(size 1.54991 0.24994)
			(layers "F.Cu" "F.Mask" "F.Paste")
		)
		(pad "53" smd rect
			(at 2.02488 -13.24991 90)
			(size 1.54991 0.24994)
			(layers "F.Cu" "F.Mask" "F.Paste")
		)
		(pad "54" smd rect
			(at -2.02489 -13.24991 90)
			(size 1.54991 0.24994)
			(layers "F.Cu" "F.Mask" "F.Paste")
		)
		(pad "55" smd rect
			(at 2.02488 -13.75004 90)
			(size 1.54991 0.24994)
			(layers "F.Cu" "F.Mask" "F.Paste")
		)
		(pad "56" smd rect
			(at -2.02489 -13.75004 90)
			(size 1.54991 0.24994)
			(layers "F.Cu" "F.Mask" "F.Paste")
		)
		(pad "57" smd rect
			(at 2.02488 -14.24991 90)
			(size 1.54991 0.24994)
			(layers "F.Cu" "F.Mask" "F.Paste")
		)
		(pad "58" smd rect
			(at -2.02489 -14.24991 90)
			(size 1.54991 0.24994)
			(layers "F.Cu" "F.Mask" "F.Paste")
		)
		(pad "59" smd rect
			(at 2.02488 -14.75004 90)
			(size 1.54991 0.24994)
			(layers "F.Cu" "F.Mask" "F.Paste")
			(net "GND")
		)
		(pad "60" smd rect
			(at -2.02489 -14.75004 90)
			(size 1.54991 0.24994)
			(layers "F.Cu" "F.Mask" "F.Paste")
			(net "GND")
		)
		(pad "61" smd rect
			(at 2.02488 -15.24991 90)
			(size 1.54991 0.24994)
			(layers "F.Cu" "F.Mask" "F.Paste")
		)
		(pad "62" smd rect
			(at -2.02489 -15.24991 90)
			(size 1.54991 0.24994)
			(layers "F.Cu" "F.Mask" "F.Paste")
		)
		(pad "63" smd rect
			(at 2.02488 -15.75003 90)
			(size 1.54991 0.24994)
			(layers "F.Cu" "F.Mask" "F.Paste")
		)
		(pad "64" smd rect
			(at -2.02489 -15.75003 90)
			(size 1.54991 0.24994)
			(layers "F.Cu" "F.Mask" "F.Paste")
		)
		(pad "65" smd rect
			(at 2.02488 -16.24991 90)
			(size 1.54991 0.24994)
			(layers "F.Cu" "F.Mask" "F.Paste")
		)
		(pad "66" smd rect
			(at -2.02489 -16.24991 90)
			(size 1.54991 0.24994)
			(layers "F.Cu" "F.Mask" "F.Paste")
		)
		(pad "67" smd rect
			(at 2.02488 -16.75003 90)
			(size 1.54991 0.24994)
			(layers "F.Cu" "F.Mask" "F.Paste")
		)
		(pad "68" smd rect
			(at -2.02489 -16.75003 90)
			(size 1.54991 0.24994)
			(layers "F.Cu" "F.Mask" "F.Paste")
		)
		(pad "69" smd rect
			(at 2.02488 -17.2499 90)
			(size 1.54991 0.24994)
			(layers "F.Cu" "F.Mask" "F.Paste")
			(net "GND")
		)
		(pad "70" smd rect
			(at -2.02489 -17.2499 90)
			(size 1.54991 0.24994)
			(layers "F.Cu" "F.Mask" "F.Paste")
			(net "GND")
		)
		(pad "71" smd rect
			(at 2.02488 -17.75003 90)
			(size 1.54991 0.24994)
			(layers "F.Cu" "F.Mask" "F.Paste")
		)
		(pad "72" smd rect
			(at -2.02489 -17.75003 90)
			(size 1.54991 0.24994)
			(layers "F.Cu" "F.Mask" "F.Paste")
		)
		(pad "73" smd rect
			(at 2.02488 -18.2499 90)
			(size 1.54991 0.24994)
			(layers "F.Cu" "F.Mask" "F.Paste")
		)
		(pad "74" smd rect
			(at -2.02489 -18.2499 90)
			(size 1.54991 0.24994)
			(layers "F.Cu" "F.Mask" "F.Paste")
		)
		(pad "75" smd rect
			(at 2.02488 -18.75003 90)
			(size 1.54991 0.24994)
			(layers "F.Cu" "F.Mask" "F.Paste")
		)
		(pad "76" smd rect
			(at -2.02489 -18.75003 90)
			(size 1.54991 0.24994)
			(layers "F.Cu" "F.Mask" "F.Paste")
		)
		(pad "77" smd rect
			(at 2.02488 -19.2499 90)
			(size 1.54991 0.24994)
			(layers "F.Cu" "F.Mask" "F.Paste")
		)
		(pad "78" smd rect
			(at -2.02489 -19.2499 90)
			(size 1.54991 0.24994)
			(layers "F.Cu" "F.Mask" "F.Paste")
		)
		(pad "79" smd rect
			(at 2.02488 -19.75003 90)
			(size 1.54991 0.24994)
			(layers "F.Cu" "F.Mask" "F.Paste")
		)
		(pad "80" smd rect
			(at -2.02489 -19.75003 90)
			(size 1.54991 0.24994)
			(layers "F.Cu" "F.Mask" "F.Paste")
		)
		(pad "81" smd rect
			(at 0.01135 1.17626 90)
			(size 1.70002 1.35001)
			(layers "F.Cu" "F.Mask" "F.Paste")
		)
		(pad "82" thru_hole circle
			(at 0 0 90)
			(size 0.55016 0.55016)
			(drill 0.55016)
			(layers "*.Cu" "*.Mask")
			(remove_unused_layers no)
			(thermal_bridge_angle 90)
		)
		(pad "83" thru_hole circle
			(at 0 -19.99996 90)
			(size 0.55016 0.55016)
			(drill 0.55016)
			(layers "*.Cu" "*.Mask")
			(remove_unused_layers no)
			(thermal_bridge_angle 90)
		)
		(pad "84" smd rect
			(at 0.01135 -21.17374 90)
			(size 1.70002 1.35001)
			(layers "F.Cu" "F.Mask" "F.Paste")
		)
	)
	(footprint "Vault:RESC1608X55X30NL15T15"
		(layer "F.Cu")
		(at 105.4261 82.9162)
		(property "Reference" "R27"
			(at 3.2286 0.026931 0)
			(unlocked yes)
			(layer "F.SilkS")
			(effects
				(font
					(size 0.762 0.762)
					(thickness 0.2286)
				)
			)
		)
		(property "Value" "4.7K"
			(at -3.087871 2.37404 270)
			(unlocked yes)
			(layer "F.SilkS")
			(hide yes)
			(effects
				(font
					(size 0.762 0.762)
					(thickness 0.2286)
				)
			)
		)
		(sheetname "GPS_IMU_SENSORS")
		(sheetfile "GPS_IMU_SENSORS.kicad_sch")
		(duplicate_pad_numbers_are_jumpers no)
		(pad "1" smd rect
			(at -0.75 0 90)
			(size 0.95 0.95)
			(layers "F.Cu" "F.Mask" "F.Paste")
			(net "SCL")
		)
		(pad "2" smd rect
			(at 0.75 0 90)
			(size 0.95 0.95)
			(layers "F.Cu" "F.Mask" "F.Paste")
			(net "+3.3V")
		)
	)
	(footprint "Vault:RESC1005X40X25LL05T05"
		(layer "F.Cu")
		(at 232.7261 117.0162 -90)
		(property "Reference" "R65"
			(at 0.3286 1.226931 270)
			(unlocked yes)
			(layer "F.SilkS")
			(effects
				(font
					(size 0.762 0.762)
					(thickness 0.2286)
				)
			)
		)
		(property "Value" "0_1%_0402"
			(at -2.579871 6.66536 180)
			(unlocked yes)
			(layer "F.SilkS")
			(hide yes)
			(effects
				(font
					(size 0.762 0.762)
					(thickness 0.2286)
				)
			)
		)
		(sheetname "POWER")
		(sheetfile "POWER.kicad_sch")
		(duplicate_pad_numbers_are_jumpers no)
		(pad "1" smd rect
			(at -0.4 0)
			(size 0.45 0.45)
			(layers "F.Cu" "F.Mask" "F.Paste")
			(net "NetR65_1")
		)
		(pad "2" smd rect
			(at 0.4 0)
			(size 0.45 0.45)
			(layers "F.Cu" "F.Mask" "F.Paste")
			(net "+3.3V")
		)
	)
	(footprint "SA53:SolderSocket"
		(layer "F.Cu")
		(at 99.3261 115.2162 90)
		(property "Reference" "SKT6"
			(at -0.126921 -6.9714 0)
			(unlocked yes)
			(layer "F.SilkS")
			(effects
				(font
					(size 0.762 0.762)
					(thickness 0.2286)
				)
			)
		)
		(property "Value" "0332-0-43-80-18-27-10-0"
			(at -2.910071 16.1362 0)
			(unlocked yes)
			(layer "F.SilkS")
			(hide yes)
			(effects
				(font
					(size 0.762 0.762)
					(thickness 0.2286)
				)
			)
		)
		(sheetname "MAC")
		(sheetfile "MAC.kicad_sch")
		(duplicate_pad_numbers_are_jumpers no)
		(pad "1" thru_hole circle
			(at 0 0 90)
			(size 2.54 2.54)
			(drill 2.0066)
			(layers "*.Cu" "*.Mask")
			(remove_unused_layers no)
			(net "GND")
			(thermal_bridge_angle 90)
		)
	)
	(footprint "Vault:FP-GRM31C-0_2-e0_3_0_8-IPC_C"
		(layer "F.Cu")
		(at 214.1261 119.5162 90)
		(property "Reference" "C77"
			(at 0.46924 -2.601729 90)
			(unlocked yes)
			(layer "F.SilkS")
			(effects
				(font
					(size 0.762 0.762)
					(thickness 0.2286)
				)
			)
		)
		(property "Value" "4.7uF_50V_1206"
			(at 8.594615 2.719551 90)
			(unlocked yes)
			(layer "F.SilkS")
			(hide yes)
			(effects
				(font
					(size 0.762 0.762)
					(thickness 0.2286)
				)
			)
		)
		(sheetname "POWER")
		(sheetfile "POWER.kicad_sch")
		(duplicate_pad_numbers_are_jumpers no)
		(fp_line
			(start -0.39847 -0.9)
			(end 0.39846 -0.9)
			(stroke
				(width 0.2)
				(type solid)
			)
			(layer "F.SilkS")
		)
		(fp_line
			(start -0.39847 0.9)
			(end 0.39846 0.9)
			(stroke
				(width 0.2)
				(type solid)
			)
			(layer "F.SilkS")
		)
		(fp_line
			(start 1.9531 -1)
			(end 1.9531 1)
			(stroke
				(width 0.2)
				(type solid)
			)
			(layer "F.CrtYd")
		)
		(fp_line
			(start -1.9531 -1)
			(end 1.9531 -1)
			(stroke
				(width 0.2)
				(type solid)
			)
			(layer "F.CrtYd")
		)
		(fp_line
			(start -1.9531 -1)
			(end -1.9531 1)
			(stroke
				(width 0.2)
				(type solid)
			)
			(layer "F.CrtYd")
		)
		(fp_line
			(start -1.9531 1)
			(end 1.9531 1)
			(stroke
				(width 0.2)
				(type solid)
			)
			(layer "F.CrtYd")
		)
		(fp_line
			(start 1.9531 -1)
			(end 1.9531 1)
			(stroke
				(width 0.2)
				(type solid)
			)
			(layer "F.Fab")
		)
		(fp_line
			(start -1.9531 -1)
			(end 1.9531 -1)
			(stroke
				(width 0.2)
				(type solid)
			)
			(layer "F.Fab")
		)
		(fp_line
			(start -1.9531 -1)
			(end -1.9531 1)
			(stroke
				(width 0.2)
				(type solid)
			)
			(layer "F.Fab")
		)
		(fp_line
			(start 0 -0.5)
			(end 0 0.5)
			(stroke
				(width 0.1)
				(type solid)
			)
			(layer "F.Fab")
		)
		(fp_line
			(start -0.5 0)
			(end 0.5 0)
			(stroke
				(width 0.1)
				(type solid)
			)
			(layer "F.Fab")
		)
		(fp_line
			(start -1.9531 1)
			(end 1.9531 1)
			(stroke
				(width 0.2)
				(type solid)
			)
			(layer "F.Fab")
		)
		(fp_text user "${REFERENCE}"
			(at -0.00002 0.09601 90)
			(unlocked yes)
			(layer "F.Fab")
			(effects
				(font
					(face "Arial")
					(size 0.63 0.63)
					(thickness 0.1)
				)
				(justify left bottom)
			)
		)
		(pad "1" smd rect
			(at -1.27578 0 90)
			(size 1.15464 1.7062)
			(layers "F.Cu" "F.Mask" "F.Paste")
			(net "+12V")
			(solder_mask_margin 0)
			(solder_paste_margin 0)
		)
		(pad "2" smd rect
			(at 1.27578 0 90)
			(size 1.15464 1.7062)
			(layers "F.Cu" "F.Mask" "F.Paste")
			(net "GND")
			(solder_mask_margin 0)
			(solder_paste_margin 0)
		)
	)
	(footprint "Vault:RESC1005X40X25LL05T05"
		(layer "F.Cu")
		(at 203.3261 82.8162 180)
		(property "Reference" "R62"
			(at -0.0286 1.573069 0)
			(unlocked yes)
			(layer "F.SilkS")
			(effects
				(font
					(size 0.762 0.762)
					(thickness 0.2286)
				)
			)
		)
		(property "Value" "0_1%_0402"
			(at -2.579871 6.66536 90)
			(unlocked yes)
			(layer "F.SilkS")
			(hide yes)
			(effects
				(font
					(size 0.762 0.762)
					(thickness 0.2286)
				)
			)
		)
		(sheetname "POWER")
		(sheetfile "POWER.kicad_sch")
		(duplicate_pad_numbers_are_jumpers no)
		(pad "1" smd rect
			(at -0.4 0 270)
			(size 0.45 0.45)
			(layers "F.Cu" "F.Mask" "F.Paste")
			(net "NetR62_1")
		)
		(pad "2" smd rect
			(at 0.4 0 270)
			(size 0.45 0.45)
			(layers "F.Cu" "F.Mask" "F.Paste")
			(net "GND")
		)
	)
	(footprint "Vault:RESC1005X40X25LL05T05"
		(layer "F.Cu")
		(at 206.1261 108.2162)
		(property "Reference" "R2"
			(at -5.21855 -0.039955 0)
			(unlocked yes)
			(layer "F.SilkS")
			(effects
				(font
					(size 0.762 0.762)
					(thickness 0.2286)
				)
				(justify left bottom)
			)
		)
		(property "Value" "4.7K_0402"
			(at 17.0993 9.461245 0)
			(unlocked yes)
			(layer "F.SilkS")
			(hide yes)
			(effects
				(font
					(size 0.762 0.762)
					(thickness 0.2286)
				)
				(justify left bottom)
			)
		)
		(sheetname "POWER")
		(sheetfile "POWER.kicad_sch")
		(duplicate_pad_numbers_are_jumpers no)
		(pad "1" smd rect
			(at -0.4 0 90)
			(size 0.45 0.45)
			(layers "F.Cu" "F.Mask" "F.Paste")
			(net "+12V")
		)
		(pad "2" smd rect
			(at 0.4 0 90)
			(size 0.45 0.45)
			(layers "F.Cu" "F.Mask" "F.Paste")
			(net "NetR2_2")
		)
	)
	(footprint "Vault:FP-CL180-IPC_C"
		(layer "F.Cu")
		(at 213.4261 129.1162 -90)
		(property "Reference" "C72"
			(at 2.3286 0.126931 270)
			(unlocked yes)
			(layer "F.SilkS")
			(effects
				(font
					(size 0.762 0.762)
					(thickness 0.2286)
				)
			)
		)
		(property "Value" "DNI_1nF_50V_0402"
			(at -2.440151 11.38813 180)
			(unlocked yes)
			(layer "F.SilkS")
			(hide yes)
			(effects
				(font
					(size 0.762 0.762)
					(thickness 0.2286)
				)
			)
		)
		(sheetname "POWER")
		(sheetfile "POWER.kicad_sch")
		(duplicate_pad_numbers_are_jumpers no)
		(fp_line
			(start 0.63624 0.675)
			(end -0.63624 0.675)
			(stroke
				(width 0.2)
				(type solid)
			)
			(layer "F.SilkS")
		)
		(fp_line
			(start 0.63624 -0.675)
			(end -0.63624 -0.675)
			(stroke
				(width 0.2)
				(type solid)
			)
			(layer "F.SilkS")
		)
		(fp_line
			(start -0.73624 0.375)
			(end -0.73624 -0.375)
			(stroke
				(width 0.2)
				(type solid)
			)
			(layer "F.CrtYd")
		)
		(fp_line
			(start 0.73624 0.375)
			(end -0.73624 0.375)
			(stroke
				(width 0.2)
				(type solid)
			)
			(layer "F.CrtYd")
		)
		(fp_line
			(start 0.73624 0.375)
			(end 0.73624 -0.375)
			(stroke
				(width 0.2)
				(type solid)
			)
			(layer "F.CrtYd")
		)
		(fp_line
			(start 0.73624 -0.375)
			(end -0.73624 -0.375)
			(stroke
				(width 0.2)
				(type solid)
			)
			(layer "F.CrtYd")
		)
		(fp_line
			(start 0 0.5)
			(end 0 -0.5)
			(stroke
				(width 0.1)
				(type solid)
			)
			(layer "F.Fab")
		)
		(fp_line
			(start 0 0.5)
			(end 0 -0.5)
			(stroke
				(width 0.1)
				(type solid)
			)
			(layer "F.Fab")
		)
		(fp_line
			(start -0.73624 0.375)
			(end -0.73624 -0.375)
			(stroke
				(width 0.2)
				(type solid)
			)
			(layer "F.Fab")
		)
		(fp_line
			(start 0.73624 0.375)
			(end -0.73624 0.375)
			(stroke
				(width 0.2)
				(type solid)
			)
			(layer "F.Fab")
		)
		(fp_line
			(start 0.73624 0.375)
			(end 0.73624 -0.375)
			(stroke
				(width 0.2)
				(type solid)
			)
			(layer "F.Fab")
		)
		(fp_line
			(start 0.5 0)
			(end -0.5 0)
			(stroke
				(width 0.1)
				(type solid)
			)
			(layer "F.Fab")
		)
		(fp_line
			(start 0.5 0)
			(end -0.5 0)
			(stroke
				(width 0.1)
				(type solid)
			)
			(layer "F.Fab")
		)
		(fp_line
			(start 0.73624 -0.375)
			(end -0.73624 -0.375)
			(stroke
				(width 0.2)
				(type solid)
			)
			(layer "F.Fab")
		)
		(fp_text user "${REFERENCE}"
			(at 0 0.28425 270)
			(unlocked yes)
			(layer "F.Fab")
			(effects
				(font
					(face "Arial")
					(size 0.63 0.63)
					(thickness 0.1)
				)
				(justify left bottom)
			)
		)
		(pad "1" smd rect
			(at -0.37856 0 270)
			(size 0.51535 0.47247)
			(layers "F.Cu" "F.Mask" "F.Paste")
			(net "NetC72_1")
			(solder_mask_margin 0)
			(solder_paste_margin 0)
		)
		(pad "2" smd rect
			(at 0.37856 0 270)
			(size 0.51535 0.47247)
			(layers "F.Cu" "F.Mask" "F.Paste")
			(net "GND")
			(solder_mask_margin 0)
			(solder_paste_margin 0)
		)
	)
	(footprint "Vault:RESC1005X40X25LL05T05"
		(layer "F.Cu")
		(at 206.1261 107.3162)
		(property "Reference" "R3"
			(at -5.11855 -0.239955 0)
			(unlocked yes)
			(layer "F.SilkS")
			(effects
				(font
					(size 0.762 0.762)
					(thickness 0.2286)
				)
				(justify left bottom)
			)
		)
		(property "Value" "4.7K_0402"
			(at 26.9821 21.663245 0)
			(unlocked yes)
			(layer "F.SilkS")
			(hide yes)
			(effects
				(font
					(size 0.762 0.762)
					(thickness 0.2286)
				)
				(justify left bottom)
			)
		)
		(sheetname "POWER")
		(sheetfile "POWER.kicad_sch")
		(duplicate_pad_numbers_are_jumpers no)
		(pad "1" smd rect
			(at -0.4 0 90)
			(size 0.45 0.45)
			(layers "F.Cu" "F.Mask" "F.Paste")
			(net "+3.3V")
		)
		(pad "2" smd rect
			(at 0.4 0 90)
			(size 0.45 0.45)
			(layers "F.Cu" "F.Mask" "F.Paste")
			(net "NetR3_2")
		)
	)
	(footprint "Vault:RESC1608X55X30LL15T20"
		(layer "F.Cu")
		(at 179.6261 90.0786 180)
		(property "Reference" "R37"
			(at 2.1714 -0.164531 0)
			(unlocked yes)
			(layer "F.SilkS")
			(effects
				(font
					(size 0.762 0.762)
					(thickness 0.2286)
				)
			)
		)
		(property "Value" "10K"
			(at -2.630671 1.76468 90)
			(unlocked yes)
			(layer "F.SilkS")
			(hide yes)
			(effects
				(font
					(size 0.762 0.762)
					(thickness 0.2286)
				)
			)
		)
		(sheetname "GPS_IMU_SENSORS")
		(sheetfile "GPS_IMU_SENSORS.kicad_sch")
		(duplicate_pad_numbers_are_jumpers no)
		(pad "1" smd rect
			(at -0.575 0 270)
			(size 0.85 0.75)
			(layers "F.Cu" "F.Mask" "F.Paste")
			(net "EXT_EEPROM_WP")
		)
		(pad "2" smd rect
			(at 0.575 0 270)
			(size 0.85 0.75)
			(layers "F.Cu" "F.Mask" "F.Paste")
			(net "+3.3V")
		)
	)
	(footprint "Vault:RESC1005X40X25NL10T10"
		(layer "F.Cu")
		(at 202.8761 122.6662)
		(property "Reference" "R78"
			(at -3.1214 4.176931 0)
			(unlocked yes)
			(layer "F.SilkS")
			(effects
				(font
					(size 0.762 0.762)
					(thickness 0.2286)
				)
			)
		)
		(property "Value" "787_1%_0402"
			(at -2.884671 8.036475 270)
			(unlocked yes)
			(layer "F.SilkS")
			(hide yes)
			(effects
				(font
					(size 0.762 0.762)
					(thickness 0.2286)
				)
			)
		)
		(sheetname "POWER")
		(sheetfile "POWER.kicad_sch")
		(duplicate_pad_numbers_are_jumpers no)
		(pad "1" smd rect
			(at -0.425 0 90)
			(size 0.6 0.65)
			(layers "F.Cu" "F.Mask" "F.Paste")
			(net "GND")
		)
		(pad "2" smd rect
			(at 0.425 0 90)
			(size 0.6 0.65)
			(layers "F.Cu" "F.Mask" "F.Paste")
			(net "P3V3_FB")
		)
	)
	(footprint "Vault:FP-BNO055-MFG"
		(layer "F.Cu")
		(at 187.3261 86.2162 -90)
		(property "Reference" "U13"
			(at 3.126931 1.3714 0)
			(unlocked yes)
			(layer "F.SilkS")
			(effects
				(font
					(size 0.762 0.762)
					(thickness 0.2286)
				)
			)
		)
		(property "Value" "BNO055"
			(at 1.94174 3.494271 270)
			(unlocked yes)
			(layer "F.SilkS")
			(hide yes)
			(effects
				(font
					(size 0.762 0.762)
					(thickness 0.2286)
				)
			)
		)
		(sheetname "GPS_IMU_SENSORS")
		(sheetfile "GPS_IMU_SENSORS.kicad_sch")
		(duplicate_pad_numbers_are_jumpers no)
		(fp_rect
			(start -0.400005 2.575005)
			(end -0.100005 2.049995)
			(stroke
				(width 0)
				(type default)
			)
			(fill yes)
			(layer "F.Mask")
		)
		(fp_rect
			(start -0.9 2.575)
			(end -0.6 2.05)
			(stroke
				(width 0)
				(type default)
			)
			(fill yes)
			(layer "F.Mask")
		)
		(fp_rect
			(start 0.09999 2.575)
			(end 0.39999 2.05)
			(stroke
				(width 0)
				(type default)
			)
			(fill yes)
			(layer "F.Mask")
		)
		(fp_rect
			(start 0.6 2.575)
			(end 0.9 2.05)
			(stroke
				(width 0)
				(type default)
			)
			(fill yes)
			(layer "F.Mask")
		)
		(fp_rect
			(start -1.82501 2.45001)
			(end -1.30001 2.05001)
			(stroke
				(width 0)
				(type default)
			)
			(fill yes)
			(layer "F.Mask")
		)
		(fp_rect
			(start 1.3 2.44999)
			(end 1.825 2.04999)
			(stroke
				(width 0)
				(type default)
			)
			(fill yes)
			(layer "F.Mask")
		)
		(fp_rect
			(start -1.825005 1.950005)
			(end -1.300005 1.549995)
			(stroke
				(width 0)
				(type default)
			)
			(fill yes)
			(layer "F.Mask")
		)
		(fp_rect
			(start 1.299995 1.950005)
			(end 1.824995 1.549995)
			(stroke
				(width 0)
				(type default)
			)
			(fill yes)
			(layer "F.Mask")
		)
		(fp_rect
			(start 1.29999 1.45001)
			(end 1.82499 1.05001)
			(stroke
				(width 0)
				(type default)
			)
			(fill yes)
			(layer "F.Mask")
		)
		(fp_rect
			(start -1.825 1.44999)
			(end -1.3 1.04999)
			(stroke
				(width 0)
				(type default)
			)
			(fill yes)
			(layer "F.Mask")
		)
		(fp_rect
			(start -1.825005 0.950005)
			(end -1.300005 0.549995)
			(stroke
				(width 0)
				(type default)
			)
			(fill yes)
			(layer "F.Mask")
		)
		(fp_rect
			(start 1.299995 0.950005)
			(end 1.824995 0.549995)
			(stroke
				(width 0)
				(type default)
			)
			(fill yes)
			(layer "F.Mask")
		)
		(fp_rect
			(start -1.82501 0.45001)
			(end -1.30001 0.05001)
			(stroke
				(width 0)
				(type default)
			)
			(fill yes)
			(layer "F.Mask")
		)
		(fp_rect
			(start 1.3 0.44999)
			(end 1.825 0.04999)
			(stroke
				(width 0)
				(type default)
			)
			(fill yes)
			(layer "F.Mask")
		)
		(fp_rect
			(start -1.82501 -0.04999)
			(end -1.30001 -0.44999)
			(stroke
				(width 0)
				(type default)
			)
			(fill yes)
			(layer "F.Mask")
		)
		(fp_rect
			(start 1.3 -0.05001)
			(end 1.825 -0.45001)
			(stroke
				(width 0)
				(type default)
			)
			(fill yes)
			(layer "F.Mask")
		)
		(fp_rect
			(start -1.825005 -0.549995)
			(end -1.300005 -0.950005)
			(stroke
				(width 0)
				(type default)
			)
			(fill yes)
			(layer "F.Mask")
		)
		(fp_rect
			(start 1.299995 -0.549995)
			(end 1.824995 -0.950005)
			(stroke
				(width 0)
				(type default)
			)
			(fill yes)
			(layer "F.Mask")
		)
		(fp_rect
			(start 1.29999 -1.04999)
			(end 1.82499 -1.44999)
			(stroke
				(width 0)
				(type default)
			)
			(fill yes)
			(layer "F.Mask")
		)
		(fp_rect
			(start -1.825 -1.05001)
			(end -1.3 -1.45001)
			(stroke
				(width 0)
				(type default)
			)
			(fill yes)
			(layer "F.Mask")
		)
		(fp_rect
			(start -1.825005 -1.549995)
			(end -1.300005 -1.950005)
			(stroke
				(width 0)
				(type default)
			)
			(fill yes)
			(layer "F.Mask")
		)
		(fp_rect
			(start 1.299995 -1.549995)
			(end 1.824995 -1.950005)
			(stroke
				(width 0)
				(type default)
			)
			(fill yes)
			(layer "F.Mask")
		)
		(fp_rect
			(start -1.82501 -2.04999)
			(end -1.30001 -2.44999)
			(stroke
				(width 0)
				(type default)
			)
			(fill yes)
			(layer "F.Mask")
		)
		(fp_rect
			(start -0.400005 -2.049995)
			(end -0.100005 -2.575005)
			(stroke
				(width 0)
				(type default)
			)
			(fill yes)
			(layer "F.Mask")
		)
		(fp_rect
			(start -0.9 -2.05)
			(end -0.6 -2.575)
			(stroke
				(width 0)
				(type default)
			)
			(fill yes)
			(layer "F.Mask")
		)
		(fp_rect
			(start 0.09999 -2.05)
			(end 0.39999 -2.575)
			(stroke
				(width 0)
				(type default)
			)
			(fill yes)
			(layer "F.Mask")
		)
		(fp_rect
			(start 0.6 -2.05)
			(end 0.9 -2.575)
			(stroke
				(width 0)
				(type default)
			)
			(fill yes)
			(layer "F.Mask")
		)
		(fp_rect
			(start 1.3 -2.05001)
			(end 1.825 -2.45001)
			(stroke
				(width 0)
				(type default)
			)
			(fill yes)
			(layer "F.Mask")
		)
		(fp_line
			(start -2.25 2.65)
			(end -2.25 -2.65)
			(stroke
				(width 0.2)
				(type solid)
			)
			(layer "F.SilkS")
		)
		(fp_line
			(start 2.25 2.65)
			(end 2.25 -2.65)
			(stroke
				(width 0.2)
				(type solid)
			)
			(layer "F.SilkS")
		)
		(fp_circle
			(center 2.75 -2.25)
			(end 2.625 -2.25)
			(stroke
				(width 0.25)
				(type solid)
			)
			(fill no)
			(layer "F.SilkS")
		)
		(fp_line
			(start -2.45 3.15)
			(end -2.45 -3.15)
			(stroke
				(width 0.2)
				(type solid)
			)
			(layer "F.CrtYd")
		)
		(fp_line
			(start 2.45 3.15)
			(end -2.45 3.15)
			(stroke
				(width 0.2)
				(type solid)
			)
			(layer "F.CrtYd")
		)
		(fp_line
			(start 2.45 3.15)
			(end 2.45 -3.15)
			(stroke
				(width 0.2)
				(type solid)
			)
			(layer "F.CrtYd")
		)
		(fp_line
			(start 2.45 -3.15)
			(end -2.45 -3.15)
			(stroke
				(width 0.2)
				(type solid)
			)
			(layer "F.CrtYd")
		)
		(fp_line
			(start -2.45 3.15)
			(end -2.45 -3.15)
			(stroke
				(width 0.2)
				(type solid)
			)
			(layer "F.Fab")
		)
		(fp_line
			(start 2.45 3.15)
			(end -2.45 3.15)
			(stroke
				(width 0.2)
				(type solid)
			)
			(layer "F.Fab")
		)
		(fp_line
			(start 2.45 3.15)
			(end 2.45 -3.15)
			(stroke
				(width 0.2)
				(type solid)
			)
			(layer "F.Fab")
		)
		(fp_line
			(start 0 0.735)
			(end 0 -0.735)
			(stroke
				(width 0.1)
				(type solid)
			)
			(layer "F.Fab")
		)
		(fp_line
			(start 0.735 0)
			(end -0.735 0)
			(stroke
				(width 0.1)
				(type solid)
			)
			(layer "F.Fab")
		)
		(fp_line
			(start 2.45 -3.15)
			(end -2.45 -3.15)
			(stroke
				(width 0.2)
				(type solid)
			)
			(layer "F.Fab")
		)
		(fp_text user "${REFERENCE}"
			(at 0 0.28425 270)
			(unlocked yes)
			(layer "F.Fab")
			(effects
				(font
					(face "Arial")
					(size 0.63 0.63)
					(thickness 0.1)
				)
				(justify left bottom)
			)
		)
		(pad "1" smd rect
			(at 1.5625 -2.25 270)
			(size 0.475 0.35)
			(layers "F.Cu" "F.Mask" "F.Paste")
			(solder_mask_margin -1000)
			(solder_paste_margin 0)
		)
		(pad "2" smd rect
			(at 0.75 -2.3125 270)
			(size 0.25 0.475)
			(layers "F.Cu" "F.Mask" "F.Paste")
			(net "GND")
			(solder_mask_margin -1000)
			(solder_paste_margin 0)
		)
		(pad "3" smd rect
			(at 0.25 -2.3125 270)
			(size 0.25 0.475)
			(layers "F.Cu" "F.Mask" "F.Paste")
			(net "+3.3V")
			(solder_mask_margin -1000)
			(solder_paste_margin 0)
		)
		(pad "4" smd rect
			(at -0.25 -2.3125 270)
			(size 0.25 0.475)
			(layers "F.Cu" "F.Mask" "F.Paste")
			(net "NetR51_2")
			(solder_mask_margin -1000)
			(solder_paste_margin 0)
		)
		(pad "5" smd rect
			(at -0.75 -2.3125 270)
			(size 0.25 0.475)
			(layers "F.Cu" "F.Mask" "F.Paste")
			(net "GND")
			(solder_mask_margin -1000)
			(solder_paste_margin 0)
		)
		(pad "6" smd rect
			(at -1.5625 -2.25 270)
			(size 0.475 0.35)
			(layers "F.Cu" "F.Mask" "F.Paste")
			(net "GND")
			(solder_mask_margin -1000)
			(solder_paste_margin 0)
		)
		(pad "7" smd rect
			(at -1.5625 -1.75 270)
			(size 0.475 0.35)
			(layers "F.Cu" "F.Mask" "F.Paste")
			(net "NetR57_2")
			(solder_mask_margin -1000)
			(solder_paste_margin 0)
		)
		(pad "8" smd rect
			(at -1.5625 -1.25 270)
			(size 0.475 0.35)
			(layers "F.Cu" "F.Mask" "F.Paste")
			(net "NetR58_2")
			(solder_mask_margin -1000)
			(solder_paste_margin 0)
		)
		(pad "9" smd rect
			(at -1.5625 -0.75 270)
			(size 0.475 0.35)
			(layers "F.Cu" "F.Mask" "F.Paste")
			(net "NetC65_1")
			(solder_mask_margin -1000)
			(solder_paste_margin 0)
		)
		(pad "10" smd rect
			(at -1.5625 -0.25 270)
			(size 0.475 0.35)
			(layers "F.Cu" "F.Mask" "F.Paste")
			(net "NetR55_2")
			(solder_mask_margin -1000)
			(solder_paste_margin 0)
		)
		(pad "11" smd rect
			(at -1.5625 0.25 270)
			(size 0.475 0.35)
			(layers "F.Cu" "F.Mask" "F.Paste")
			(net "NetR52_1")
			(solder_mask_margin -1000)
			(solder_paste_margin 0)
		)
		(pad "12" smd rect
			(at -1.5625 0.75 270)
			(size 0.475 0.35)
			(layers "F.Cu" "F.Mask" "F.Paste")
			(solder_mask_margin -1000)
			(solder_paste_margin 0)
		)
		(pad "13" smd rect
			(at -1.5625 1.25 270)
			(size 0.475 0.35)
			(layers "F.Cu" "F.Mask" "F.Paste")
			(solder_mask_margin -1000)
			(solder_paste_margin 0)
		)
		(pad "14" smd rect
			(at -1.5625 1.75 270)
			(size 0.475 0.35)
			(layers "F.Cu" "F.Mask" "F.Paste")
			(net "BNO_INT")
			(solder_mask_margin -1000)
			(solder_paste_margin 0)
		)
		(pad "15" smd rect
			(at -1.5625 2.25 270)
			(size 0.475 0.35)
			(layers "F.Cu" "F.Mask" "F.Paste")
			(solder_mask_margin -1000)
			(solder_paste_margin 0)
		)
		(pad "16" smd rect
			(at -0.75 2.3125 270)
			(size 0.25 0.475)
			(layers "F.Cu" "F.Mask" "F.Paste")
			(solder_mask_margin -1000)
			(solder_paste_margin 0)
		)
		(pad "17" smd rect
			(at -0.25 2.3125 270)
			(size 0.25 0.475)
			(layers "F.Cu" "F.Mask" "F.Paste")
			(net "NetR53_1")
			(solder_mask_margin -1000)
			(solder_paste_margin 0)
		)
		(pad "18" smd rect
			(at 0.25 2.3125 270)
			(size 0.25 0.475)
			(layers "F.Cu" "F.Mask" "F.Paste")
			(net "GND")
			(solder_mask_margin -1000)
			(solder_paste_margin 0)
		)
		(pad "19" smd rect
			(at 0.75 2.3125 270)
			(size 0.25 0.475)
			(layers "F.Cu" "F.Mask" "F.Paste")
			(net "SCL")
			(solder_mask_margin -1000)
			(solder_paste_margin 0)
		)
		(pad "20" smd rect
			(at 1.5625 2.25 270)
			(size 0.475 0.35)
			(layers "F.Cu" "F.Mask" "F.Paste")
			(net "SDA")
			(solder_mask_margin -1000)
			(solder_paste_margin 0)
		)
		(pad "21" smd rect
			(at 1.5625 1.75 270)
			(size 0.475 0.35)
			(layers "F.Cu" "F.Mask" "F.Paste")
			(solder_mask_margin -1000)
			(solder_paste_margin 0)
		)
		(pad "22" smd rect
			(at 1.5625 1.25 270)
			(size 0.475 0.35)
			(layers "F.Cu" "F.Mask" "F.Paste")
			(solder_mask_margin -1000)
			(solder_paste_margin 0)
		)
		(pad "23" smd rect
			(at 1.5625 0.75 270)
			(size 0.475 0.35)
			(layers "F.Cu" "F.Mask" "F.Paste")
			(solder_mask_margin -1000)
			(solder_paste_margin 0)
		)
		(pad "24" smd rect
			(at 1.5625 0.25 270)
			(size 0.475 0.35)
			(layers "F.Cu" "F.Mask" "F.Paste")
			(solder_mask_margin -1000)
			(solder_paste_margin 0)
		)
		(pad "25" smd rect
			(at 1.5625 -0.25 270)
			(size 0.475 0.35)
			(layers "F.Cu" "F.Mask" "F.Paste")
			(net "GND")
			(solder_mask_margin -1000)
			(solder_paste_margin 0)
		)
		(pad "26" smd rect
			(at 1.5625 -0.75 270)
			(size 0.475 0.35)
			(layers "F.Cu" "F.Mask" "F.Paste")
			(net "BNO_XOUT32")
			(solder_mask_margin -1000)
			(solder_paste_margin 0)
		)
		(pad "27" smd rect
			(at 1.5625 -1.25 270)
			(size 0.475 0.35)
			(layers "F.Cu" "F.Mask" "F.Paste")
			(net "BNO_XIN32")
			(solder_mask_margin -1000)
			(solder_paste_margin 0)
		)
		(pad "28" smd rect
			(at 1.5625 -1.75 270)
			(size 0.475 0.35)
			(layers "F.Cu" "F.Mask" "F.Paste")
			(net "+3.3V")
			(solder_mask_margin -1000)
			(solder_paste_margin 0)
		)
	)
	(footprint "Vault:FP-BME280-MFG"
		(layer "F.Cu")
		(at 194.1261 86.8286)
		(property "Reference" "U14"
			(at 0.926931 2.759 90)
			(unlocked yes)
			(layer "F.SilkS")
			(effects
				(font
					(size 0.762 0.762)
					(thickness 0.2286)
				)
			)
		)
		(property "Value" "BME280"
			(at 2.9069 3.443471 0)
			(unlocked yes)
			(layer "F.SilkS")
			(hide yes)
			(effects
				(font
					(size 0.762 0.762)
					(thickness 0.2286)
				)
			)
		)
		(sheetname "GPS_IMU_SENSORS")
		(sheetfile "GPS_IMU_SENSORS.kicad_sch")
		(duplicate_pad_numbers_are_jumpers no)
		(fp_line
			(start -1.3 -1.55)
			(end 1.3 -1.55)
			(stroke
				(width 0.2)
				(type solid)
			)
			(layer "F.SilkS")
		)
		(fp_line
			(start -1.3 1.55)
			(end 1.3 1.55)
			(stroke
				(width 0.2)
				(type solid)
			)
			(layer "F.SilkS")
		)
		(fp_circle
			(center 1.85 -0.975)
			(end 1.85 -1.1)
			(stroke
				(width 0.25)
				(type solid)
			)
			(fill no)
			(layer "F.SilkS")
		)
		(fp_line
			(start -1.8 -1.8)
			(end 1.8 -1.8)
			(stroke
				(width 0.2)
				(type solid)
			)
			(layer "F.CrtYd")
		)
		(fp_line
			(start -1.8 1.8)
			(end -1.8 -1.8)
			(stroke
				(width 0.2)
				(type solid)
			)
			(layer "F.CrtYd")
		)
		(fp_line
			(start -1.8 1.8)
			(end 1.8 1.8)
			(stroke
				(width 0.2)
				(type solid)
			)
			(layer "F.CrtYd")
		)
		(fp_line
			(start 1.8 1.8)
			(end 1.8 -1.8)
			(stroke
				(width 0.2)
				(type solid)
			)
			(layer "F.CrtYd")
		)
		(fp_line
			(start -1.8 -1.8)
			(end 1.8 -1.8)
			(stroke
				(width 0.2)
				(type solid)
			)
			(layer "F.Fab")
		)
		(fp_line
			(start -1.8 1.8)
			(end -1.8 -1.8)
			(stroke
				(width 0.2)
				(type solid)
			)
			(layer "F.Fab")
		)
		(fp_line
			(start -1.8 1.8)
			(end 1.8 1.8)
			(stroke
				(width 0.2)
				(type solid)
			)
			(layer "F.Fab")
		)
		(fp_line
			(start -0.5 0)
			(end 0.5 0)
			(stroke
				(width 0.1)
				(type solid)
			)
			(layer "F.Fab")
		)
		(fp_line
			(start 0 0.5)
			(end 0 -0.5)
			(stroke
				(width 0.1)
				(type solid)
			)
			(layer "F.Fab")
		)
		(fp_line
			(start 1.8 1.8)
			(end 1.8 -1.8)
			(stroke
				(width 0.2)
				(type solid)
			)
			(layer "F.Fab")
		)
		(fp_text user "${REFERENCE}"
			(at 0 0.28425 0)
			(unlocked yes)
			(layer "F.Fab")
			(effects
				(font
					(face "Arial")
					(size 0.63 0.63)
					(thickness 0.1)
				)
				(justify left bottom)
			)
		)
		(pad "1" smd rect
			(at 1.025 -0.975)
			(size 0.5 0.35)
			(layers "F.Cu" "F.Mask" "F.Paste")
			(net "GND")
			(solder_mask_margin 0)
			(solder_paste_margin 0)
		)
		(pad "2" smd rect
			(at 1.025 -0.325)
			(size 0.5 0.35)
			(layers "F.Cu" "F.Mask" "F.Paste")
			(net "+3.3V")
			(solder_mask_margin 0)
			(solder_paste_margin 0)
		)
		(pad "3" smd rect
			(at 1.025 0.325)
			(size 0.5 0.35)
			(layers "F.Cu" "F.Mask" "F.Paste")
			(net "SDA")
			(solder_mask_margin 0)
			(solder_paste_margin 0)
		)
		(pad "4" smd rect
			(at 1.025 0.975)
			(size 0.5 0.35)
			(layers "F.Cu" "F.Mask" "F.Paste")
			(net "SCL")
			(solder_mask_margin 0)
			(solder_paste_margin 0)
		)
		(pad "5" smd rect
			(at -1.025 0.975)
			(size 0.5 0.35)
			(layers "F.Cu" "F.Mask" "F.Paste")
			(net "GND")
			(solder_mask_margin 0)
			(solder_paste_margin 0)
		)
		(pad "6" smd rect
			(at -1.025 0.325)
			(size 0.5 0.35)
			(layers "F.Cu" "F.Mask" "F.Paste")
			(net "+3.3V")
			(solder_mask_margin 0)
			(solder_paste_margin 0)
		)
		(pad "7" smd rect
			(at -1.025 -0.325)
			(size 0.5 0.35)
			(layers "F.Cu" "F.Mask" "F.Paste")
			(net "GND")
			(solder_mask_margin 0)
			(solder_paste_margin 0)
		)
		(pad "8" smd rect
			(at -1.025 -0.975)
			(size 0.5 0.35)
			(layers "F.Cu" "F.Mask" "F.Paste")
			(net "+3.3V")
			(solder_mask_margin 0)
			(solder_paste_margin 0)
		)
	)
	(footprint "Vault:FP-CC0402-MFG"
		(layer "F.Cu")
		(at 205.4261 105.8162 -90)
		(property "Reference" "C8"
			(at -2.4 0.493345 270)
			(unlocked yes)
			(layer "F.SilkS")
			(effects
				(font
					(size 0.762 0.762)
					(thickness 0.2286)
				)
				(justify left bottom)
			)
		)
		(property "Value" "4.7nF_50V_0402"
			(at 31.257845 -2.1089 0)
			(unlocked yes)
			(layer "F.SilkS")
			(hide yes)
			(effects
				(font
					(size 0.762 0.762)
					(thickness 0.2286)
				)
				(justify left bottom)
			)
		)
		(sheetname "POWER")
		(sheetfile "POWER.kicad_sch")
		(duplicate_pad_numbers_are_jumpers no)
		(fp_line
			(start 0.51967 0.68067)
			(end -0.53033 0.68067)
			(stroke
				(width 0.2)
				(type solid)
			)
			(layer "F.SilkS")
		)
		(fp_line
			(start 0.525 -0.675)
			(end -0.525 -0.675)
			(stroke
				(width 0.2)
				(type solid)
			)
			(layer "F.SilkS")
		)
		(fp_line
			(start -0.875 0.475)
			(end -0.875 -0.475)
			(stroke
				(width 0.2)
				(type solid)
			)
			(layer "F.CrtYd")
		)
		(fp_line
			(start 0.875 0.475)
			(end -0.875 0.475)
			(stroke
				(width 0.2)
				(type solid)
			)
			(layer "F.CrtYd")
		)
		(fp_line
			(start 0.875 0.475)
			(end 0.875 -0.475)
			(stroke
				(width 0.2)
				(type solid)
			)
			(layer "F.CrtYd")
		)
		(fp_line
			(start 0.875 -0.475)
			(end -0.875 -0.475)
			(stroke
				(width 0.2)
				(type solid)
			)
			(layer "F.CrtYd")
		)
		(fp_line
			(start 0 0.5)
			(end 0 -0.5)
			(stroke
				(width 0.1)
				(type solid)
			)
			(layer "F.Fab")
		)
		(fp_line
			(start -0.875 0.475)
			(end -0.875 -0.475)
			(stroke
				(width 0.2)
				(type solid)
			)
			(layer "F.Fab")
		)
		(fp_line
			(start 0.875 0.475)
			(end -0.875 0.475)
			(stroke
				(width 0.2)
				(type solid)
			)
			(layer "F.Fab")
		)
		(fp_line
			(start 0.875 0.475)
			(end 0.875 -0.475)
			(stroke
				(width 0.2)
				(type solid)
			)
			(layer "F.Fab")
		)
		(fp_line
			(start 0.5 0)
			(end -0.5 0)
			(stroke
				(width 0.1)
				(type solid)
			)
			(layer "F.Fab")
		)
		(fp_line
			(start 0.875 -0.475)
			(end -0.875 -0.475)
			(stroke
				(width 0.2)
				(type solid)
			)
			(layer "F.Fab")
		)
		(fp_text user "${REFERENCE}"
			(at -0.00001 0.09602 270)
			(unlocked yes)
			(layer "F.Fab")
			(effects
				(font
					(face "Arial")
					(size 0.63 0.63)
					(thickness 0.1)
				)
				(justify left bottom)
			)
		)
		(pad "1" smd rect
			(at -0.5 0 270)
			(size 0.5 0.5)
			(layers "F.Cu" "F.Mask" "F.Paste")
			(net "P5V_SENSE")
			(solder_mask_margin 0)
			(solder_paste_margin 0)
		)
		(pad "2" smd rect
			(at 0.5 0 270)
			(size 0.5 0.5)
			(layers "F.Cu" "F.Mask" "F.Paste")
			(net "P5V_FB")
			(solder_mask_margin 0)
			(solder_paste_margin 0)
		)
	)
	(footprint "Vault:CAPC1005X56X25NL10T15"
		(layer "F.Cu")
		(at 190.8261 87.0162 90)
		(property "Reference" "C67"
			(at 0.2286 1.326931 90)
			(unlocked yes)
			(layer "F.SilkS")
			(effects
				(font
					(size 0.762 0.762)
					(thickness 0.2286)
				)
			)
		)
		(property "Value" "0.1uF_0402"
			(at 2.06903 2.567191 90)
			(unlocked yes)
			(layer "F.SilkS")
			(hide yes)
			(effects
				(font
					(size 0.762 0.762)
					(thickness 0.2286)
				)
			)
		)
		(sheetname "GPS_IMU_SENSORS")
		(sheetfile "GPS_IMU_SENSORS.kicad_sch")
		(duplicate_pad_numbers_are_jumpers no)
		(pad "1" smd rect
			(at -0.44 0 180)
			(size 0.64 0.68)
			(layers "F.Cu" "F.Mask" "F.Paste")
			(net "GND")
		)
		(pad "2" smd rect
			(at 0.44 0 180)
			(size 0.64 0.68)
			(layers "F.Cu" "F.Mask" "F.Paste")
			(net "+3.3V")
		)
	)
	(footprint "Vault:RESC1005X40X25LL05T10"
		(layer "F.Cu")
		(at 125.1261 88.3162)
		(property "Reference" "R97"
			(at -1.7714 0.626931 0)
			(unlocked yes)
			(layer "F.SilkS")
			(effects
				(font
					(size 0.762 0.762)
					(thickness 0.2286)
				)
			)
		)
		(property "Value" "49.9_1%_0402"
			(at -2.579871 8.823665 270)
			(unlocked yes)
			(layer "F.SilkS")
			(hide yes)
			(effects
				(font
					(size 0.762 0.762)
					(thickness 0.2286)
				)
			)
		)
		(sheetname "USBUart_DipSelects")
		(sheetfile "USBUart_DipSelects.kicad_sch")
		(duplicate_pad_numbers_are_jumpers no)
		(pad "1" smd rect
			(at -0.375 0 90)
			(size 0.45 0.5)
			(layers "F.Cu" "F.Mask" "F.Paste")
			(net "FPGA_MAC_PPSDIFF_OUT")
		)
		(pad "2" smd rect
			(at 0.375 0 90)
			(size 0.45 0.5)
			(layers "F.Cu" "F.Mask" "F.Paste")
			(net "NetR97_2")
		)
	)
	(footprint "Vault:FP-0402-L_1_0_0_05-W_0_5-IPC_A"
		(layer "F.Cu")
		(at 202.8261 129.2162 180)
		(property "Reference" "C69"
			(at 3.1714 -3.426921 0)
			(unlocked yes)
			(layer "F.SilkS")
			(effects
				(font
					(size 0.762 0.762)
					(thickness 0.2286)
				)
			)
		)
		(property "Value" "1uF_16V_0402"
			(at -2.744951 8.290315 90)
			(unlocked yes)
			(layer "F.SilkS")
			(hide yes)
			(effects
				(font
					(size 0.762 0.762)
					(thickness 0.2286)
				)
			)
		)
		(sheetname "POWER")
		(sheetfile "POWER.kicad_sch")
		(duplicate_pad_numbers_are_jumpers no)
		(fp_line
			(start 0.83624 0.73624)
			(end -0.83624 0.73624)
			(stroke
				(width 0.2)
				(type solid)
			)
			(layer "F.SilkS")
		)
		(fp_line
			(start 0.83624 -0.73624)
			(end -0.83624 -0.73624)
			(stroke
				(width 0.2)
				(type solid)
			)
			(layer "F.SilkS")
		)
		(fp_line
			(start 1.03624 0.53624)
			(end -1.03624 0.53624)
			(stroke
				(width 0.2)
				(type solid)
			)
			(layer "F.CrtYd")
		)
		(fp_line
			(start 1.03624 -0.53624)
			(end 1.03624 0.53624)
			(stroke
				(width 0.2)
				(type solid)
			)
			(layer "F.CrtYd")
		)
		(fp_line
			(start 1.03624 -0.53624)
			(end -1.03624 -0.53624)
			(stroke
				(width 0.2)
				(type solid)
			)
			(layer "F.CrtYd")
		)
		(fp_line
			(start -1.03624 -0.53624)
			(end -1.03624 0.53624)
			(stroke
				(width 0.2)
				(type solid)
			)
			(layer "F.CrtYd")
		)
		(fp_line
			(start 1.03624 0.53624)
			(end -1.03624 0.53624)
			(stroke
				(width 0.2)
				(type solid)
			)
			(layer "F.Fab")
		)
		(fp_line
			(start 1.03624 -0.53624)
			(end 1.03624 0.53624)
			(stroke
				(width 0.2)
				(type solid)
			)
			(layer "F.Fab")
		)
		(fp_line
			(start 1.03624 -0.53624)
			(end -1.03624 -0.53624)
			(stroke
				(width 0.2)
				(type solid)
			)
			(layer "F.Fab")
		)
		(fp_line
			(start 0.5 0)
			(end -0.5 0)
			(stroke
				(width 0.1)
				(type solid)
			)
			(layer "F.Fab")
		)
		(fp_line
			(start 0 -0.5)
			(end 0 0.5)
			(stroke
				(width 0.1)
				(type solid)
			)
			(layer "F.Fab")
		)
		(fp_line
			(start -1.03624 -0.53624)
			(end -1.03624 0.53624)
			(stroke
				(width 0.2)
				(type solid)
			)
			(layer "F.Fab")
		)
		(fp_text user "${REFERENCE}"
			(at -0.00001 0.09601 180)
			(unlocked yes)
			(layer "F.Fab")
			(effects
				(font
					(face "Arial")
					(size 0.63 0.63)
					(thickness 0.1)
				)
				(justify left bottom)
			)
		)
		(pad "1" smd rect
			(at -0.47856 0 180)
			(size 0.71535 0.67248)
			(layers "F.Cu" "F.Mask" "F.Paste")
			(net "P3V3_VDD")
			(solder_mask_margin 0)
			(solder_paste_margin 0)
		)
		(pad "2" smd rect
			(at 0.47856 0 180)
			(size 0.71535 0.67248)
			(layers "F.Cu" "F.Mask" "F.Paste")
			(net "GND")
			(solder_mask_margin 0)
			(solder_paste_margin 0)
		)
	)
	(footprint "Vault:AMPH-901-143-6RFX_V"
		(layer "F.Cu")
		(at 60.9761 108.5782 180)
		(property "Reference" "AN2"
			(at -5.917345 2.55101 90)
			(unlocked yes)
			(layer "F.SilkS")
			(effects
				(font
					(size 0.762 0.762)
					(thickness 0.2286)
				)
				(justify left bottom)
			)
		)
		(property "Value" "RF2-49B-T-00-50-G-HDW"
			(at 4.6101 -1.960245 0)
			(unlocked yes)
			(layer "F.SilkS")
			(hide yes)
			(effects
				(font
					(size 0.762 0.762)
					(thickness 0.2286)
				)
				(justify left bottom)
			)
		)
		(sheetname "USER_IO")
		(sheetfile "USER_IO.kicad_sch")
		(duplicate_pad_numbers_are_jumpers no)
		(fp_line
			(start 3.5 -1.38)
			(end 3.5 1.38)
			(stroke
				(width 0.2)
				(type solid)
			)
			(layer "F.SilkS")
		)
		(fp_line
			(start 1.38 3.5)
			(end -1.38 3.5)
			(stroke
				(width 0.2)
				(type solid)
			)
			(layer "F.SilkS")
		)
		(fp_line
			(start 1.38 -3.5)
			(end -1.38 -3.5)
			(stroke
				(width 0.2)
				(type solid)
			)
			(layer "F.SilkS")
		)
		(fp_line
			(start -3.5 -1.38)
			(end -3.5 1.38)
			(stroke
				(width 0.2)
				(type solid)
			)
			(layer "F.SilkS")
		)
		(pad "1" thru_hole rect
			(at 0 0 180)
			(size 2 2)
			(drill 1.5)
			(layers "*.Cu" "*.Mask")
			(remove_unused_layers no)
			(net "NetAN2_1")
		)
		(pad "2" thru_hole circle
			(at -2.54 -2.54 180)
			(size 2.2 2.2)
			(drill 1.7)
			(layers "*.Cu" "*.Mask")
			(remove_unused_layers no)
			(net "GND")
			(thermal_bridge_angle 90)
		)
		(pad "3" thru_hole circle
			(at -2.54 2.54 180)
			(size 2.2 2.2)
			(drill 1.7)
			(layers "*.Cu" "*.Mask")
			(remove_unused_layers no)
			(net "GND")
			(thermal_bridge_angle 90)
		)
		(pad "4" thru_hole circle
			(at 2.54 2.54 180)
			(size 2.2 2.2)
			(drill 1.7)
			(layers "*.Cu" "*.Mask")
			(remove_unused_layers no)
			(net "GND")
			(thermal_bridge_angle 90)
		)
		(pad "5" thru_hole circle
			(at 2.54 -2.54 180)
			(size 2.2 2.2)
			(drill 1.7)
			(layers "*.Cu" "*.Mask")
			(remove_unused_layers no)
			(net "GND")
			(thermal_bridge_angle 90)
		)
	)
	(footprint "Vault:SMTC-TSW-105-05-X-S"
		(layer "F.Cu")
		(at 109.2261 85.6162 180)
		(property "Reference" "P1"
			(at 13.073079 0.228605 90)
			(unlocked yes)
			(layer "F.SilkS")
			(effects
				(font
					(size 0.762 0.762)
					(thickness 0.2286)
				)
			)
		)
		(property "Value" "TSW-105-05-L-S"
			(at -2.910071 6.360355 90)
			(unlocked yes)
			(layer "F.SilkS")
			(hide yes)
			(effects
				(font
					(size 0.762 0.762)
					(thickness 0.2286)
				)
			)
		)
		(sheetname "GPS_IMU_SENSORS")
		(sheetfile "GPS_IMU_SENSORS.kicad_sch")
		(duplicate_pad_numbers_are_jumpers no)
		(fp_line
			(start 11.62 1.27)
			(end -1.46 1.27)
			(stroke
				(width 0.2)
				(type solid)
			)
			(layer "F.SilkS")
		)
		(fp_line
			(start 11.62 -1.27)
			(end 11.62 1.27)
			(stroke
				(width 0.2)
				(type solid)
			)
			(layer "F.SilkS")
		)
		(fp_line
			(start 11.62 -1.27)
			(end -1.46 -1.27)
			(stroke
				(width 0.2)
				(type solid)
			)
			(layer "F.SilkS")
		)
		(fp_line
			(start -1.46 -1.27)
			(end -1.46 1.27)
			(stroke
				(width 0.2)
				(type solid)
			)
			(layer "F.SilkS")
		)
		(pad "1" thru_hole rect
			(at 0 0 180)
			(size 1.55 1.55)
			(drill 1.02)
			(layers "*.Cu" "*.Mask")
			(remove_unused_layers no)
			(net "+3.3V")
		)
		(pad "2" thru_hole circle
			(at 2.54 0 180)
			(size 1.55 1.55)
			(drill 1.02)
			(layers "*.Cu" "*.Mask")
			(remove_unused_layers no)
			(net "GND")
			(thermal_bridge_angle 90)
		)
		(pad "3" thru_hole circle
			(at 5.08 0 180)
			(size 1.55 1.55)
			(drill 1.02)
			(layers "*.Cu" "*.Mask")
			(remove_unused_layers no)
			(net "SCL")
			(thermal_bridge_angle 90)
		)
		(pad "4" thru_hole circle
			(at 7.62 0 180)
			(size 1.55 1.55)
			(drill 1.02)
			(layers "*.Cu" "*.Mask")
			(remove_unused_layers no)
			(net "SDA")
			(thermal_bridge_angle 90)
		)
		(pad "5" thru_hole circle
			(at 10.16 0 180)
			(size 1.55 1.55)
			(drill 1.02)
			(layers "*.Cu" "*.Mask")
			(remove_unused_layers no)
			(net "NetP1_5")
			(thermal_bridge_angle 90)
		)
	)
	(footprint "Vault:FP-0402-L_1_0_1-W_0_5_0_1-IPC_C"
		(layer "F.Cu")
		(at 222.5261 78.8162)
		(property "Reference" "C94"
			(at 2.3286 0.126931 0)
			(unlocked yes)
			(layer "F.SilkS")
			(effects
				(font
					(size 0.762 0.762)
					(thickness 0.2286)
				)
			)
		)
		(property "Value" "0.1uF_25V_0402"
			(at -2.465551 9.839215 270)
			(unlocked yes)
			(layer "F.SilkS")
			(hide yes)
			(effects
				(font
					(size 0.762 0.762)
					(thickness 0.2286)
				)
			)
		)
		(sheetname "USBUart_DipSelects")
		(sheetfile "USBUart_DipSelects.kicad_sch")
		(duplicate_pad_numbers_are_jumpers no)
		(fp_line
			(start -0.65607 -0.7)
			(end 0.65607 -0.7)
			(stroke
				(width 0.2)
				(type solid)
			)
			(layer "F.SilkS")
		)
		(fp_line
			(start -0.65607 0.7)
			(end 0.65607 0.7)
			(stroke
				(width 0.2)
				(type solid)
			)
			(layer "F.SilkS")
		)
		(fp_line
			(start -0.75607 -0.4)
			(end 0.75607 -0.4)
			(stroke
				(width 0.2)
				(type solid)
			)
			(layer "F.CrtYd")
		)
		(fp_line
			(start -0.75607 0.4)
			(end -0.75607 -0.4)
			(stroke
				(width 0.2)
				(type solid)
			)
			(layer "F.CrtYd")
		)
		(fp_line
			(start -0.75607 0.4)
			(end 0.75607 0.4)
			(stroke
				(width 0.2)
				(type solid)
			)
			(layer "F.CrtYd")
		)
		(fp_line
			(start 0.75607 0.4)
			(end 0.75607 -0.4)
			(stroke
				(width 0.2)
				(type solid)
			)
			(layer "F.CrtYd")
		)
		(fp_line
			(start -0.75607 -0.4)
			(end 0.75607 -0.4)
			(stroke
				(width 0.2)
				(type solid)
			)
			(layer "F.Fab")
		)
		(fp_line
			(start -0.75607 0.4)
			(end -0.75607 -0.4)
			(stroke
				(width 0.2)
				(type solid)
			)
			(layer "F.Fab")
		)
		(fp_line
			(start -0.75607 0.4)
			(end 0.75607 0.4)
			(stroke
				(width 0.2)
				(type solid)
			)
			(layer "F.Fab")
		)
		(fp_line
			(start -0.5 0)
			(end 0.5 0)
			(stroke
				(width 0.1)
				(type solid)
			)
			(layer "F.Fab")
		)
		(fp_line
			(start 0 0.5)
			(end 0 -0.5)
			(stroke
				(width 0.1)
				(type solid)
			)
			(layer "F.Fab")
		)
		(fp_line
			(start 0.75607 0.4)
			(end 0.75607 -0.4)
			(stroke
				(width 0.2)
				(type solid)
			)
			(layer "F.Fab")
		)
		(fp_text user "${REFERENCE}"
			(at -0.00001 0.09602 360)
			(unlocked yes)
			(layer "F.Fab")
			(effects
				(font
					(face "Arial")
					(size 0.63 0.63)
					(thickness 0.1)
				)
				(justify left bottom)
			)
		)
		(pad "1" smd rect
			(at -0.36554 0)
			(size 0.58106 0.51213)
			(layers "F.Cu" "F.Mask" "F.Paste")
			(net "+3.3V")
			(solder_mask_margin 0)
			(solder_paste_margin 0)
		)
		(pad "2" smd rect
			(at 0.36554 0)
			(size 0.58106 0.51213)
			(layers "F.Cu" "F.Mask" "F.Paste")
			(net "GND")
			(solder_mask_margin 0)
			(solder_paste_margin 0)
		)
	)
	(footprint "Vault:FP-CC0603-DA-MFG"
		(layer "F.Cu")
		(at 215.6261 130.2162 180)
		(property "Reference" "C68"
			(at 0.0286 -1.573069 180)
			(unlocked yes)
			(layer "F.SilkS")
			(effects
				(font
					(size 0.762 0.762)
					(thickness 0.2286)
				)
			)
		)
		(property "Value" "0.1uF_50V_0603"
			(at -3.075151 9.686815 90)
			(unlocked yes)
			(layer "F.SilkS")
			(hide yes)
			(effects
				(font
					(size 0.762 0.762)
					(thickness 0.2286)
				)
			)
		)
		(sheetname "POWER")
		(sheetfile "POWER.kicad_sch")
		(duplicate_pad_numbers_are_jumpers no)
		(fp_line
			(start 0.85 0.85)
			(end -0.85 0.85)
			(stroke
				(width 0.2)
				(type solid)
			)
			(layer "F.SilkS")
		)
		(fp_line
			(start 0.85 -0.85)
			(end -0.85 -0.85)
			(stroke
				(width 0.2)
				(type solid)
			)
			(layer "F.SilkS")
		)
		(fp_line
			(start 1.35 0.75)
			(end -1.35 0.75)
			(stroke
				(width 0.2)
				(type solid)
			)
			(layer "F.CrtYd")
		)
		(fp_line
			(start 1.35 -0.75)
			(end 1.35 0.75)
			(stroke
				(width 0.2)
				(type solid)
			)
			(layer "F.CrtYd")
		)
		(fp_line
			(start 1.35 -0.75)
			(end -1.35 -0.75)
			(stroke
				(width 0.2)
				(type solid)
			)
			(layer "F.CrtYd")
		)
		(fp_line
			(start -1.35 -0.75)
			(end -1.35 0.75)
			(stroke
				(width 0.2)
				(type solid)
			)
			(layer "F.CrtYd")
		)
		(fp_line
			(start 1.35 0.75)
			(end -1.35 0.75)
			(stroke
				(width 0.2)
				(type solid)
			)
			(layer "F.Fab")
		)
		(fp_line
			(start 1.35 -0.75)
			(end 1.35 0.75)
			(stroke
				(width 0.2)
				(type solid)
			)
			(layer "F.Fab")
		)
		(fp_line
			(start 1.35 -0.75)
			(end -1.35 -0.75)
			(stroke
				(width 0.2)
				(type solid)
			)
			(layer "F.Fab")
		)
		(fp_line
			(start 0.5 0)
			(end -0.5 0)
			(stroke
				(width 0.1)
				(type solid)
			)
			(layer "F.Fab")
		)
		(fp_line
			(start 0 -0.5)
			(end 0 0.5)
			(stroke
				(width 0.1)
				(type solid)
			)
			(layer "F.Fab")
		)
		(fp_line
			(start -1.35 -0.75)
			(end -1.35 0.75)
			(stroke
				(width 0.2)
				(type solid)
			)
			(layer "F.Fab")
		)
		(fp_text user "${REFERENCE}"
			(at -0.00001 0.09602 180)
			(unlocked yes)
			(layer "F.Fab")
			(effects
				(font
					(face "Arial")
					(size 0.63 0.63)
					(thickness 0.1)
				)
				(justify left bottom)
			)
		)
		(pad "1" smd rect
			(at -0.75 0 180)
			(size 0.8 0.9)
			(layers "F.Cu" "F.Mask" "F.Paste")
			(net "NetC68_1")
			(solder_mask_margin 0)
			(solder_paste_margin 0)
		)
		(pad "2" smd rect
			(at 0.75 0 180)
			(size 0.8 0.9)
			(layers "F.Cu" "F.Mask" "F.Paste")
			(net "NetC68_2")
			(solder_mask_margin 0)
			(solder_paste_margin 0)
		)
	)
	(footprint "Vault:RESC0402(1005)_N"
		(layer "F.Cu")
		(at 219.8261 116.0162)
		(property "Reference" "R4"
			(at -0.6 1.793345 0)
			(unlocked yes)
			(layer "F.SilkS")
			(effects
				(font
					(size 0.762 0.762)
					(thickness 0.2286)
				)
				(justify left bottom)
			)
		)
		(property "Value" "1.21_1%_0402"
			(at -0.2227 -8.970755 0)
			(unlocked yes)
			(layer "F.SilkS")
			(hide yes)
			(effects
				(font
					(size 0.762 0.762)
					(thickness 0.2286)
				)
				(justify left bottom)
			)
		)
		(sheetname "POWER")
		(sheetfile "POWER.kicad_sch")
		(duplicate_pad_numbers_are_jumpers no)
		(pad "1" smd rect
			(at -0.5 0 90)
			(size 0.65 0.55)
			(layers "F.Cu" "F.Mask" "F.Paste")
			(net "NetR4_1")
		)
		(pad "2" smd rect
			(at 0.5 0 90)
			(size 0.65 0.55)
			(layers "F.Cu" "F.Mask" "F.Paste")
			(net "NetC3_1")
		)
	)
	(footprint "Vault:RESC1608X55X30NL15T15"
		(layer "F.Cu")
		(at 84.1261 139.6162 -90)
		(property "Reference" "R31"
			(at 2.771395 -0.026931 90)
			(unlocked yes)
			(layer "F.SilkS")
			(effects
				(font
					(size 0.762 0.762)
					(thickness 0.2286)
				)
			)
		)
		(property "Value" "4.7K"
			(at 1.61204 2.325871 270)
			(unlocked yes)
			(layer "F.SilkS")
			(hide yes)
			(effects
				(font
					(size 0.762 0.762)
					(thickness 0.2286)
				)
			)
		)
		(sheetname "USER_IO")
		(sheetfile "USER_IO.kicad_sch")
		(duplicate_pad_numbers_are_jumpers no)
		(pad "1" smd rect
			(at -0.75 0)
			(size 0.95 0.95)
			(layers "F.Cu" "F.Mask" "F.Paste")
			(net "ANT4_IO_OUT")
		)
		(pad "2" smd rect
			(at 0.75 0)
			(size 0.95 0.95)
			(layers "F.Cu" "F.Mask" "F.Paste")
			(net "+3.3V")
		)
	)
	(footprint "Vault:CAPC1005X56X25NL10T15"
		(layer "F.Cu")
		(at 231.9261 127.0162 180)
		(property "Reference" "C84"
			(at -2.7286 -0.226931 0)
			(unlocked yes)
			(layer "F.SilkS")
			(effects
				(font
					(size 0.762 0.762)
					(thickness 0.2286)
				)
			)
		)
		(property "Value" "0.1uF_0402"
			(at -2.592551 7.0716 90)
			(unlocked yes)
			(layer "F.SilkS")
			(hide yes)
			(effects
				(font
					(size 0.762 0.762)
					(thickness 0.2286)
				)
			)
		)
		(sheetname "POWER")
		(sheetfile "POWER.kicad_sch")
		(duplicate_pad_numbers_are_jumpers no)
		(pad "1" smd rect
			(at -0.44 0 270)
			(size 0.64 0.68)
			(layers "F.Cu" "F.Mask" "F.Paste")
			(net "GND")
		)
		(pad "2" smd rect
			(at 0.44 0 270)
			(size 0.64 0.68)
			(layers "F.Cu" "F.Mask" "F.Paste")
			(net "+3.3V")
		)
	)
	(footprint "Vault:CAPC1608X87X45ML20T05"
		(layer "F.Cu")
		(at 80.6261 112.1162 -90)
		(property "Reference" "C28"
			(at 2.7714 -0.026931 90)
			(unlocked yes)
			(layer "F.SilkS")
			(effects
				(font
					(size 0.762 0.762)
					(thickness 0.2286)
				)
			)
		)
		(property "Value" "0.1uF"
			(at 2.069025 2.630671 270)
			(unlocked yes)
			(layer "F.SilkS")
			(hide yes)
			(effects
				(font
					(size 0.762 0.762)
					(thickness 0.2286)
				)
			)
		)
		(sheetname "USER_IO")
		(sheetfile "USER_IO.kicad_sch")
		(duplicate_pad_numbers_are_jumpers no)
		(pad "1" smd rect
			(at -0.7 0)
			(size 1.1 1.05)
			(layers "F.Cu" "F.Mask" "F.Paste")
			(net "+3.3V")
		)
		(pad "2" smd rect
			(at 0.7 0)
			(size 1.1 1.05)
			(layers "F.Cu" "F.Mask" "F.Paste")
			(net "GND")
		)
	)
	(footprint "Vault:FP-0402-L_1_0_0_05-W_0_5-IPC_A"
		(layer "F.Cu")
		(at 205.7261 111.4162 180)
		(property "Reference" "C4"
			(at 0.6 -3.393345 0)
			(unlocked yes)
			(layer "F.SilkS")
			(effects
				(font
					(size 0.762 0.762)
					(thickness 0.2286)
				)
				(justify left bottom)
			)
		)
		(property "Value" "1uF_16V_0402"
			(at -8.7497 -4.622845 0)
			(unlocked yes)
			(layer "F.SilkS")
			(hide yes)
			(effects
				(font
					(size 0.762 0.762)
					(thickness 0.2286)
				)
				(justify left bottom)
			)
		)
		(sheetname "POWER")
		(sheetfile "POWER.kicad_sch")
		(duplicate_pad_numbers_are_jumpers no)
		(fp_line
			(start 0.83623 0.73624)
			(end -0.83624 0.73624)
			(stroke
				(width 0.2)
				(type solid)
			)
			(layer "F.SilkS")
		)
		(fp_line
			(start 0.83623 -0.73624)
			(end -0.83624 -0.73624)
			(stroke
				(width 0.2)
				(type solid)
			)
			(layer "F.SilkS")
		)
		(fp_line
			(start 1.03623 0.53624)
			(end -1.03624 0.53624)
			(stroke
				(width 0.2)
				(type solid)
			)
			(layer "F.CrtYd")
		)
		(fp_line
			(start 1.03623 -0.53624)
			(end 1.03623 0.53624)
			(stroke
				(width 0.2)
				(type solid)
			)
			(layer "F.CrtYd")
		)
		(fp_line
			(start 1.03623 -0.53624)
			(end -1.03624 -0.53624)
			(stroke
				(width 0.2)
				(type solid)
			)
			(layer "F.CrtYd")
		)
		(fp_line
			(start -1.03624 -0.53624)
			(end -1.03624 0.53624)
			(stroke
				(width 0.2)
				(type solid)
			)
			(layer "F.CrtYd")
		)
		(fp_line
			(start 1.03623 0.53624)
			(end -1.03624 0.53624)
			(stroke
				(width 0.2)
				(type solid)
			)
			(layer "F.Fab")
		)
		(fp_line
			(start 1.03623 -0.53624)
			(end 1.03623 0.53624)
			(stroke
				(width 0.2)
				(type solid)
			)
			(layer "F.Fab")
		)
		(fp_line
			(start 1.03623 -0.53624)
			(end -1.03624 -0.53624)
			(stroke
				(width 0.2)
				(type solid)
			)
			(layer "F.Fab")
		)
		(fp_line
			(start 0.5 0)
			(end -0.5 0)
			(stroke
				(width 0.1)
				(type solid)
			)
			(layer "F.Fab")
		)
		(fp_line
			(start 0 -0.5)
			(end 0 0.5)
			(stroke
				(width 0.1)
				(type solid)
			)
			(layer "F.Fab")
		)
		(fp_line
			(start -1.03624 -0.53624)
			(end -1.03624 0.53624)
			(stroke
				(width 0.2)
				(type solid)
			)
			(layer "F.Fab")
		)
		(fp_text user "${REFERENCE}"
			(at -0.00002 0.09601 180)
			(unlocked yes)
			(layer "F.Fab")
			(effects
				(font
					(face "Arial")
					(size 0.63 0.63)
					(thickness 0.1)
				)
				(justify left bottom)
			)
		)
		(pad "1" smd rect
			(at -0.47856 0 180)
			(size 0.71535 0.67248)
			(layers "F.Cu" "F.Mask" "F.Paste")
			(net "P5V_VDD")
			(solder_mask_margin 0)
			(solder_paste_margin 0)
		)
		(pad "2" smd rect
			(at 0.47856 0 180)
			(size 0.71535 0.67248)
			(layers "F.Cu" "F.Mask" "F.Paste")
			(net "GND")
			(solder_mask_margin 0)
			(solder_paste_margin 0)
		)
	)
	(footprint "Vault:AMPH-901-143-6RFX_V"
		(layer "F.Cu")
		(at 60.9761 135.5786 180)
		(property "Reference" "AN4"
			(at -5.817355 2.786 90)
			(unlocked yes)
			(layer "F.SilkS")
			(effects
				(font
					(size 0.762 0.762)
					(thickness 0.2286)
				)
				(justify left bottom)
			)
		)
		(property "Value" "RF2-49B-T-00-50-G-HDW"
			(at 4.6101 -12.120245 0)
			(unlocked yes)
			(layer "F.SilkS")
			(hide yes)
			(effects
				(font
					(size 0.762 0.762)
					(thickness 0.2286)
				)
				(justify left bottom)
			)
		)
		(sheetname "USER_IO")
		(sheetfile "USER_IO.kicad_sch")
		(duplicate_pad_numbers_are_jumpers no)
		(fp_line
			(start 3.5 -1.38)
			(end 3.5 1.38)
			(stroke
				(width 0.2)
				(type solid)
			)
			(layer "F.SilkS")
		)
		(fp_line
			(start 1.38 3.5)
			(end -1.38 3.5)
			(stroke
				(width 0.2)
				(type solid)
			)
			(layer "F.SilkS")
		)
		(fp_line
			(start 1.38 -3.5)
			(end -1.38 -3.5)
			(stroke
				(width 0.2)
				(type solid)
			)
			(layer "F.SilkS")
		)
		(fp_line
			(start -3.5 -1.38)
			(end -3.5 1.38)
			(stroke
				(width 0.2)
				(type solid)
			)
			(layer "F.SilkS")
		)
		(pad "1" thru_hole rect
			(at 0 0 180)
			(size 2 2)
			(drill 1.5)
			(layers "*.Cu" "*.Mask")
			(remove_unused_layers no)
			(net "NetAN4_1")
		)
		(pad "2" thru_hole circle
			(at -2.54 -2.54 180)
			(size 2.2 2.2)
			(drill 1.7)
			(layers "*.Cu" "*.Mask")
			(remove_unused_layers no)
			(net "GND")
			(thermal_bridge_angle 90)
		)
		(pad "3" thru_hole circle
			(at -2.54 2.54 180)
			(size 2.2 2.2)
			(drill 1.7)
			(layers "*.Cu" "*.Mask")
			(remove_unused_layers no)
			(net "GND")
			(thermal_bridge_angle 90)
		)
		(pad "4" thru_hole circle
			(at 2.54 2.54 180)
			(size 2.2 2.2)
			(drill 1.7)
			(layers "*.Cu" "*.Mask")
			(remove_unused_layers no)
			(net "GND")
			(thermal_bridge_angle 90)
		)
		(pad "5" thru_hole circle
			(at 2.54 -2.54 180)
			(size 2.2 2.2)
			(drill 1.7)
			(layers "*.Cu" "*.Mask")
			(remove_unused_layers no)
			(net "GND")
			(thermal_bridge_angle 90)
		)
	)
	(footprint "Vault:RESC1005X40X25NL05T05"
		(layer "F.Cu")
		(at 218.0761 75.9162)
		(property "Reference" "R100"
			(at -0.0214 -1.073069 0)
			(unlocked yes)
			(layer "F.SilkS")
			(effects
				(font
					(size 0.762 0.762)
					(thickness 0.2286)
				)
			)
		)
		(property "Value" "DNI_27_1%_0402"
			(at -2.732281 10.296375 270)
			(unlocked yes)
			(layer "F.SilkS")
			(hide yes)
			(effects
				(font
					(size 0.762 0.762)
					(thickness 0.2286)
				)
			)
		)
		(sheetname "USBUart_DipSelects")
		(sheetfile "USBUart_DipSelects.kicad_sch")
		(duplicate_pad_numbers_are_jumpers no)
		(pad "1" smd rect
			(at -0.45 0 90)
			(size 0.55 0.55)
			(layers "F.Cu" "F.Mask" "F.Paste")
			(net "FTDI_RX")
		)
		(pad "2" smd rect
			(at 0.45 0 90)
			(size 0.55 0.55)
			(layers "F.Cu" "F.Mask" "F.Paste")
			(net "UART1_TXD")
		)
	)
	(footprint "Vault:RESC1005X40X25LL05T10"
		(layer "F.Cu")
		(at 128.0261 84.4162 180)
		(property "Reference" "R98"
			(at -1.0286 2.873069 0)
			(unlocked yes)
			(layer "F.SilkS")
			(effects
				(font
					(size 0.762 0.762)
					(thickness 0.2286)
				)
			)
		)
		(property "Value" "49.9_1%_0402"
			(at -2.579871 8.823665 90)
			(unlocked yes)
			(layer "F.SilkS")
			(hide yes)
			(effects
				(font
					(size 0.762 0.762)
					(thickness 0.2286)
				)
			)
		)
		(sheetname "USBUart_DipSelects")
		(sheetfile "USBUart_DipSelects.kicad_sch")
		(duplicate_pad_numbers_are_jumpers no)
		(pad "1" smd rect
			(at -0.375 0 270)
			(size 0.45 0.5)
			(layers "F.Cu" "F.Mask" "F.Paste")
			(net "MAC_PPS_IN")
		)
		(pad "2" smd rect
			(at 0.375 0 270)
			(size 0.45 0.5)
			(layers "F.Cu" "F.Mask" "F.Paste")
			(net "NetR98_2")
		)
	)
	(footprint "Vault:RESC1608X55X25NL10T15"
		(layer "F.Cu")
		(at 77.8761 108.6162 180)
		(property "Reference" "R33"
			(at -0.2286 1.473069 0)
			(unlocked yes)
			(layer "F.SilkS")
			(effects
				(font
					(size 0.762 0.762)
					(thickness 0.2286)
				)
			)
		)
		(property "Value" "49.9R"
			(at -2.884671 3.186595 90)
			(unlocked yes)
			(layer "F.SilkS")
			(hide yes)
			(effects
				(font
					(size 0.762 0.762)
					(thickness 0.2286)
				)
			)
		)
		(sheetname "USER_IO")
		(sheetfile "USER_IO.kicad_sch")
		(duplicate_pad_numbers_are_jumpers no)
		(pad "1" smd rect
			(at -0.7 0 270)
			(size 0.9 0.7)
			(layers "F.Cu" "F.Mask" "F.Paste")
			(net "NetR33_1")
		)
		(pad "2" smd rect
			(at 0.7 0 270)
			(size 0.9 0.7)
			(layers "F.Cu" "F.Mask" "F.Paste")
			(net "NetAN2_1")
		)
	)
	(footprint "Vault:RESC1005X40X25NL05T10"
		(layer "F.Cu")
		(at 203.5761 121.0662 90)
		(property "Reference" "R76"
			(at 2.3786 -1.523079 90)
			(unlocked yes)
			(layer "F.SilkS")
			(effects
				(font
					(size 0.762 0.762)
					(thickness 0.2286)
				)
			)
		)
		(property "Value" "2.49K_1%_0402"
			(at -2.732271 9.53462 0)
			(unlocked yes)
			(layer "F.SilkS")
			(hide yes)
			(effects
				(font
					(size 0.762 0.762)
					(thickness 0.2286)
				)
			)
		)
		(sheetname "POWER")
		(sheetfile "POWER.kicad_sch")
		(duplicate_pad_numbers_are_jumpers no)
		(pad "1" smd rect
			(at -0.425 0 180)
			(size 0.55 0.6)
			(layers "F.Cu" "F.Mask" "F.Paste")
			(net "P3V3_FB")
		)
		(pad "2" smd rect
			(at 0.425 0 180)
			(size 0.55 0.6)
			(layers "F.Cu" "F.Mask" "F.Paste")
			(net "P3V3_SENSE")
		)
	)
	(footprint "Vault:RESC1005X40X25NL05T05"
		(layer "F.Cu")
		(at 217.2261 79.3162)
		(property "Reference" "R87"
			(at 0.0286 -0.673069 0)
			(unlocked yes)
			(layer "F.SilkS")
			(effects
				(font
					(size 0.762 0.762)
					(thickness 0.2286)
				)
			)
		)
		(property "Value" "27_1%_0402"
			(at -2.732281 7.37632 270)
			(unlocked yes)
			(layer "F.SilkS")
			(hide yes)
			(effects
				(font
					(size 0.762 0.762)
					(thickness 0.2286)
				)
			)
		)
		(sheetname "USBUart_DipSelects")
		(sheetfile "USBUart_DipSelects.kicad_sch")
		(duplicate_pad_numbers_are_jumpers no)
		(pad "1" smd rect
			(at -0.45 0 90)
			(size 0.55 0.55)
			(layers "F.Cu" "F.Mask" "F.Paste")
			(net "FTDI_TX")
		)
		(pad "2" smd rect
			(at 0.45 0 90)
			(size 0.55 0.55)
			(layers "F.Cu" "F.Mask" "F.Paste")
			(net "NetR87_2")
		)
	)
	(footprint "Vault:FP-T495D107K016ATE125-MFG"
		(layer "F.Cu")
		(at 230.8261 101.7162 -90)
		(property "Reference" "C14"
			(at -1.97531 -1.604455 90)
			(unlocked yes)
			(layer "F.SilkS")
			(effects
				(font
					(size 0.762 0.762)
					(thickness 0.2286)
				)
				(justify left bottom)
			)
		)
		(property "Value" "100uF_16V_2917"
			(at 15.597845 -5.1281 0)
			(unlocked yes)
			(layer "F.SilkS")
			(hide yes)
			(effects
				(font
					(size 0.762 0.762)
					(thickness 0.2286)
				)
				(justify left bottom)
			)
		)
		(sheetname "POWER")
		(sheetfile "POWER.kicad_sch")
		(duplicate_pad_numbers_are_jumpers no)
		(fp_line
			(start -3.8 2.3)
			(end -3.8 1.54)
			(stroke
				(width 0.2)
				(type solid)
			)
			(layer "F.SilkS")
		)
		(fp_line
			(start 3.8 2.3)
			(end -3.8 2.3)
			(stroke
				(width 0.2)
				(type solid)
			)
			(layer "F.SilkS")
		)
		(fp_line
			(start 3.8 2.3)
			(end 3.8 1.54)
			(stroke
				(width 0.2)
				(type solid)
			)
			(layer "F.SilkS")
		)
		(fp_line
			(start 4.7 0.3)
			(end 4.7 -0.3)
			(stroke
				(width 0.2)
				(type solid)
			)
			(layer "F.SilkS")
		)
		(fp_line
			(start 5 0)
			(end 4.4 0)
			(stroke
				(width 0.2)
				(type solid)
			)
			(layer "F.SilkS")
		)
		(fp_line
			(start -3.8 -1.54)
			(end -3.8 -2.3)
			(stroke
				(width 0.2)
				(type solid)
			)
			(layer "F.SilkS")
		)
		(fp_line
			(start 3.8 -1.54)
			(end 3.8 -2.3)
			(stroke
				(width 0.2)
				(type solid)
			)
			(layer "F.SilkS")
		)
		(fp_line
			(start 3.8 -2.3)
			(end -3.8 -2.3)
			(stroke
				(width 0.2)
				(type solid)
			)
			(layer "F.SilkS")
		)
		(fp_line
			(start -4.105 2.4)
			(end -4.105 -2.4)
			(stroke
				(width 0.2)
				(type solid)
			)
			(layer "F.CrtYd")
		)
		(fp_line
			(start 4.105 2.4)
			(end -4.105 2.4)
			(stroke
				(width 0.2)
				(type solid)
			)
			(layer "F.CrtYd")
		)
		(fp_line
			(start 4.105 2.4)
			(end 4.105 -2.4)
			(stroke
				(width 0.2)
				(type solid)
			)
			(layer "F.CrtYd")
		)
		(fp_line
			(start 4.105 -2.4)
			(end -4.105 -2.4)
			(stroke
				(width 0.2)
				(type solid)
			)
			(layer "F.CrtYd")
		)
		(fp_line
			(start -4.105 2.4)
			(end -4.105 -2.4)
			(stroke
				(width 0.2)
				(type solid)
			)
			(layer "F.Fab")
		)
		(fp_line
			(start 4.105 2.4)
			(end -4.105 2.4)
			(stroke
				(width 0.2)
				(type solid)
			)
			(layer "F.Fab")
		)
		(fp_line
			(start 4.105 2.4)
			(end 4.105 -2.4)
			(stroke
				(width 0.2)
				(type solid)
			)
			(layer "F.Fab")
		)
		(fp_line
			(start 0 0.5)
			(end 0 -0.5)
			(stroke
				(width 0.1)
				(type solid)
			)
			(layer "F.Fab")
		)
		(fp_line
			(start 0.5 0)
			(end -0.5 0)
			(stroke
				(width 0.1)
				(type solid)
			)
			(layer "F.Fab")
		)
		(fp_line
			(start 4.105 -2.4)
			(end -4.105 -2.4)
			(stroke
				(width 0.2)
				(type solid)
			)
			(layer "F.Fab")
		)
		(fp_text user "${REFERENCE}"
			(at 0.00001 0.28425 270)
			(unlocked yes)
			(layer "F.Fab")
			(effects
				(font
					(face "Arial")
					(size 0.63 0.63)
					(thickness 0.1)
				)
				(justify left bottom)
			)
		)
		(pad "1" smd rect
			(at -3.01 0 270)
			(size 1.99 2.33)
			(layers "F.Cu" "F.Mask" "F.Paste")
			(net "GND")
			(solder_mask_margin 0)
			(solder_paste_margin 0)
		)
		(pad "2" smd rect
			(at 3.01 0 270)
			(size 1.99 2.33)
			(layers "F.Cu" "F.Mask" "F.Paste")
			(net "+5.0V")
			(solder_mask_margin 0)
			(solder_paste_margin 0)
		)
	)
	(footprint "GNSS:GNSS"
		(locked yes)
		(layer "F.Cu")
		(at 225.8486 61.6786 180)
		(property "Reference" "U15"
			(at 61.995579 -17.309 90)
			(unlocked yes)
			(layer "F.SilkS")
			(effects
				(font
					(size 0.762 0.762)
					(thickness 0.2286)
				)
			)
		)
		(property "Value" "RCB-F9T-1"
			(at -7.786881 -13.756155 90)
			(unlocked yes)
			(layer "F.SilkS")
			(hide yes)
			(effects
				(font
					(size 0.762 0.762)
					(thickness 0.2286)
				)
			)
		)
		(sheetname "GPS_IMU_SENSORS")
		(sheetfile "GPS_IMU_SENSORS.kicad_sch")
		(duplicate_pad_numbers_are_jumpers no)
		(fp_line
			(start 61.07 11.28)
			(end -6.11 11.28)
			(stroke
				(width 0.254)
				(type solid)
			)
			(layer "F.SilkS")
		)
		(fp_line
			(start 61.07 -20.47)
			(end 61.07 11.28)
			(stroke
				(width 0.254)
				(type solid)
			)
			(layer "F.SilkS")
		)
		(fp_line
			(start 61.07 -20.47)
			(end -6.11 -20.47)
			(stroke
				(width 0.254)
				(type solid)
			)
			(layer "F.SilkS")
		)
		(fp_line
			(start -6.11 -20.47)
			(end -6.11 11.28)
			(stroke
				(width 0.254)
				(type solid)
			)
			(layer "F.SilkS")
		)
		(pad "0" thru_hole circle
			(at 0 -2 90)
			(size 0 0)
			(drill 0.76)
			(layers "*.Cu" "*.Mask")
			(remove_unused_layers no)
			(thermal_bridge_angle 90)
		)
		(pad "0" thru_hole circle
			(at 0 2 90)
			(size 0 0)
			(drill 0.76)
			(layers "*.Cu" "*.Mask")
			(remove_unused_layers no)
			(thermal_bridge_angle 90)
		)
		(pad "1" smd rect
			(at -2.2225 3 90)
			(size 1.12 2.105)
			(layers "F.Cu" "F.Mask" "F.Paste")
			(net "+5.0V")
		)
		(pad "2" smd rect
			(at 2.2225 3 90)
			(size 1.12 2.105)
			(layers "F.Cu" "F.Mask" "F.Paste")
			(net "+3.3V")
		)
		(pad "3" smd rect
			(at -2.2225 1 90)
			(size 1.12 2.105)
			(layers "F.Cu" "F.Mask" "F.Paste")
			(net "GPS2_TX")
		)
		(pad "4" smd rect
			(at 2.2225 1 90)
			(size 1.12 2.105)
			(layers "F.Cu" "F.Mask" "F.Paste")
			(net "GPS2_RST")
		)
		(pad "5" smd rect
			(at -2.2225 -1 90)
			(size 1.12 2.105)
			(layers "F.Cu" "F.Mask" "F.Paste")
			(net "GPS2_RX")
		)
		(pad "6" smd rect
			(at 2.2225 -1 90)
			(size 1.12 2.105)
			(layers "F.Cu" "F.Mask" "F.Paste")
			(net "GPS2_TP1")
		)
		(pad "7" smd rect
			(at -2.2225 -3 90)
			(size 1.12 2.105)
			(layers "F.Cu" "F.Mask" "F.Paste")
			(net "GPS2_TP2")
		)
		(pad "8" smd rect
			(at 2.2225 -3 90)
			(size 1.12 2.105)
			(layers "F.Cu" "F.Mask" "F.Paste")
			(net "GND")
		)
	)
	(footprint "SA53:SA53"
		(locked yes)
		(layer "F.Cu")
		(at 120.49358 116.5662 180)
		(property "Reference" "U10"
			(at -22.46112 27.623069 0)
			(unlocked yes)
			(layer "F.SilkS")
			(effects
				(font
					(size 0.762 0.762)
					(thickness 0.2286)
				)
			)
		)
		(property "Value" "MAC-SA5X"
			(at -18.327985 28.437071 180)
			(unlocked yes)
			(layer "F.SilkS")
			(hide yes)
			(effects
				(font
					(size 0.762 0.762)
					(thickness 0.2286)
				)
			)
		)
		(sheetname "MAC")
		(sheetfile "MAC.kicad_sch")
		(duplicate_pad_numbers_are_jumpers no)
		(fp_line
			(start 26.26748 26.75)
			(end -24.53252 26.75)
			(stroke
				(width 0.254)
				(type solid)
			)
			(layer "F.SilkS")
		)
		(fp_line
			(start 26.26748 -24.05)
			(end 26.26748 26.75)
			(stroke
				(width 0.254)
				(type solid)
			)
			(layer "F.SilkS")
		)
		(fp_line
			(start 26.26748 -24.05)
			(end -24.53252 -24.05)
			(stroke
				(width 0.254)
				(type solid)
			)
			(layer "F.SilkS")
		)
		(fp_line
			(start -24.53252 -24.05)
			(end -24.53252 26.75)
			(stroke
				(width 0.254)
				(type solid)
			)
			(layer "F.SilkS")
		)
		(fp_circle
			(center -15.74749 3.64128)
			(end -15.74749 3.76828)
			(stroke
				(width 0.254)
				(type solid)
			)
			(fill no)
			(layer "F.SilkS")
		)
		(pad "" np_thru_hole circle
			(at -15.05499 -16.94261 180)
			(size 6.096 6.096)
			(drill 2.54)
			(layers "*.Cu" "*.Mask")
			(thermal_bridge_angle 90)
			(padstack
				(mode front_inner_back)
				(layer "Inner"
					(shape circle)
					(size 3.048 3.048)
				)
				(layer "B.Cu"
					(shape circle)
					(size 6.096 6.096)
				)
			)
		)
		(pad "" np_thru_hole circle
			(at -14.98753 19.5926 180)
			(size 6.096 6.096)
			(drill 2.54)
			(layers "*.Cu" "*.Mask")
			(thermal_bridge_angle 90)
			(padstack
				(mode front_inner_back)
				(layer "Inner"
					(shape circle)
					(size 3.048 3.048)
				)
				(layer "B.Cu"
					(shape circle)
					(size 6.096 6.096)
				)
			)
		)
		(pad "" np_thru_hole circle
			(at 16.08749 22.666 180)
			(size 6.096 6.096)
			(drill 2.54)
			(layers "*.Cu" "*.Mask")
			(thermal_bridge_angle 90)
			(padstack
				(mode front_inner_back)
				(layer "Inner"
					(shape circle)
					(size 3.048 3.048)
				)
				(layer "B.Cu"
					(shape circle)
					(size 6.096 6.096)
				)
			)
		)
		(pad "" np_thru_hole circle
			(at 16.72249 -18.442 180)
			(size 6.096 6.096)
			(drill 2.54)
			(layers "*.Cu" "*.Mask")
			(thermal_bridge_angle 90)
			(padstack
				(mode front_inner_back)
				(layer "Inner"
					(shape circle)
					(size 3.048 3.048)
				)
				(layer "B.Cu"
					(shape circle)
					(size 6.096 6.096)
				)
			)
		)
		(pad "1" smd rect
			(at -17.16749 3.64128 270)
			(size 0.25 1.8)
			(layers "F.Cu" "F.Mask" "F.Paste")
			(net "MAC_PPS_IN1+")
		)
		(pad "2" smd rect
			(at -21.16749 3.64128 270)
			(size 0.25 1.8)
			(layers "F.Cu" "F.Mask" "F.Paste")
			(net "MAC_USB+")
		)
		(pad "3" smd rect
			(at -17.16749 3.13328 270)
			(size 0.25 1.8)
			(layers "F.Cu" "F.Mask" "F.Paste")
			(net "MAC_PPS_IN1-")
		)
		(pad "4" smd rect
			(at -21.16749 3.13328 270)
			(size 0.25 1.8)
			(layers "F.Cu" "F.Mask" "F.Paste")
			(net "MAC_USB-")
		)
		(pad "5" smd rect
			(at -17.16749 2.62528 270)
			(size 0.25 1.8)
			(layers "F.Cu" "F.Mask" "F.Paste")
			(net "MAC_PPS_IN0+")
		)
		(pad "6" smd rect
			(at -21.16749 2.62528 270)
			(size 0.25 1.8)
			(layers "F.Cu" "F.Mask" "F.Paste")
			(net "MAC_USB_PWR")
		)
		(pad "7" smd rect
			(at -17.16749 2.11728 270)
			(size 0.25 1.8)
			(layers "F.Cu" "F.Mask" "F.Paste")
			(net "MAC_PPS_IN0-")
		)
		(pad "8" smd rect
			(at -21.16749 2.11728 270)
			(size 0.25 1.8)
			(layers "F.Cu" "F.Mask" "F.Paste")
			(net "GND")
		)
		(pad "9" smd rect
			(at -17.16749 1.60928 270)
			(size 0.25 1.8)
			(layers "F.Cu" "F.Mask" "F.Paste")
			(net "GND")
		)
		(pad "10" smd rect
			(at -21.16749 1.60928 270)
			(size 0.25 1.8)
			(layers "F.Cu" "F.Mask" "F.Paste")
		)
		(pad "11" smd rect
			(at -17.16749 1.10128 270)
			(size 0.25 1.8)
			(layers "F.Cu" "F.Mask" "F.Paste")
		)
		(pad "12" smd rect
			(at -21.16749 1.10128 270)
			(size 0.25 1.8)
			(layers "F.Cu" "F.Mask" "F.Paste")
		)
		(pad "13" smd rect
			(at -17.16749 0.59328 270)
			(size 0.25 1.8)
			(layers "F.Cu" "F.Mask" "F.Paste")
		)
		(pad "14" smd rect
			(at -21.16749 0.59328 270)
			(size 0.25 1.8)
			(layers "F.Cu" "F.Mask" "F.Paste")
		)
		(pad "15" smd rect
			(at -17.16749 0.08528 270)
			(size 0.25 1.8)
			(layers "F.Cu" "F.Mask" "F.Paste")
			(net "GND")
		)
		(pad "16" smd rect
			(at -21.16749 0.08528 270)
			(size 0.25 1.8)
			(layers "F.Cu" "F.Mask" "F.Paste")
		)
		(pad "17" smd rect
			(at -17.16749 -0.42272 270)
			(size 0.25 1.8)
			(layers "F.Cu" "F.Mask" "F.Paste")
			(net "MAC_PPS_OUT+")
		)
		(pad "18" smd rect
			(at -21.16749 -0.42272 270)
			(size 0.25 1.8)
			(layers "F.Cu" "F.Mask" "F.Paste")
		)
		(pad "19" smd rect
			(at -17.16749 -0.93072 270)
			(size 0.25 1.8)
			(layers "F.Cu" "F.Mask" "F.Paste")
			(net "MAC_PPS_OUT-")
		)
		(pad "20" smd rect
			(at -21.16749 -0.93072 270)
			(size 0.25 1.8)
			(layers "F.Cu" "F.Mask" "F.Paste")
			(net "MAC_ALARM")
		)
		(pad "P1" thru_hole circle
			(at 21.16748 21.65 90)
			(size 2.54 2.54)
			(drill 2.0066)
			(layers "*.Cu" "*.Mask")
			(remove_unused_layers no)
			(net "MAC_FREQ_CTRL")
			(thermal_bridge_angle 90)
		)
		(pad "P2" thru_hole circle
			(at 21.16748 1.35 90)
			(size 2.54 2.54)
			(drill 2.0066)
			(layers "*.Cu" "*.Mask")
			(remove_unused_layers no)
			(net "GND")
			(thermal_bridge_angle 90)
		)
		(pad "P3" thru_hole circle
			(at 21.16748 -18.95 90)
			(size 2.54 2.54)
			(drill 2.0066)
			(layers "*.Cu" "*.Mask")
			(remove_unused_layers no)
			(net "MAC_RF_OUT")
			(thermal_bridge_angle 90)
		)
		(pad "P4" thru_hole circle
			(at -19.43252 -18.95 90)
			(size 2.54 2.54)
			(drill 2.0066)
			(layers "*.Cu" "*.Mask")
			(remove_unused_layers no)
			(net "GND")
			(thermal_bridge_angle 90)
		)
		(pad "P5" thru_hole circle
			(at -19.43252 21.65 90)
			(size 2.54 2.54)
			(drill 2.0066)
			(layers "*.Cu" "*.Mask")
			(remove_unused_layers no)
			(net "MAC_VCC")
			(thermal_bridge_angle 90)
		)
		(pad "P6" thru_hole circle
			(at -17.33252 -21.65 90)
			(size 2.54 2.54)
			(drill 2.0066)
			(layers "*.Cu" "*.Mask")
			(remove_unused_layers no)
			(net "MAC_BITE")
			(thermal_bridge_angle 90)
		)
		(pad "P7" thru_hole circle
			(at -14.33252 -21.65 90)
			(size 2.54 2.54)
			(drill 2.0066)
			(layers "*.Cu" "*.Mask")
			(remove_unused_layers no)
			(net "MAC_RX")
			(thermal_bridge_angle 90)
		)
		(pad "P8" thru_hole circle
			(at -11.33252 -21.65 90)
			(size 2.54 2.54)
			(drill 2.0066)
			(layers "*.Cu" "*.Mask")
			(remove_unused_layers no)
			(net "MAC_TX")
			(thermal_bridge_angle 90)
		)
		(pad "P9" thru_hole circle
			(at -8.28452 -21.65 90)
			(size 2.54 2.54)
			(drill 2.0066)
			(layers "*.Cu" "*.Mask")
			(remove_unused_layers no)
			(net "MAC_PPS_IN")
			(thermal_bridge_angle 90)
		)
		(pad "P10" thru_hole circle
			(at -5.23652 -21.65 90)
			(size 2.54 2.54)
			(drill 2.0066)
			(layers "*.Cu" "*.Mask")
			(remove_unused_layers no)
			(net "MAC_PPS_OUT")
			(thermal_bridge_angle 90)
		)
		(zone
			(layer "F.Cu")
			(hatch edge 0.5)
			(connect_pads
				(clearance 0)
			)
			(min_thickness 0.25)
			(keepout
				(tracks allowed)
				(vias allowed)
				(pads allowed)
				(copperpour not_allowed)
				(footprints allowed)
			)
			(placement
				(enabled no)
				(sheetname "")
			)
			(fill
				(thermal_gap 0.5)
				(thermal_bridge_width 0.5)
				(island_removal_mode 0)
			)
			(polygon
				(pts
					(xy 135.99358 120.0662) (xy 135.99359 110.0662) (xy 143.49359 110.0662) (xy 143.49358 120.0662)
				)
			)
		)
		(zone
			(layer "F.Cu")
			(hatch edge 0.5)
			(connect_pads
				(clearance 0)
			)
			(min_thickness 0.25)
			(keepout
				(tracks allowed)
				(vias allowed)
				(pads allowed)
				(copperpour not_allowed)
				(footprints allowed)
			)
			(placement
				(enabled no)
				(sheetname "")
			)
			(fill
				(thermal_gap 0.5)
				(thermal_bridge_width 0.5)
				(island_removal_mode 0)
			)
			(polygon
				(pts
					(xy 144.99358 121.5662) (xy 133.49358 121.5662) (xy 133.49358 109.0662) (xy 144.99358 109.0662)
				)
			)
		)
	)
	(footprint "Vault:CAPC1005X56X25NL10T15"
		(layer "F.Cu")
		(at 189.6261 90.0162 180)
		(property "Reference" "C32"
			(at -2.5286 -0.326931 0)
			(unlocked yes)
			(layer "F.SilkS")
			(effects
				(font
					(size 0.762 0.762)
					(thickness 0.2286)
				)
			)
		)
		(property "Value" "0.1uF_0402"
			(at 2.06904 2.567191 180)
			(unlocked yes)
			(layer "F.SilkS")
			(hide yes)
			(effects
				(font
					(size 0.762 0.762)
					(thickness 0.2286)
				)
			)
		)
		(sheetname "GPS_IMU_SENSORS")
		(sheetfile "GPS_IMU_SENSORS.kicad_sch")
		(duplicate_pad_numbers_are_jumpers no)
		(pad "1" smd rect
			(at -0.44 0 270)
			(size 0.64 0.68)
			(layers "F.Cu" "F.Mask" "F.Paste")
			(net "BNO_XIN32_C")
		)
		(pad "2" smd rect
			(at 0.44 0 270)
			(size 0.64 0.68)
			(layers "F.Cu" "F.Mask" "F.Paste")
			(net "BNO_XIN32")
		)
	)
	(footprint "Vault:FP-0402-L_1_0_1-W_0_5_0_1-IPC_C"
		(layer "F.Cu")
		(at 214.8261 78.5162 90)
		(property "Reference" "C95"
			(at 5.3286 0.126931 90)
			(unlocked yes)
			(layer "F.SilkS")
			(effects
				(font
					(size 0.762 0.762)
					(thickness 0.2286)
				)
			)
		)
		(property "Value" "0.1uF_25V_0402"
			(at -2.465551 9.839205 0)
			(unlocked yes)
			(layer "F.SilkS")
			(hide yes)
			(effects
				(font
					(size 0.762 0.762)
					(thickness 0.2286)
				)
			)
		)
		(sheetname "USBUart_DipSelects")
		(sheetfile "USBUart_DipSelects.kicad_sch")
		(duplicate_pad_numbers_are_jumpers no)
		(fp_line
			(start -0.65607 -0.7)
			(end 0.65607 -0.7)
			(stroke
				(width 0.2)
				(type solid)
			)
			(layer "F.SilkS")
		)
		(fp_line
			(start -0.65607 0.7)
			(end 0.65607 0.7)
			(stroke
				(width 0.2)
				(type solid)
			)
			(layer "F.SilkS")
		)
		(fp_line
			(start 0.75607 -0.4)
			(end 0.75607 0.4)
			(stroke
				(width 0.2)
				(type solid)
			)
			(layer "F.CrtYd")
		)
		(fp_line
			(start -0.75606 -0.4)
			(end 0.75607 -0.4)
			(stroke
				(width 0.2)
				(type solid)
			)
			(layer "F.CrtYd")
		)
		(fp_line
			(start -0.75606 -0.4)
			(end -0.75606 0.4)
			(stroke
				(width 0.2)
				(type solid)
			)
			(layer "F.CrtYd")
		)
		(fp_line
			(start -0.75606 0.4)
			(end 0.75607 0.4)
			(stroke
				(width 0.2)
				(type solid)
			)
			(layer "F.CrtYd")
		)
		(fp_line
			(start 0 -0.5)
			(end 0 0.5)
			(stroke
				(width 0.1)
				(type solid)
			)
			(layer "F.Fab")
		)
		(fp_line
			(start 0.75607 -0.4)
			(end 0.75607 0.4)
			(stroke
				(width 0.2)
				(type solid)
			)
			(layer "F.Fab")
		)
		(fp_line
			(start -0.75606 -0.4)
			(end 0.75607 -0.4)
			(stroke
				(width 0.2)
				(type solid)
			)
			(layer "F.Fab")
		)
		(fp_line
			(start -0.75606 -0.4)
			(end -0.75606 0.4)
			(stroke
				(width 0.2)
				(type solid)
			)
			(layer "F.Fab")
		)
		(fp_line
			(start -0.5 0)
			(end 0.5 0)
			(stroke
				(width 0.1)
				(type solid)
			)
			(layer "F.Fab")
		)
		(fp_line
			(start -0.75606 0.4)
			(end 0.75607 0.4)
			(stroke
				(width 0.2)
				(type solid)
			)
			(layer "F.Fab")
		)
		(fp_text user "${REFERENCE}"
			(at -0.00001 0.09601 90)
			(unlocked yes)
			(layer "F.Fab")
			(effects
				(font
					(face "Arial")
					(size 0.63 0.63)
					(thickness 0.1)
				)
				(justify left bottom)
			)
		)
		(pad "1" smd rect
			(at -0.36553 0 90)
			(size 0.58106 0.51213)
			(layers "F.Cu" "F.Mask" "F.Paste")
			(net "+3.3V")
			(solder_mask_margin 0)
			(solder_paste_margin 0)
		)
		(pad "2" smd rect
			(at 0.36554 0 90)
			(size 0.58106 0.51213)
			(layers "F.Cu" "F.Mask" "F.Paste")
			(net "GND")
			(solder_mask_margin 0)
			(solder_paste_margin 0)
		)
	)
	(footprint "Vault:FP-0402-L_1_0_0_05-W_0_5-IPC_A"
		(layer "F.Cu")
		(at 231.9261 125.3162)
		(property "Reference" "C82"
			(at 2.5286 0.026921 0)
			(unlocked yes)
			(layer "F.SilkS")
			(effects
				(font
					(size 0.762 0.762)
					(thickness 0.2286)
				)
			)
		)
		(property "Value" "1uF_16V_0402"
			(at -2.744951 8.290305 270)
			(unlocked yes)
			(layer "F.SilkS")
			(hide yes)
			(effects
				(font
					(size 0.762 0.762)
					(thickness 0.2286)
				)
			)
		)
		(sheetname "POWER")
		(sheetfile "POWER.kicad_sch")
		(duplicate_pad_numbers_are_jumpers no)
		(fp_line
			(start -0.83624 -0.73624)
			(end 0.83624 -0.73624)
			(stroke
				(width 0.2)
				(type solid)
			)
			(layer "F.SilkS")
		)
		(fp_line
			(start -0.83624 0.73624)
			(end 0.83624 0.73624)
			(stroke
				(width 0.2)
				(type solid)
			)
			(layer "F.SilkS")
		)
		(fp_line
			(start -1.03624 -0.53624)
			(end 1.03624 -0.53624)
			(stroke
				(width 0.2)
				(type solid)
			)
			(layer "F.CrtYd")
		)
		(fp_line
			(start -1.03624 0.53624)
			(end -1.03624 -0.53624)
			(stroke
				(width 0.2)
				(type solid)
			)
			(layer "F.CrtYd")
		)
		(fp_line
			(start -1.03624 0.53624)
			(end 1.03624 0.53624)
			(stroke
				(width 0.2)
				(type solid)
			)
			(layer "F.CrtYd")
		)
		(fp_line
			(start 1.03624 0.53624)
			(end 1.03624 -0.53624)
			(stroke
				(width 0.2)
				(type solid)
			)
			(layer "F.CrtYd")
		)
		(fp_line
			(start -1.03624 -0.53624)
			(end 1.03624 -0.53624)
			(stroke
				(width 0.2)
				(type solid)
			)
			(layer "F.Fab")
		)
		(fp_line
			(start -1.03624 0.53624)
			(end -1.03624 -0.53624)
			(stroke
				(width 0.2)
				(type solid)
			)
			(layer "F.Fab")
		)
		(fp_line
			(start -1.03624 0.53624)
			(end 1.03624 0.53624)
			(stroke
				(width 0.2)
				(type solid)
			)
			(layer "F.Fab")
		)
		(fp_line
			(start -0.5 0)
			(end 0.5 0)
			(stroke
				(width 0.1)
				(type solid)
			)
			(layer "F.Fab")
		)
		(fp_line
			(start 0 0.5)
			(end 0 -0.5)
			(stroke
				(width 0.1)
				(type solid)
			)
			(layer "F.Fab")
		)
		(fp_line
			(start 1.03624 0.53624)
			(end 1.03624 -0.53624)
			(stroke
				(width 0.2)
				(type solid)
			)
			(layer "F.Fab")
		)
		(fp_text user "${REFERENCE}"
			(at -0.00001 0.09602 360)
			(unlocked yes)
			(layer "F.Fab")
			(effects
				(font
					(face "Arial")
					(size 0.63 0.63)
					(thickness 0.1)
				)
				(justify left bottom)
			)
		)
		(pad "1" smd rect
			(at -0.47856 0)
			(size 0.71535 0.67248)
			(layers "F.Cu" "F.Mask" "F.Paste")
			(net "+3.3V")
			(solder_mask_margin 0)
			(solder_paste_margin 0)
		)
		(pad "2" smd rect
			(at 0.47856 0)
			(size 0.71535 0.67248)
			(layers "F.Cu" "F.Mask" "F.Paste")
			(net "GND")
			(solder_mask_margin 0)
			(solder_paste_margin 0)
		)
	)
	(footprint "Vault:RESC1005X40X25NL05T10"
		(layer "F.Cu")
		(at 211.3261 127.6162)
		(property "Reference" "R75"
			(at -0.0714 2.226931 0)
			(unlocked yes)
			(layer "F.SilkS")
			(effects
				(font
					(size 0.762 0.762)
					(thickness 0.2286)
				)
			)
		)
		(property "Value" "19.6K_1%_0402"
			(at -2.732271 9.40766 270)
			(unlocked yes)
			(layer "F.SilkS")
			(hide yes)
			(effects
				(font
					(size 0.762 0.762)
					(thickness 0.2286)
				)
			)
		)
		(sheetname "POWER")
		(sheetfile "POWER.kicad_sch")
		(duplicate_pad_numbers_are_jumpers no)
		(pad "1" smd rect
			(at -0.425 0 90)
			(size 0.55 0.6)
			(layers "F.Cu" "F.Mask" "F.Paste")
			(net "NetC74_1")
		)
		(pad "2" smd rect
			(at 0.425 0 90)
			(size 0.55 0.6)
			(layers "F.Cu" "F.Mask" "F.Paste")
			(net "NetL2_1")
		)
	)
	(footprint "Vault:FP-MK212BG-MFG"
		(layer "F.Cu")
		(at 94.7261 65.5162 90)
		(property "Reference" "C41"
			(at 3.171395 -0.026931 270)
			(unlocked yes)
			(layer "F.SilkS")
			(effects
				(font
					(size 0.762 0.762)
					(thickness 0.2286)
				)
			)
		)
		(property "Value" "10uF"
			(at 1.45964 2.478271 90)
			(unlocked yes)
			(layer "F.SilkS")
			(hide yes)
			(effects
				(font
					(size 0.762 0.762)
					(thickness 0.2286)
				)
			)
		)
		(sheetname "GPS_IMU_SENSORS")
		(sheetfile "GPS_IMU_SENSORS.kicad_sch")
		(duplicate_pad_numbers_are_jumpers no)
		(fp_line
			(start -0.125 -0.725)
			(end 0.125 -0.725)
			(stroke
				(width 0.2)
				(type solid)
			)
			(layer "F.SilkS")
		)
		(fp_line
			(start -0.125 0.725)
			(end 0.125 0.725)
			(stroke
				(width 0.2)
				(type solid)
			)
			(layer "F.SilkS")
		)
		(fp_line
			(start 1.6 -0.825)
			(end 1.6 0.825)
			(stroke
				(width 0.2)
				(type solid)
			)
			(layer "F.CrtYd")
		)
		(fp_line
			(start -1.6 -0.825)
			(end 1.6 -0.825)
			(stroke
				(width 0.2)
				(type solid)
			)
			(layer "F.CrtYd")
		)
		(fp_line
			(start -1.6 -0.825)
			(end -1.6 0.825)
			(stroke
				(width 0.2)
				(type solid)
			)
			(layer "F.CrtYd")
		)
		(fp_line
			(start -1.6 0.825)
			(end 1.6 0.825)
			(stroke
				(width 0.2)
				(type solid)
			)
			(layer "F.CrtYd")
		)
		(fp_line
			(start 1.6 -0.825)
			(end 1.6 0.825)
			(stroke
				(width 0.2)
				(type solid)
			)
			(layer "F.Fab")
		)
		(fp_line
			(start -1.6 -0.825)
			(end 1.6 -0.825)
			(stroke
				(width 0.2)
				(type solid)
			)
			(layer "F.Fab")
		)
		(fp_line
			(start -1.6 -0.825)
			(end -1.6 0.825)
			(stroke
				(width 0.2)
				(type solid)
			)
			(layer "F.Fab")
		)
		(fp_line
			(start 0 -0.5)
			(end 0 0.5)
			(stroke
				(width 0.1)
				(type solid)
			)
			(layer "F.Fab")
		)
		(fp_line
			(start -0.5 0)
			(end 0.5 0)
			(stroke
				(width 0.1)
				(type solid)
			)
			(layer "F.Fab")
		)
		(fp_line
			(start -1.6 0.825)
			(end 1.6 0.825)
			(stroke
				(width 0.2)
				(type solid)
			)
			(layer "F.Fab")
		)
		(fp_text user "${REFERENCE}"
			(at -0.00001 0.09601 90)
			(unlocked yes)
			(layer "F.Fab")
			(effects
				(font
					(face "Arial")
					(size 0.63 0.63)
					(thickness 0.1)
				)
				(justify left bottom)
			)
		)
		(pad "1" smd rect
			(at -1 0 90)
			(size 1 1.25)
			(layers "F.Cu" "F.Mask" "F.Paste")
			(net "+3.3V")
			(solder_mask_margin 0)
			(solder_paste_margin 0)
		)
		(pad "2" smd rect
			(at 1 0 90)
			(size 1 1.25)
			(layers "F.Cu" "F.Mask" "F.Paste")
			(net "GND")
			(solder_mask_margin 0)
			(solder_paste_margin 0)
		)
	)
	(footprint "Vault:RESC1005X40X25LL10T10"
		(layer "F.Cu")
		(at 214.1261 113.5162 90)
		(property "Reference" "R9"
			(at -2.427 -0.395345 270)
			(unlocked yes)
			(layer "F.SilkS")
			(effects
				(font
					(size 0.762 0.762)
					(thickness 0.2286)
				)
				(justify left bottom)
			)
		)
		(property "Value" "1.21_1%_0402"
			(at -10.660245 10.4651 0)
			(unlocked yes)
			(layer "F.SilkS")
			(hide yes)
			(effects
				(font
					(size 0.762 0.762)
					(thickness 0.2286)
				)
				(justify left bottom)
			)
		)
		(sheetname "POWER")
		(sheetfile "POWER.kicad_sch")
		(duplicate_pad_numbers_are_jumpers no)
		(pad "1" smd rect
			(at -0.375 0 180)
			(size 0.5 0.55)
			(layers "F.Cu" "F.Mask" "F.Paste")
			(net "NetC7_1")
		)
		(pad "2" smd rect
			(at 0.375 0 180)
			(size 0.5 0.55)
			(layers "F.Cu" "F.Mask" "F.Paste")
			(net "NetL1_1")
		)
	)
	(footprint "Vault:RESC1608X55X30NL15T15"
		(layer "F.Cu")
		(at 84.1261 112.1162 -90)
		(property "Reference" "R29"
			(at 4 -0.593345 90)
			(unlocked yes)
			(layer "F.SilkS")
			(effects
				(font
					(size 0.762 0.762)
					(thickness 0.2286)
				)
				(justify left bottom)
			)
		)
		(property "Value" "4.7K"
			(at 3.636645 0.4445 0)
			(unlocked yes)
			(layer "F.SilkS")
			(hide yes)
			(effects
				(font
					(size 0.762 0.762)
					(thickness 0.2286)
				)
				(justify left bottom)
			)
		)
		(sheetname "USER_IO")
		(sheetfile "USER_IO.kicad_sch")
		(duplicate_pad_numbers_are_jumpers no)
		(pad "1" smd rect
			(at -0.75 0)
			(size 0.95 0.95)
			(layers "F.Cu" "F.Mask" "F.Paste")
			(net "ANT2_IO_OUT")
		)
		(pad "2" smd rect
			(at 0.75 0)
			(size 0.95 0.95)
			(layers "F.Cu" "F.Mask" "F.Paste")
			(net "+3.3V")
		)
	)
	(footprint "Vault:RESC1608X55X30NL15T15"
		(layer "F.Cu")
		(at 73.3761 55.6162 90)
		(property "Reference" "R38"
			(at -5.7714 0.026921 90)
			(unlocked yes)
			(layer "F.SilkS")
			(effects
				(font
					(size 0.762 0.762)
					(thickness 0.2286)
				)
			)
		)
		(property "Value" "200 OHM"
			(at -2.935471 4.78626 0)
			(unlocked yes)
			(layer "F.SilkS")
			(hide yes)
			(effects
				(font
					(size 0.762 0.762)
					(thickness 0.2286)
				)
			)
		)
		(sheetname "USER_IO_STATUS")
		(sheetfile "USER_IO_STATUS.kicad_sch")
		(duplicate_pad_numbers_are_jumpers no)
		(pad "1" smd rect
			(at -0.675 0 180)
			(size 0.95 0.8)
			(layers "F.Cu" "F.Mask" "F.Paste")
			(net "LED3")
		)
		(pad "2" smd rect
			(at 0.675 0 180)
			(size 0.95 0.8)
			(layers "F.Cu" "F.Mask" "F.Paste")
			(net "NetD10_1")
		)
	)
	(footprint "Vault:RESC3116X65X50ML20T20"
		(layer "F.Cu")
		(at 155.9123 83.7162)
		(property "Reference" "R46"
			(at 3.9286 0.126931 0)
			(unlocked yes)
			(layer "F.SilkS")
			(effects
				(font
					(size 0.762 0.762)
					(thickness 0.2286)
				)
			)
		)
		(property "Value" "DNI_0_5%_1206"
			(at 7.27402 3.291071 0)
			(unlocked yes)
			(layer "F.SilkS")
			(hide yes)
			(effects
				(font
					(size 0.762 0.762)
					(thickness 0.2286)
				)
			)
		)
		(sheetname "MAC")
		(sheetfile "MAC.kicad_sch")
		(duplicate_pad_numbers_are_jumpers no)
		(fp_line
			(start -0.35 -0.85)
			(end 0.35 -0.85)
			(stroke
				(width 0.2)
				(type solid)
			)
			(layer "F.SilkS")
		)
		(fp_line
			(start -0.35 0.85)
			(end 0.35 0.85)
			(stroke
				(width 0.2)
				(type solid)
			)
			(layer "F.SilkS")
		)
		(pad "1" smd rect
			(at -1.475 0 90)
			(size 1.9 1.45)
			(layers "F.Cu" "F.Mask" "F.Paste")
			(net "MAC_VCC")
		)
		(pad "2" smd rect
			(at 1.475 0 90)
			(size 1.9 1.45)
			(layers "F.Cu" "F.Mask" "F.Paste")
			(net "+12V")
		)
	)
	(footprint "Vault:RESC1608X55X30NL15T15"
		(layer "F.Cu")
		(at 82.3761 112.1162 -90)
		(property "Reference" "R30"
			(at 4 -0.593345 90)
			(unlocked yes)
			(layer "F.SilkS")
			(effects
				(font
					(size 0.762 0.762)
					(thickness 0.2286)
				)
				(justify left bottom)
			)
		)
		(property "Value" "4.7K"
			(at 3.636645 0.4445 0)
			(unlocked yes)
			(layer "F.SilkS")
			(hide yes)
			(effects
				(font
					(size 0.762 0.762)
					(thickness 0.2286)
				)
				(justify left bottom)
			)
		)
		(sheetname "USER_IO")
		(sheetfile "USER_IO.kicad_sch")
		(duplicate_pad_numbers_are_jumpers no)
		(pad "1" smd rect
			(at -0.75 0)
			(size 0.95 0.95)
			(layers "F.Cu" "F.Mask" "F.Paste")
			(net "ANT2_IO_IN")
		)
		(pad "2" smd rect
			(at 0.75 0)
			(size 0.95 0.95)
			(layers "F.Cu" "F.Mask" "F.Paste")
			(net "+3.3V")
		)
	)
	(footprint "Vault:RESC0402(1005)_N"
		(layer "F.Cu")
		(at 207.3261 111.5162 -90)
		(property "Reference" "R5"
			(at 1.3 0.393345 270)
			(unlocked yes)
			(layer "F.SilkS")
			(effects
				(font
					(size 0.762 0.762)
					(thickness 0.2286)
				)
				(justify left bottom)
			)
		)
		(property "Value" "1.21_1%_0402"
			(at 32.959045 -0.6183 0)
			(unlocked yes)
			(layer "F.SilkS")
			(hide yes)
			(effects
				(font
					(size 0.762 0.762)
					(thickness 0.2286)
				)
				(justify left bottom)
			)
		)
		(sheetname "POWER")
		(sheetfile "POWER.kicad_sch")
		(duplicate_pad_numbers_are_jumpers no)
		(pad "1" smd rect
			(at -0.5 -0.00001)
			(size 0.65 0.55)
			(layers "F.Cu" "F.Mask" "F.Paste")
			(net "P5V_VDD")
		)
		(pad "2" smd rect
			(at 0.5 -0.00001)
			(size 0.65 0.55)
			(layers "F.Cu" "F.Mask" "F.Paste")
			(net "P5V_PVDD")
		)
	)
	(footprint "Vault:RESC1005X40X25NL05T05"
		(layer "F.Cu")
		(at 235.9261 65.6162 180)
		(property "Reference" "R42"
			(at 0.4714 0.973079 0)
			(unlocked yes)
			(layer "F.SilkS")
			(effects
				(font
					(size 0.762 0.762)
					(thickness 0.2286)
				)
			)
		)
		(property "Value" "27_1%_0402"
			(at -3.011631 6.10665 90)
			(unlocked yes)
			(layer "F.SilkS")
			(hide yes)
			(effects
				(font
					(size 0.762 0.762)
					(thickness 0.2286)
				)
			)
		)
		(sheetname "USBUart_DipSelects")
		(sheetfile "USBUart_DipSelects.kicad_sch")
		(duplicate_pad_numbers_are_jumpers no)
		(pad "1" smd rect
			(at -0.45 0 270)
			(size 0.55 0.55)
			(layers "F.Cu" "F.Mask" "F.Paste")
			(net "NetR42_1")
		)
		(pad "2" smd rect
			(at 0.45 0 270)
			(size 0.55 0.55)
			(layers "F.Cu" "F.Mask" "F.Paste")
			(net "FTDI_RX")
		)
	)
	(footprint "Vault:FP-ERJ2RK-IPC_A"
		(layer "F.Cu")
		(at 237.4261 135.3162 180)
		(property "Reference" "R77"
			(at -2.5286 -0.026921 0)
			(unlocked yes)
			(layer "F.SilkS")
			(effects
				(font
					(size 0.762 0.762)
					(thickness 0.2286)
				)
			)
		)
		(property "Value" "200_1%_0402"
			(at -2.935471 7.782475 90)
			(unlocked yes)
			(layer "F.SilkS")
			(hide yes)
			(effects
				(font
					(size 0.762 0.762)
					(thickness 0.2286)
				)
			)
		)
		(sheetname "POWER")
		(sheetfile "POWER.kicad_sch")
		(duplicate_pad_numbers_are_jumpers no)
		(fp_line
			(start 0.83624 0.73624)
			(end -0.83624 0.73624)
			(stroke
				(width 0.2)
				(type solid)
			)
			(layer "F.SilkS")
		)
		(fp_line
			(start 0.83624 -0.73624)
			(end -0.83624 -0.73624)
			(stroke
				(width 0.2)
				(type solid)
			)
			(layer "F.SilkS")
		)
		(fp_line
			(start 1.03624 0.53624)
			(end -1.03623 0.53624)
			(stroke
				(width 0.2)
				(type solid)
			)
			(layer "F.CrtYd")
		)
		(fp_line
			(start 1.03624 -0.53624)
			(end 1.03624 0.53624)
			(stroke
				(width 0.2)
				(type solid)
			)
			(layer "F.CrtYd")
		)
		(fp_line
			(start 1.03624 -0.53624)
			(end -1.03623 -0.53624)
			(stroke
				(width 0.2)
				(type solid)
			)
			(layer "F.CrtYd")
		)
		(fp_line
			(start -1.03623 -0.53624)
			(end -1.03623 0.53624)
			(stroke
				(width 0.2)
				(type solid)
			)
			(layer "F.CrtYd")
		)
		(fp_line
			(start 1.03624 0.53624)
			(end -1.03623 0.53624)
			(stroke
				(width 0.2)
				(type solid)
			)
			(layer "F.Fab")
		)
		(fp_line
			(start 1.03624 -0.53624)
			(end 1.03624 0.53624)
			(stroke
				(width 0.2)
				(type solid)
			)
			(layer "F.Fab")
		)
		(fp_line
			(start 1.03624 -0.53624)
			(end -1.03623 -0.53624)
			(stroke
				(width 0.2)
				(type solid)
			)
			(layer "F.Fab")
		)
		(fp_line
			(start 0.5 0)
			(end -0.5 0)
			(stroke
				(width 0.1)
				(type solid)
			)
			(layer "F.Fab")
		)
		(fp_line
			(start 0 -0.5)
			(end 0 0.5)
			(stroke
				(width 0.1)
				(type solid)
			)
			(layer "F.Fab")
		)
		(fp_line
			(start -1.03623 -0.53624)
			(end -1.03623 0.53624)
			(stroke
				(width 0.2)
				(type solid)
			)
			(layer "F.Fab")
		)
		(fp_text user "${REFERENCE}"
			(at -0.00001 0.10711 180)
			(unlocked yes)
			(layer "F.Fab")
			(effects
				(font
					(face "Arial")
					(size 0.63 0.63)
					(thickness 0.1)
				)
				(justify left bottom)
			)
		)
		(pad "1" smd rect
			(at -0.50215 0 180)
			(size 0.66818 0.67248)
			(layers "F.Cu" "F.Mask" "F.Paste")
			(net "GND")
			(solder_mask_margin 0)
			(solder_paste_margin 0)
		)
		(pad "2" smd rect
			(at 0.50215 0 180)
			(size 0.66818 0.67248)
			(layers "F.Cu" "F.Mask" "F.Paste")
			(net "NetD20_1")
			(solder_mask_margin 0)
			(solder_paste_margin 0)
		)
	)
	(footprint "Vault:FP-0603-L_1_6_0_2-W_0_8_0-MFG"
		(layer "F.Cu")
		(at 234.4261 107.8162 -90)
		(property "Reference" "C15"
			(at -3.1 -0.206655 270)
			(unlocked yes)
			(layer "F.SilkS")
			(effects
				(font
					(size 0.762 0.762)
					(thickness 0.2286)
				)
				(justify left bottom)
			)
		)
		(property "Value" "10uF_16V_0603"
			(at 0.993045 -12.1875 0)
			(unlocked yes)
			(layer "F.SilkS")
			(hide yes)
			(effects
				(font
					(size 0.762 0.762)
					(thickness 0.2286)
				)
				(justify left bottom)
			)
		)
		(sheetname "POWER")
		(sheetfile "POWER.kicad_sch")
		(duplicate_pad_numbers_are_jumpers no)
		(fp_line
			(start 0.9 0.825)
			(end -0.9 0.825)
			(stroke
				(width 0.2)
				(type solid)
			)
			(layer "F.SilkS")
		)
		(fp_line
			(start 0.9 -0.825)
			(end -0.9 -0.825)
			(stroke
				(width 0.2)
				(type solid)
			)
			(layer "F.SilkS")
		)
		(fp_line
			(start -1.15 0.6)
			(end -1.15 -0.6)
			(stroke
				(width 0.2)
				(type solid)
			)
			(layer "F.CrtYd")
		)
		(fp_line
			(start 1.15 0.6)
			(end -1.15 0.6)
			(stroke
				(width 0.2)
				(type solid)
			)
			(layer "F.CrtYd")
		)
		(fp_line
			(start 1.15 0.6)
			(end 1.15 -0.6)
			(stroke
				(width 0.2)
				(type solid)
			)
			(layer "F.CrtYd")
		)
		(fp_line
			(start 1.15 -0.6)
			(end -1.15 -0.6)
			(stroke
				(width 0.2)
				(type solid)
			)
			(layer "F.CrtYd")
		)
		(fp_line
			(start -1.15 0.6)
			(end -1.15 -0.6)
			(stroke
				(width 0.2)
				(type solid)
			)
			(layer "F.Fab")
		)
		(fp_line
			(start 1.15 0.6)
			(end -1.15 0.6)
			(stroke
				(width 0.2)
				(type solid)
			)
			(layer "F.Fab")
		)
		(fp_line
			(start 1.15 0.6)
			(end 1.15 -0.6)
			(stroke
				(width 0.2)
				(type solid)
			)
			(layer "F.Fab")
		)
		(fp_line
			(start 0 0.5)
			(end 0 -0.5)
			(stroke
				(width 0.1)
				(type solid)
			)
			(layer "F.Fab")
		)
		(fp_line
			(start 0.5 0)
			(end -0.5 0)
			(stroke
				(width 0.1)
				(type solid)
			)
			(layer "F.Fab")
		)
		(fp_line
			(start 1.15 -0.6)
			(end -1.15 -0.6)
			(stroke
				(width 0.2)
				(type solid)
			)
			(layer "F.Fab")
		)
		(fp_text user "${REFERENCE}"
			(at -0.00001 0.09602 270)
			(unlocked yes)
			(layer "F.Fab")
			(effects
				(font
					(face "Arial")
					(size 0.63 0.63)
					(thickness 0.1)
				)
				(justify left bottom)
			)
		)
		(pad "1" smd rect
			(at -0.7 0 270)
			(size 0.7 0.7)
			(layers "F.Cu" "F.Mask" "F.Paste")
			(net "+5.0V")
			(solder_mask_margin 0)
			(solder_paste_margin 0)
		)
		(pad "2" smd rect
			(at 0.7 0 270)
			(size 0.7 0.7)
			(layers "F.Cu" "F.Mask" "F.Paste")
			(net "GND")
			(solder_mask_margin 0)
			(solder_paste_margin 0)
		)
	)
	(footprint "Vault:RESC1005X40X25ML05T10"
		(layer "F.Cu")
		(at 211.3261 128.7162)
		(property "Reference" "R71"
			(at -0.171395 2.226931 0)
			(unlocked yes)
			(layer "F.SilkS")
			(effects
				(font
					(size 0.762 0.762)
					(thickness 0.2286)
				)
			)
		)
		(property "Value" "2.21_1%_0402"
			(at -2.884671 8.544305 270)
			(unlocked yes)
			(layer "F.SilkS")
			(hide yes)
			(effects
				(font
					(size 0.762 0.762)
					(thickness 0.2286)
				)
			)
		)
		(sheetname "POWER")
		(sheetfile "POWER.kicad_sch")
		(duplicate_pad_numbers_are_jumpers no)
		(pad "1" smd rect
			(at -0.475 0 90)
			(size 0.65 0.7)
			(layers "F.Cu" "F.Mask" "F.Paste")
			(net "NetC68_2")
		)
		(pad "2" smd rect
			(at 0.475 0 90)
			(size 0.65 0.7)
			(layers "F.Cu" "F.Mask" "F.Paste")
			(net "NetL2_1")
		)
	)
	(footprint "Resistors:RESC1608X50N"
		(layer "F.Cu")
		(at 91.9361 122.0786 180)
		(property "Reference" "R22"
			(at 1.06 0.906655 0)
			(unlocked yes)
			(layer "F.SilkS")
			(effects
				(font
					(size 0.762 0.762)
					(thickness 0.2286)
				)
				(justify left bottom)
			)
		)
		(property "Value" "ERJ-3EKF4701V"
			(at 0.4445 -3.636645 0)
			(unlocked yes)
			(layer "F.SilkS")
			(hide yes)
			(effects
				(font
					(size 0.762 0.762)
					(thickness 0.2286)
				)
				(justify left bottom)
			)
		)
		(sheetname "PCIe_JTAG")
		(sheetfile "PCIe_JTAG.kicad_sch")
		(duplicate_pad_numbers_are_jumpers no)
		(fp_line
			(start 0 -0.5)
			(end 0 0.5)
			(stroke
				(width 0.1524)
				(type solid)
			)
			(layer "F.SilkS")
		)
		(pad "1" smd rect
			(at -0.69 0 270)
			(size 1 0.72)
			(layers "F.Cu" "F.Mask" "F.Paste")
			(net "PCIE_PERST")
		)
		(pad "2" smd rect
			(at 0.69 0 270)
			(size 1 0.72)
			(layers "F.Cu" "F.Mask" "F.Paste")
			(net "+3.3V")
		)
	)
	(footprint "Vault:AMPH-901-143-6RFX_V"
		(layer "F.Cu")
		(at 60.9761 95.0786 180)
		(property "Reference" "AN1"
			(at -5.993345 2.7124 90)
			(unlocked yes)
			(layer "F.SilkS")
			(effects
				(font
					(size 0.762 0.762)
					(thickness 0.2286)
				)
				(justify left bottom)
			)
		)
		(property "Value" "RF2-49B-T-00-50-G-HDW"
			(at 4.6101 -12.120245 0)
			(unlocked yes)
			(layer "F.SilkS")
			(hide yes)
			(effects
				(font
					(size 0.762 0.762)
					(thickness 0.2286)
				)
				(justify left bottom)
			)
		)
		(sheetname "USER_IO")
		(sheetfile "USER_IO.kicad_sch")
		(duplicate_pad_numbers_are_jumpers no)
		(fp_line
			(start 3.5 -1.38)
			(end 3.5 1.38)
			(stroke
				(width 0.2)
				(type solid)
			)
			(layer "F.SilkS")
		)
		(fp_line
			(start 1.38 3.5)
			(end -1.38 3.5)
			(stroke
				(width 0.2)
				(type solid)
			)
			(layer "F.SilkS")
		)
		(fp_line
			(start 1.38 -3.5)
			(end -1.38 -3.5)
			(stroke
				(width 0.2)
				(type solid)
			)
			(layer "F.SilkS")
		)
		(fp_line
			(start -3.5 -1.38)
			(end -3.5 1.38)
			(stroke
				(width 0.2)
				(type solid)
			)
			(layer "F.SilkS")
		)
		(pad "1" thru_hole rect
			(at 0 0 180)
			(size 2 2)
			(drill 1.5)
			(layers "*.Cu" "*.Mask")
			(remove_unused_layers no)
			(net "NetAN1_1")
		)
		(pad "2" thru_hole circle
			(at -2.54 -2.54 180)
			(size 2.2 2.2)
			(drill 1.7)
			(layers "*.Cu" "*.Mask")
			(remove_unused_layers no)
			(net "GND")
			(thermal_bridge_angle 90)
		)
		(pad "3" thru_hole circle
			(at -2.54 2.54 180)
			(size 2.2 2.2)
			(drill 1.7)
			(layers "*.Cu" "*.Mask")
			(remove_unused_layers no)
			(net "GND")
			(thermal_bridge_angle 90)
		)
		(pad "4" thru_hole circle
			(at 2.54 2.54 180)
			(size 2.2 2.2)
			(drill 1.7)
			(layers "*.Cu" "*.Mask")
			(remove_unused_layers no)
			(net "GND")
			(thermal_bridge_angle 90)
		)
		(pad "5" thru_hole circle
			(at 2.54 -2.54 180)
			(size 2.2 2.2)
			(drill 1.7)
			(layers "*.Cu" "*.Mask")
			(remove_unused_layers no)
			(net "GND")
			(thermal_bridge_angle 90)
		)
	)
	(footprint "Vault:CAPC1608X87X45ML20T05"
		(layer "F.Cu")
		(at 123.3261 82.6162)
		(property "Reference" "C24"
			(at -1.1714 -1.673079 0)
			(unlocked yes)
			(layer "F.SilkS")
			(effects
				(font
					(size 0.762 0.762)
					(thickness 0.2286)
				)
			)
		)
		(property "Value" "0.1uF"
			(at 2.069025 2.630671 0)
			(unlocked yes)
			(layer "F.SilkS")
			(hide yes)
			(effects
				(font
					(size 0.762 0.762)
					(thickness 0.2286)
				)
			)
		)
		(sheetname "MAC")
		(sheetfile "MAC.kicad_sch")
		(duplicate_pad_numbers_are_jumpers no)
		(pad "1" smd rect
			(at -0.7 0 90)
			(size 1.1 1.05)
			(layers "F.Cu" "F.Mask" "F.Paste")
			(net "+3.3V")
		)
		(pad "2" smd rect
			(at 0.7 0 90)
			(size 1.1 1.05)
			(layers "F.Cu" "F.Mask" "F.Paste")
			(net "GND")
		)
	)
	(footprint "Vault:FP-0402-L_1_0_1-W_0_5_0_1-IPC_C"
		(layer "F.Cu")
		(at 236.3261 107.75066 -90)
		(property "Reference" "C18"
			(at -3.03446 0.393345 270)
			(unlocked yes)
			(layer "F.SilkS")
			(effects
				(font
					(size 0.762 0.762)
					(thickness 0.2286)
				)
				(justify left bottom)
			)
		)
		(property "Value" "0.1uF_25V_0402"
			(at 5.258585 -17.76611 0)
			(unlocked yes)
			(layer "F.SilkS")
			(hide yes)
			(effects
				(font
					(size 0.762 0.762)
					(thickness 0.2286)
				)
				(justify left bottom)
			)
		)
		(sheetname "POWER")
		(sheetfile "POWER.kicad_sch")
		(duplicate_pad_numbers_are_jumpers no)
		(fp_line
			(start 0.65607 0.7)
			(end -0.65606 0.7)
			(stroke
				(width 0.2)
				(type solid)
			)
			(layer "F.SilkS")
		)
		(fp_line
			(start 0.65607 -0.7)
			(end -0.65606 -0.7)
			(stroke
				(width 0.2)
				(type solid)
			)
			(layer "F.SilkS")
		)
		(fp_line
			(start -0.75606 0.4)
			(end -0.75606 -0.4)
			(stroke
				(width 0.2)
				(type solid)
			)
			(layer "F.CrtYd")
		)
		(fp_line
			(start 0.75607 0.4)
			(end -0.75606 0.4)
			(stroke
				(width 0.2)
				(type solid)
			)
			(layer "F.CrtYd")
		)
		(fp_line
			(start 0.75607 0.4)
			(end 0.75607 -0.4)
			(stroke
				(width 0.2)
				(type solid)
			)
			(layer "F.CrtYd")
		)
		(fp_line
			(start 0.75607 -0.4)
			(end -0.75606 -0.4)
			(stroke
				(width 0.2)
				(type solid)
			)
			(layer "F.CrtYd")
		)
		(fp_line
			(start 0 0.5)
			(end 0 -0.5)
			(stroke
				(width 0.1)
				(type solid)
			)
			(layer "F.Fab")
		)
		(fp_line
			(start -0.75606 0.4)
			(end -0.75606 -0.4)
			(stroke
				(width 0.2)
				(type solid)
			)
			(layer "F.Fab")
		)
		(fp_line
			(start 0.75607 0.4)
			(end -0.75606 0.4)
			(stroke
				(width 0.2)
				(type solid)
			)
			(layer "F.Fab")
		)
		(fp_line
			(start 0.75607 0.4)
			(end 0.75607 -0.4)
			(stroke
				(width 0.2)
				(type solid)
			)
			(layer "F.Fab")
		)
		(fp_line
			(start 0.5 0)
			(end -0.5 0)
			(stroke
				(width 0.1)
				(type solid)
			)
			(layer "F.Fab")
		)
		(fp_line
			(start 0.75607 -0.4)
			(end -0.75606 -0.4)
			(stroke
				(width 0.2)
				(type solid)
			)
			(layer "F.Fab")
		)
		(fp_text user "${REFERENCE}"
			(at -0.00001 0.09602 270)
			(unlocked yes)
			(layer "F.Fab")
			(effects
				(font
					(face "Arial")
					(size 0.63 0.63)
					(thickness 0.1)
				)
				(justify left bottom)
			)
		)
		(pad "1" smd rect
			(at -0.36553 0 270)
			(size 0.58106 0.51213)
			(layers "F.Cu" "F.Mask" "F.Paste")
			(net "+5.0V")
			(solder_mask_margin 0)
			(solder_paste_margin 0)
		)
		(pad "2" smd rect
			(at 0.36554 0 270)
			(size 0.58106 0.51213)
			(layers "F.Cu" "F.Mask" "F.Paste")
			(net "GND")
			(solder_mask_margin 0)
			(solder_paste_margin 0)
		)
	)
	(footprint "Vault:FP-LTST-C191TBKT-MFG"
		(layer "F.Cu")
		(at 75.1261 52.1162 90)
		(property "Reference" "D11"
			(at -7.75 0.343345 90)
			(unlocked yes)
			(layer "F.SilkS")
			(effects
				(font
					(size 0.762 0.762)
					(thickness 0.2286)
				)
				(justify left bottom)
			)
		)
		(property "Value" "BLUE"
			(at -3.128645 -1.4097 0)
			(unlocked yes)
			(layer "F.SilkS")
			(hide yes)
			(effects
				(font
					(size 0.762 0.762)
					(thickness 0.2286)
				)
				(justify left bottom)
			)
		)
		(sheetname "USER_IO_STATUS")
		(sheetfile "USER_IO_STATUS.kicad_sch")
		(duplicate_pad_numbers_are_jumpers no)
		(fp_line
			(start -0.85 -0.8)
			(end 0.85 -0.8)
			(stroke
				(width 0.2)
				(type solid)
			)
			(layer "F.SilkS")
		)
		(fp_line
			(start -0.85 0.8)
			(end 0.85 0.8)
			(stroke
				(width 0.2)
				(type solid)
			)
			(layer "F.SilkS")
		)
		(fp_circle
			(center -1.75 0)
			(end -1.625 0)
			(stroke
				(width 0.25)
				(type solid)
			)
			(fill no)
			(layer "F.SilkS")
		)
		(fp_line
			(start 1.25 -0.55)
			(end 1.25 0.55)
			(stroke
				(width 0.2)
				(type solid)
			)
			(layer "F.CrtYd")
		)
		(fp_line
			(start -1.25 -0.55)
			(end 1.25 -0.55)
			(stroke
				(width 0.2)
				(type solid)
			)
			(layer "F.CrtYd")
		)
		(fp_line
			(start -1.25 -0.55)
			(end -1.25 0.55)
			(stroke
				(width 0.2)
				(type solid)
			)
			(layer "F.CrtYd")
		)
		(fp_line
			(start -1.25 0.55)
			(end 1.25 0.55)
			(stroke
				(width 0.2)
				(type solid)
			)
			(layer "F.CrtYd")
		)
		(fp_line
			(start 1.25 -0.55)
			(end 1.25 0.55)
			(stroke
				(width 0.2)
				(type solid)
			)
			(layer "F.Fab")
		)
		(fp_line
			(start -1.25 -0.55)
			(end 1.25 -0.55)
			(stroke
				(width 0.2)
				(type solid)
			)
			(layer "F.Fab")
		)
		(fp_line
			(start -1.25 -0.55)
			(end -1.25 0.55)
			(stroke
				(width 0.2)
				(type solid)
			)
			(layer "F.Fab")
		)
		(fp_line
			(start 0 -0.5)
			(end 0 0.5)
			(stroke
				(width 0.1)
				(type solid)
			)
			(layer "F.Fab")
		)
		(fp_line
			(start -0.5 0)
			(end 0.5 0)
			(stroke
				(width 0.1)
				(type solid)
			)
			(layer "F.Fab")
		)
		(fp_line
			(start -1.25 0.55)
			(end 1.25 0.55)
			(stroke
				(width 0.2)
				(type solid)
			)
			(layer "F.Fab")
		)
		(pad "1" smd rect
			(at -0.75 0 90)
			(size 0.8 0.8)
			(layers "F.Cu" "F.Mask" "F.Paste")
			(net "NetD11_1")
			(solder_mask_margin 0)
			(solder_paste_margin 0)
		)
		(pad "2" smd rect
			(at 0.75 0 90)
			(size 0.8 0.8)
			(layers "F.Cu" "F.Mask" "F.Paste")
			(net "+3.3V")
			(solder_mask_margin 0)
			(solder_paste_margin 0)
		)
	)
	(footprint "Vault:FP-0402-L_1_0_0_05-W_0_5-IPC_A"
		(layer "F.Cu")
		(at 236.69996 102.15182 90)
		(property "Reference" "C17"
			(at 3.33562 -0.667205 270)
			(unlocked yes)
			(layer "F.SilkS")
			(effects
				(font
					(size 0.762 0.762)
					(thickness 0.2286)
				)
				(justify left bottom)
			)
		)
		(property "Value" "1uF_16V_0402"
			(at -6.793035 11.9755 0)
			(unlocked yes)
			(layer "F.SilkS")
			(hide yes)
			(effects
				(font
					(size 0.762 0.762)
					(thickness 0.2286)
				)
				(justify left bottom)
			)
		)
		(sheetname "POWER")
		(sheetfile "POWER.kicad_sch")
		(duplicate_pad_numbers_are_jumpers no)
		(fp_line
			(start -0.83623 -0.73623)
			(end 0.83624 -0.73623)
			(stroke
				(width 0.2)
				(type solid)
			)
			(layer "F.SilkS")
		)
		(fp_line
			(start -0.83623 0.73624)
			(end 0.83624 0.73624)
			(stroke
				(width 0.2)
				(type solid)
			)
			(layer "F.SilkS")
		)
		(fp_line
			(start 1.03624 -0.53623)
			(end 1.03624 0.53624)
			(stroke
				(width 0.2)
				(type solid)
			)
			(layer "F.CrtYd")
		)
		(fp_line
			(start -1.03623 -0.53623)
			(end 1.03624 -0.53623)
			(stroke
				(width 0.2)
				(type solid)
			)
			(layer "F.CrtYd")
		)
		(fp_line
			(start -1.03623 -0.53623)
			(end -1.03623 0.53624)
			(stroke
				(width 0.2)
				(type solid)
			)
			(layer "F.CrtYd")
		)
		(fp_line
			(start -1.03623 0.53624)
			(end 1.03624 0.53624)
			(stroke
				(width 0.2)
				(type solid)
			)
			(layer "F.CrtYd")
		)
		(fp_line
			(start 1.03624 -0.53623)
			(end 1.03624 0.53624)
			(stroke
				(width 0.2)
				(type solid)
			)
			(layer "F.Fab")
		)
		(fp_line
			(start -1.03623 -0.53623)
			(end 1.03624 -0.53623)
			(stroke
				(width 0.2)
				(type solid)
			)
			(layer "F.Fab")
		)
		(fp_line
			(start -1.03623 -0.53623)
			(end -1.03623 0.53624)
			(stroke
				(width 0.2)
				(type solid)
			)
			(layer "F.Fab")
		)
		(fp_line
			(start 0 -0.5)
			(end 0 0.5)
			(stroke
				(width 0.1)
				(type solid)
			)
			(layer "F.Fab")
		)
		(fp_line
			(start -0.5 0)
			(end 0.5 0)
			(stroke
				(width 0.1)
				(type solid)
			)
			(layer "F.Fab")
		)
		(fp_line
			(start -1.03623 0.53624)
			(end 1.03624 0.53624)
			(stroke
				(width 0.2)
				(type solid)
			)
			(layer "F.Fab")
		)
		(fp_text user "${REFERENCE}"
			(at -0.00001 0.09602 90)
			(unlocked yes)
			(layer "F.Fab")
			(effects
				(font
					(face "Arial")
					(size 0.63 0.63)
					(thickness 0.1)
				)
				(justify left bottom)
			)
		)
		(pad "1" smd rect
			(at -0.47856 0 90)
			(size 0.71535 0.67248)
			(layers "F.Cu" "F.Mask" "F.Paste")
			(net "+5.0V")
			(solder_mask_margin 0)
			(solder_paste_margin 0)
		)
		(pad "2" smd rect
			(at 0.47857 0 90)
			(size 0.71535 0.67248)
			(layers "F.Cu" "F.Mask" "F.Paste")
			(net "GND")
			(solder_mask_margin 0)
			(solder_paste_margin 0)
		)
	)
	(footprint "Vault:AMPH-901-143-6RFX_V"
		(layer "F.Cu")
		(at 60.9761 122.0782 180)
		(property "Reference" "AN3"
			(at -5.917345 2.516 90)
			(unlocked yes)
			(layer "F.SilkS")
			(effects
				(font
					(size 0.762 0.762)
					(thickness 0.2286)
				)
				(justify left bottom)
			)
		)
		(property "Value" "RF2-49B-T-00-50-G-HDW"
			(at 4.6101 -1.960245 0)
			(unlocked yes)
			(layer "F.SilkS")
			(hide yes)
			(effects
				(font
					(size 0.762 0.762)
					(thickness 0.2286)
				)
				(justify left bottom)
			)
		)
		(sheetname "USER_IO")
		(sheetfile "USER_IO.kicad_sch")
		(duplicate_pad_numbers_are_jumpers no)
		(fp_line
			(start 3.5 -1.38)
			(end 3.5 1.38)
			(stroke
				(width 0.2)
				(type solid)
			)
			(layer "F.SilkS")
		)
		(fp_line
			(start 1.38 3.5)
			(end -1.38 3.5)
			(stroke
				(width 0.2)
				(type solid)
			)
			(layer "F.SilkS")
		)
		(fp_line
			(start 1.38 -3.5)
			(end -1.38 -3.5)
			(stroke
				(width 0.2)
				(type solid)
			)
			(layer "F.SilkS")
		)
		(fp_line
			(start -3.5 -1.38)
			(end -3.5 1.38)
			(stroke
				(width 0.2)
				(type solid)
			)
			(layer "F.SilkS")
		)
		(pad "1" thru_hole rect
			(at 0 0 180)
			(size 2 2)
			(drill 1.5)
			(layers "*.Cu" "*.Mask")
			(remove_unused_layers no)
			(net "NetAN3_1")
		)
		(pad "2" thru_hole circle
			(at -2.54 -2.54 180)
			(size 2.2 2.2)
			(drill 1.7)
			(layers "*.Cu" "*.Mask")
			(remove_unused_layers no)
			(net "GND")
			(thermal_bridge_angle 90)
		)
		(pad "3" thru_hole circle
			(at -2.54 2.54 180)
			(size 2.2 2.2)
			(drill 1.7)
			(layers "*.Cu" "*.Mask")
			(remove_unused_layers no)
			(net "GND")
			(thermal_bridge_angle 90)
		)
		(pad "4" thru_hole circle
			(at 2.54 2.54 180)
			(size 2.2 2.2)
			(drill 1.7)
			(layers "*.Cu" "*.Mask")
			(remove_unused_layers no)
			(net "GND")
			(thermal_bridge_angle 90)
		)
		(pad "5" thru_hole circle
			(at 2.54 -2.54 180)
			(size 2.2 2.2)
			(drill 1.7)
			(layers "*.Cu" "*.Mask")
			(remove_unused_layers no)
			(net "GND")
			(thermal_bridge_angle 90)
		)
	)
	(footprint "Vault:FP-5TS1-IPC_C"
		(layer "F.Cu")
		(at 180.1261 87.0786 -90)
		(property "Reference" "U7"
			(at -2.735469 -0.228595 0)
			(unlocked yes)
			(layer "F.SilkS")
			(effects
				(font
					(size 0.762 0.762)
					(thickness 0.2286)
				)
			)
		)
		(property "Value" "AT24MAC402-STUM-T"
			(at 10.727395 3.189471 270)
			(unlocked yes)
			(layer "F.SilkS")
			(hide yes)
			(effects
				(font
					(size 0.762 0.762)
					(thickness 0.2286)
				)
			)
		)
		(sheetname "GPS_IMU_SENSORS")
		(sheetfile "GPS_IMU_SENSORS.kicad_sch")
		(duplicate_pad_numbers_are_jumpers no)
		(fp_line
			(start 0.17207 1.45)
			(end -0.17207 1.45)
			(stroke
				(width 0.2)
				(type solid)
			)
			(layer "F.SilkS")
		)
		(fp_line
			(start 0.8 0.30894)
			(end 0.8 -0.30893)
			(stroke
				(width 0.2)
				(type solid)
			)
			(layer "F.SilkS")
		)
		(fp_line
			(start 0.17207 -1.45)
			(end -0.17207 -1.45)
			(stroke
				(width 0.2)
				(type solid)
			)
			(layer "F.SilkS")
		)
		(fp_circle
			(center -2.21035 -0.95)
			(end -2.33535 -0.95)
			(stroke
				(width 0.25)
				(type solid)
			)
			(fill no)
			(layer "F.SilkS")
		)
		(fp_line
			(start -1.68536 1.55)
			(end -1.68536 -1.55)
			(stroke
				(width 0.2)
				(type solid)
			)
			(layer "F.CrtYd")
		)
		(fp_line
			(start 1.68536 1.55)
			(end -1.68536 1.55)
			(stroke
				(width 0.2)
				(type solid)
			)
			(layer "F.CrtYd")
		)
		(fp_line
			(start 1.68536 1.55)
			(end 1.68536 -1.55)
			(stroke
				(width 0.2)
				(type solid)
			)
			(layer "F.CrtYd")
		)
		(fp_line
			(start 1.68536 -1.55)
			(end -1.68536 -1.55)
			(stroke
				(width 0.2)
				(type solid)
			)
			(layer "F.CrtYd")
		)
		(fp_line
			(start -1.68536 1.55)
			(end -1.68536 -1.55)
			(stroke
				(width 0.2)
				(type solid)
			)
			(layer "F.Fab")
		)
		(fp_line
			(start 1.68536 1.55)
			(end -1.68536 1.55)
			(stroke
				(width 0.2)
				(type solid)
			)
			(layer "F.Fab")
		)
		(fp_line
			(start 1.68536 1.55)
			(end 1.68536 -1.55)
			(stroke
				(width 0.2)
				(type solid)
			)
			(layer "F.Fab")
		)
		(fp_line
			(start 0 0.5)
			(end 0 -0.5)
			(stroke
				(width 0.1)
				(type solid)
			)
			(layer "F.Fab")
		)
		(fp_line
			(start 0.5 0)
			(end -0.5 0)
			(stroke
				(width 0.1)
				(type solid)
			)
			(layer "F.Fab")
		)
		(fp_line
			(start 1.68536 -1.55)
			(end -1.68536 -1.55)
			(stroke
				(width 0.2)
				(type solid)
			)
			(layer "F.Fab")
		)
		(fp_text user "${REFERENCE}"
			(at 0 0.28425 270)
			(unlocked yes)
			(layer "F.Fab")
			(effects
				(font
					(face "Arial")
					(size 0.63 0.63)
					(thickness 0.1)
				)
				(justify left bottom)
			)
		)
		(pad "1" smd rect
			(at -1.06621 -0.95 270)
			(size 1.03828 0.53213)
			(layers "F.Cu" "F.Mask" "F.Paste")
			(net "SCL")
			(solder_mask_margin 0)
			(solder_paste_margin 0)
		)
		(pad "2" smd roundrect
			(at -1.06621 0 270)
			(size 1.03828 0.53213)
			(layers "F.Cu" "F.Mask" "F.Paste")
			(roundrect_rratio 0.5)
			(net "GND")
			(solder_mask_margin 0)
			(solder_paste_margin 0)
		)
		(pad "3" smd roundrect
			(at -1.06621 0.95 270)
			(size 1.03828 0.53213)
			(layers "F.Cu" "F.Mask" "F.Paste")
			(roundrect_rratio 0.5)
			(net "SDA")
			(solder_mask_margin 0)
			(solder_paste_margin 0)
		)
		(pad "4" smd roundrect
			(at 1.06621 0.95 270)
			(size 1.03828 0.53213)
			(layers "F.Cu" "F.Mask" "F.Paste")
			(roundrect_rratio 0.5)
			(net "+3.3V")
			(solder_mask_margin 0)
			(solder_paste_margin 0)
		)
		(pad "5" smd roundrect
			(at 1.06621 -0.95 270)
			(size 1.03828 0.53213)
			(layers "F.Cu" "F.Mask" "F.Paste")
			(roundrect_rratio 0.5)
			(net "EXT_EEPROM_WP")
			(solder_mask_margin 0)
			(solder_paste_margin 0)
		)
	)
	(footprint "Vault:FP-C3216-160-0_2-MFG"
		(layer "F.Cu")
		(at 234.7261 102.0162 90)
		(property "Reference" "C13"
			(at 4.6 -0.493345 270)
			(unlocked yes)
			(layer "F.SilkS")
			(effects
				(font
					(size 0.762 0.762)
					(thickness 0.2286)
				)
				(justify left bottom)
			)
		)
		(property "Value" "47uF_16V_1206"
			(at -9.997845 1.3401 0)
			(unlocked yes)
			(layer "F.SilkS")
			(hide yes)
			(effects
				(font
					(size 0.762 0.762)
					(thickness 0.2286)
				)
				(justify left bottom)
			)
		)
		(sheetname "POWER")
		(sheetfile "POWER.kicad_sch")
		(duplicate_pad_numbers_are_jumpers no)
		(fp_line
			(start -0.725 -0.9)
			(end 0.725 -0.9)
			(stroke
				(width 0.2)
				(type solid)
			)
			(layer "F.SilkS")
		)
		(fp_line
			(start -0.725 0.9)
			(end 0.725 0.9)
			(stroke
				(width 0.2)
				(type solid)
			)
			(layer "F.SilkS")
		)
		(fp_line
			(start 2.3 -1)
			(end 2.3 1)
			(stroke
				(width 0.2)
				(type solid)
			)
			(layer "F.CrtYd")
		)
		(fp_line
			(start -2.3 -1)
			(end 2.3 -1)
			(stroke
				(width 0.2)
				(type solid)
			)
			(layer "F.CrtYd")
		)
		(fp_line
			(start -2.3 -1)
			(end -2.3 1)
			(stroke
				(width 0.2)
				(type solid)
			)
			(layer "F.CrtYd")
		)
		(fp_line
			(start -2.3 1)
			(end 2.3 1)
			(stroke
				(width 0.2)
				(type solid)
			)
			(layer "F.CrtYd")
		)
		(fp_line
			(start 2.3 -1)
			(end 2.3 1)
			(stroke
				(width 0.2)
				(type solid)
			)
			(layer "F.Fab")
		)
		(fp_line
			(start -2.3 -1)
			(end 2.3 -1)
			(stroke
				(width 0.2)
				(type solid)
			)
			(layer "F.Fab")
		)
		(fp_line
			(start -2.3 -1)
			(end -2.3 1)
			(stroke
				(width 0.2)
				(type solid)
			)
			(layer "F.Fab")
		)
		(fp_line
			(start 0 -0.5)
			(end 0 0.5)
			(stroke
				(width 0.1)
				(type solid)
			)
			(layer "F.Fab")
		)
		(fp_line
			(start -0.5 0)
			(end 0.5 0)
			(stroke
				(width 0.1)
				(type solid)
			)
			(layer "F.Fab")
		)
		(fp_line
			(start -2.3 1)
			(end 2.3 1)
			(stroke
				(width 0.2)
				(type solid)
			)
			(layer "F.Fab")
		)
		(fp_text user "${REFERENCE}"
			(at -0.00001 0.09601 90)
			(unlocked yes)
			(layer "F.Fab")
			(effects
				(font
					(face "Arial")
					(size 0.63 0.63)
					(thickness 0.1)
				)
				(justify left bottom)
			)
		)
		(pad "1" smd rect
			(at -1.65 0 90)
			(size 1.1 1.35)
			(layers "F.Cu" "F.Mask" "F.Paste")
			(net "+5.0V")
			(solder_mask_margin 0)
			(solder_paste_margin 0)
		)
		(pad "2" smd rect
			(at 1.65 0 90)
			(size 1.1 1.35)
			(layers "F.Cu" "F.Mask" "F.Paste")
			(net "GND")
			(solder_mask_margin 0)
			(solder_paste_margin 0)
		)
	)
	(footprint "Vault:RESC1005X40X25NL05T05"
		(layer "F.Cu")
		(at 214.0261 76.7162 -90)
		(property "Reference" "R90"
			(at -2.2714 0.326931 270)
			(unlocked yes)
			(layer "F.SilkS")
			(effects
				(font
					(size 0.762 0.762)
					(thickness 0.2286)
				)
			)
		)
		(property "Value" "27_1%_0402"
			(at -2.732271 7.37632 180)
			(unlocked yes)
			(layer "F.SilkS")
			(hide yes)
			(effects
				(font
					(size 0.762 0.762)
					(thickness 0.2286)
				)
			)
		)
		(sheetname "USBUart_DipSelects")
		(sheetfile "USBUart_DipSelects.kicad_sch")
		(duplicate_pad_numbers_are_jumpers no)
		(pad "1" smd rect
			(at -0.45 0)
			(size 0.55 0.55)
			(layers "F.Cu" "F.Mask" "F.Paste")
			(net "FTDI_RX")
		)
		(pad "2" smd rect
			(at 0.45 0)
			(size 0.55 0.55)
			(layers "F.Cu" "F.Mask" "F.Paste")
			(net "NetR90_2")
		)
	)
	(footprint "Vault:RESC1005X40X25NL05T05"
		(layer "F.Cu")
		(at 232.7261 75.7162 90)
		(property "Reference" "R43"
			(at 0.3714 -4.826931 270)
			(unlocked yes)
			(layer "F.SilkS")
			(effects
				(font
					(size 0.762 0.762)
					(thickness 0.2286)
				)
			)
		)
		(property "Value" "27_1%_0402"
			(at -3.011631 6.10665 0)
			(unlocked yes)
			(layer "F.SilkS")
			(hide yes)
			(effects
				(font
					(size 0.762 0.762)
					(thickness 0.2286)
				)
			)
		)
		(sheetname "USBUart_DipSelects")
		(sheetfile "USBUart_DipSelects.kicad_sch")
		(duplicate_pad_numbers_are_jumpers no)
		(pad "1" smd rect
			(at -0.45 0 180)
			(size 0.55 0.55)
			(layers "F.Cu" "F.Mask" "F.Paste")
			(net "FTDI_USB_R_N")
		)
		(pad "2" smd rect
			(at 0.45 0 180)
			(size 0.55 0.55)
			(layers "F.Cu" "F.Mask" "F.Paste")
			(net "FTDI_USB_N")
		)
	)
	(footprint "Vault:RESC1005X40X25NL05T05"
		(layer "F.Cu")
		(at 222.5261 77.1162 180)
		(property "Reference" "R84"
			(at -0.2286 1.373079 0)
			(unlocked yes)
			(layer "F.SilkS")
			(effects
				(font
					(size 0.762 0.762)
					(thickness 0.2286)
				)
			)
		)
		(property "Value" "27_1%_0402"
			(at -2.732271 7.37632 90)
			(unlocked yes)
			(layer "F.SilkS")
			(hide yes)
			(effects
				(font
					(size 0.762 0.762)
					(thickness 0.2286)
				)
			)
		)
		(sheetname "USBUart_DipSelects")
		(sheetfile "USBUart_DipSelects.kicad_sch")
		(duplicate_pad_numbers_are_jumpers no)
		(pad "1" smd rect
			(at -0.45 0 270)
			(size 0.55 0.55)
			(layers "F.Cu" "F.Mask" "F.Paste")
			(net "GND")
		)
		(pad "2" smd rect
			(at 0.45 0 270)
			(size 0.55 0.55)
			(layers "F.Cu" "F.Mask" "F.Paste")
			(net "NetR84_2")
		)
	)
	(footprint "Vault:FP-DFN-12-IPC_B"
		(layer "F.Cu")
		(at 237.2261 68.6162 90)
		(property "Reference" "U20"
			(at -1.0286 2.573069 270)
			(unlocked yes)
			(layer "F.SilkS")
			(effects
				(font
					(size 0.762 0.762)
					(thickness 0.2286)
				)
			)
		)
		(property "Value" "FT234XD-R"
			(at 4.45556 3.392671 90)
			(unlocked yes)
			(layer "F.SilkS")
			(hide yes)
			(effects
				(font
					(size 0.762 0.762)
					(thickness 0.2286)
				)
			)
		)
		(sheetname "USBUart_DipSelects")
		(sheetfile "USBUart_DipSelects.kicad_sch")
		(duplicate_pad_numbers_are_jumpers no)
		(fp_line
			(start -1.5 -1.625)
			(end 1.5 -1.625)
			(stroke
				(width 0.2)
				(type solid)
			)
			(layer "F.SilkS")
		)
		(fp_line
			(start -1.5 1.625)
			(end 1.5 1.625)
			(stroke
				(width 0.2)
				(type solid)
			)
			(layer "F.SilkS")
		)
		(fp_circle
			(center -2.38536 -1.125)
			(end -2.26036 -1.125)
			(stroke
				(width 0.25)
				(type solid)
			)
			(fill no)
			(layer "F.SilkS")
		)
		(fp_rect
			(start -0.461505 0.911635)
			(end 0.461635 -0.911495)
			(stroke
				(width 0)
				(type default)
			)
			(fill yes)
			(layer "F.Paste")
		)
		(fp_line
			(start 2.08535 -1.75)
			(end 2.08535 1.75)
			(stroke
				(width 0.2)
				(type solid)
			)
			(layer "F.CrtYd")
		)
		(fp_line
			(start -2.08536 -1.75)
			(end 2.08535 -1.75)
			(stroke
				(width 0.2)
				(type solid)
			)
			(layer "F.CrtYd")
		)
		(fp_line
			(start -2.08536 -1.75)
			(end -2.08536 1.75)
			(stroke
				(width 0.2)
				(type solid)
			)
			(layer "F.CrtYd")
		)
		(fp_line
			(start -2.08536 1.75)
			(end 2.08535 1.75)
			(stroke
				(width 0.2)
				(type solid)
			)
			(layer "F.CrtYd")
		)
		(fp_line
			(start 2.08535 -1.75)
			(end 2.08535 1.75)
			(stroke
				(width 0.2)
				(type solid)
			)
			(layer "F.Fab")
		)
		(fp_line
			(start -2.08536 -1.75)
			(end 2.08535 -1.75)
			(stroke
				(width 0.2)
				(type solid)
			)
			(layer "F.Fab")
		)
		(fp_line
			(start -2.08536 -1.75)
			(end -2.08536 1.75)
			(stroke
				(width 0.2)
				(type solid)
			)
			(layer "F.Fab")
		)
		(fp_line
			(start 0 -0.5)
			(end 0 0.5)
			(stroke
				(width 0.1)
				(type solid)
			)
			(layer "F.Fab")
		)
		(fp_line
			(start -0.5 0)
			(end 0.5 0)
			(stroke
				(width 0.1)
				(type solid)
			)
			(layer "F.Fab")
		)
		(fp_line
			(start -2.08536 1.75)
			(end 2.08535 1.75)
			(stroke
				(width 0.2)
				(type solid)
			)
			(layer "F.Fab")
		)
		(fp_text user "${REFERENCE}"
			(at 0 0.28425 90)
			(unlocked yes)
			(layer "F.Fab")
			(effects
				(font
					(face "Arial")
					(size 0.63 0.63)
					(thickness 0.1)
				)
				(justify left bottom)
			)
		)
		(pad "1" smd rect
			(at -1.4155 -1.125 90)
			(size 0.83971 0.22247)
			(layers "F.Cu" "F.Mask" "F.Paste")
			(net "FTDI_USB_N")
			(solder_mask_margin 0)
			(solder_paste_margin 0)
		)
		(pad "2" smd roundrect
			(at -1.4155 -0.675 90)
			(size 0.83971 0.22247)
			(layers "F.Cu" "F.Mask" "F.Paste")
			(roundrect_rratio 0.5)
			(net "NetC91_1")
			(solder_mask_margin 0)
			(solder_paste_margin 0)
		)
		(pad "3" smd roundrect
			(at -1.4155 -0.225 90)
			(size 0.83971 0.22247)
			(layers "F.Cu" "F.Mask" "F.Paste")
			(roundrect_rratio 0.5)
			(net "NetC92_1")
			(solder_mask_margin 0)
			(solder_paste_margin 0)
		)
		(pad "4" smd roundrect
			(at -1.4155 0.225 90)
			(size 0.83971 0.22247)
			(layers "F.Cu" "F.Mask" "F.Paste")
			(roundrect_rratio 0.5)
			(net "FTDI_VBUS")
			(solder_mask_margin 0)
			(solder_paste_margin 0)
		)
		(pad "5" smd roundrect
			(at -1.4155 0.675 90)
			(size 0.83971 0.22247)
			(layers "F.Cu" "F.Mask" "F.Paste")
			(roundrect_rratio 0.5)
			(net "GND")
			(solder_mask_margin 0)
			(solder_paste_margin 0)
		)
		(pad "6" smd roundrect
			(at -1.4155 1.125 90)
			(size 0.83971 0.22247)
			(layers "F.Cu" "F.Mask" "F.Paste")
			(roundrect_rratio 0.5)
			(solder_mask_margin 0)
			(solder_paste_margin 0)
		)
		(pad "7" smd roundrect
			(at 1.4155 1.125 90)
			(size 0.83971 0.22247)
			(layers "F.Cu" "F.Mask" "F.Paste")
			(roundrect_rratio 0.5)
			(net "NetR13_1")
			(solder_mask_margin 0)
			(solder_paste_margin 0)
		)
		(pad "8" smd roundrect
			(at 1.4155 0.675 90)
			(size 0.83971 0.22247)
			(layers "F.Cu" "F.Mask" "F.Paste")
			(roundrect_rratio 0.5)
			(solder_mask_margin 0)
			(solder_paste_margin 0)
		)
		(pad "9" smd roundrect
			(at 1.4155 0.225 90)
			(size 0.83971 0.22247)
			(layers "F.Cu" "F.Mask" "F.Paste")
			(roundrect_rratio 0.5)
			(net "NetC92_1")
			(solder_mask_margin 0)
			(solder_paste_margin 0)
		)
		(pad "10" smd roundrect
			(at 1.4155 -0.225 90)
			(size 0.83971 0.22247)
			(layers "F.Cu" "F.Mask" "F.Paste")
			(roundrect_rratio 0.5)
			(net "NetR42_1")
			(solder_mask_margin 0)
			(solder_paste_margin 0)
		)
		(pad "11" smd roundrect
			(at 1.4155 -0.675 90)
			(size 0.83971 0.22247)
			(layers "F.Cu" "F.Mask" "F.Paste")
			(roundrect_rratio 0.5)
			(solder_mask_margin 0)
			(solder_paste_margin 0)
		)
		(pad "12" smd roundrect
			(at 1.4155 -1.125 90)
			(size 0.83971 0.22247)
			(layers "F.Cu" "F.Mask" "F.Paste")
			(roundrect_rratio 0.5)
			(net "FTDI_USB_P")
			(solder_mask_margin 0)
			(solder_paste_margin 0)
		)
		(pad "13" smd rect
			(at 0 0 90)
			(size 1.65 2.55)
			(layers "F.Cu" "F.Mask" "F.Paste")
			(net "GND")
			(solder_mask_margin 0)
			(solder_paste_margin -1000)
		)
	)
	(footprint "Vault:RESC1005X40X25LL05T05"
		(layer "F.Cu")
		(at 183.6261 89.3162)
		(property "Reference" "R50"
			(at 0.2286 1.126931 0)
			(unlocked yes)
			(layer "F.SilkS")
			(effects
				(font
					(size 0.762 0.762)
					(thickness 0.2286)
				)
			)
		)
		(property "Value" "4.7K_0402"
			(at -3.024391 2.374045 270)
			(unlocked yes)
			(layer "F.SilkS")
			(hide yes)
			(effects
				(font
					(size 0.762 0.762)
					(thickness 0.2286)
				)
			)
		)
		(sheetname "GPS_IMU_SENSORS")
		(sheetfile "GPS_IMU_SENSORS.kicad_sch")
		(duplicate_pad_numbers_are_jumpers no)
		(pad "1" smd rect
			(at -0.4 0 90)
			(size 0.45 0.45)
			(layers "F.Cu" "F.Mask" "F.Paste")
			(net "+3.3V")
		)
		(pad "2" smd rect
			(at 0.4 0 90)
			(size 0.45 0.45)
			(layers "F.Cu" "F.Mask" "F.Paste")
			(net "BNO_INT")
		)
	)
	(footprint "Vault:TECO-1909763-1_V"
		(layer "F.Cu")
		(at 74.3761 135.6162 -90)
		(property "Reference" "J4"
			(at -2.723079 1.021395 0)
			(unlocked yes)
			(layer "F.SilkS")
			(effects
				(font
					(size 0.762 0.762)
					(thickness 0.2286)
				)
			)
		)
		(property "Value" "1909763-1"
			(at 4.582685 3.722871 270)
			(unlocked yes)
			(layer "F.SilkS")
			(hide yes)
			(effects
				(font
					(size 0.762 0.762)
					(thickness 0.2286)
				)
			)
		)
		(sheetname "USER_IO")
		(sheetfile "USER_IO.kicad_sch")
		(duplicate_pad_numbers_are_jumpers no)
		(fp_line
			(start 0.55 -1.3)
			(end -0.55 -1.3)
			(stroke
				(width 0.2)
				(type solid)
			)
			(layer "F.SilkS")
		)
		(fp_circle
			(center -1.778 1.65)
			(end -1.903 1.65)
			(stroke
				(width 0.25)
				(type solid)
			)
			(fill no)
			(layer "F.SilkS")
		)
		(pad "1" smd rect
			(at -1.475 0 270)
			(size 1.05 2.2)
			(layers "F.Cu" "F.Mask" "F.Paste")
			(net "GND")
		)
		(pad "2" smd rect
			(at 0 1.525 270)
			(size 1 1.05)
			(layers "F.Cu" "F.Mask" "F.Paste")
			(net "NetAN4_1")
		)
		(pad "3" smd rect
			(at 1.475 0 270)
			(size 1.05 2.2)
			(layers "F.Cu" "F.Mask" "F.Paste")
			(net "GND")
		)
	)
	(footprint "Vault:FP-MK212BG-MFG"
		(layer "F.Cu")
		(at 85.8761 79.0786 -90)
		(property "Reference" "C60"
			(at 1.5 -4.593345 90)
			(unlocked yes)
			(layer "F.SilkS")
			(effects
				(font
					(size 0.762 0.762)
					(thickness 0.2286)
				)
				(justify left bottom)
			)
		)
		(property "Value" "10uF"
			(at 3.433445 1.5875 0)
			(unlocked yes)
			(layer "F.SilkS")
			(hide yes)
			(effects
				(font
					(size 0.762 0.762)
					(thickness 0.2286)
				)
				(justify left bottom)
			)
		)
		(sheetname "GPS_IMU_SENSORS")
		(sheetfile "GPS_IMU_SENSORS.kicad_sch")
		(duplicate_pad_numbers_are_jumpers no)
		(fp_line
			(start 0.125 0.725)
			(end -0.125 0.725)
			(stroke
				(width 0.2)
				(type solid)
			)
			(layer "F.SilkS")
		)
		(fp_line
			(start 0.125 -0.725)
			(end -0.125 -0.725)
			(stroke
				(width 0.2)
				(type solid)
			)
			(layer "F.SilkS")
		)
		(fp_line
			(start -1.6 0.825)
			(end -1.6 -0.825)
			(stroke
				(width 0.2)
				(type solid)
			)
			(layer "F.CrtYd")
		)
		(fp_line
			(start 1.6 0.825)
			(end -1.6 0.825)
			(stroke
				(width 0.2)
				(type solid)
			)
			(layer "F.CrtYd")
		)
		(fp_line
			(start 1.6 0.825)
			(end 1.6 -0.825)
			(stroke
				(width 0.2)
				(type solid)
			)
			(layer "F.CrtYd")
		)
		(fp_line
			(start 1.6 -0.825)
			(end -1.6 -0.825)
			(stroke
				(width 0.2)
				(type solid)
			)
			(layer "F.CrtYd")
		)
		(fp_line
			(start -1.6 0.825)
			(end -1.6 -0.825)
			(stroke
				(width 0.2)
				(type solid)
			)
			(layer "F.Fab")
		)
		(fp_line
			(start 1.6 0.825)
			(end -1.6 0.825)
			(stroke
				(width 0.2)
				(type solid)
			)
			(layer "F.Fab")
		)
		(fp_line
			(start 1.6 0.825)
			(end 1.6 -0.825)
			(stroke
				(width 0.2)
				(type solid)
			)
			(layer "F.Fab")
		)
		(fp_line
			(start 0 0.5)
			(end 0 -0.5)
			(stroke
				(width 0.1)
				(type solid)
			)
			(layer "F.Fab")
		)
		(fp_line
			(start 0.5 0)
			(end -0.5 0)
			(stroke
				(width 0.1)
				(type solid)
			)
			(layer "F.Fab")
		)
		(fp_line
			(start 1.6 -0.825)
			(end -1.6 -0.825)
			(stroke
				(width 0.2)
				(type solid)
			)
			(layer "F.Fab")
		)
		(fp_text user "${REFERENCE}"
			(at -0.00001 0.09601 270)
			(unlocked yes)
			(layer "F.Fab")
			(effects
				(font
					(face "Arial")
					(size 0.63 0.63)
					(thickness 0.1)
				)
				(justify left bottom)
			)
		)
		(pad "1" smd rect
			(at -1 0 270)
			(size 1 1.25)
			(layers "F.Cu" "F.Mask" "F.Paste")
			(net "+5.0V")
			(solder_mask_margin 0)
			(solder_paste_margin 0)
		)
		(pad "2" smd rect
			(at 1 0 270)
			(size 1 1.25)
			(layers "F.Cu" "F.Mask" "F.Paste")
			(net "GND")
			(solder_mask_margin 0)
			(solder_paste_margin 0)
		)
	)
	(footprint "Vault:FP-SML-LX0603IW-TR-MFG"
		(layer "F.Cu")
		(at 234.0261 137.2162 180)
		(property "Reference" "D4"
			(at 1.3 -2.093345 0)
			(unlocked yes)
			(layer "F.SilkS")
			(effects
				(font
					(size 0.762 0.762)
					(thickness 0.2286)
				)
				(justify left bottom)
			)
		)
		(property "Value" "SML-LX0603IW-TR"
			(at 18.2973 -9.341045 0)
			(unlocked yes)
			(layer "F.SilkS")
			(hide yes)
			(effects
				(font
					(size 0.762 0.762)
					(thickness 0.2286)
				)
				(justify left bottom)
			)
		)
		(sheetname "POWER")
		(sheetfile "POWER.kicad_sch")
		(duplicate_pad_numbers_are_jumpers no)
		(fp_line
			(start 0.8 -0.75)
			(end -0.8 -0.75)
			(stroke
				(width 0.2)
				(type solid)
			)
			(layer "F.SilkS")
		)
		(fp_line
			(start 0.77933 0.73)
			(end -0.82067 0.73)
			(stroke
				(width 0.2)
				(type solid)
			)
			(layer "F.SilkS")
		)
		(fp_circle
			(center -1.725 0)
			(end -1.725 0.125)
			(stroke
				(width 0.25)
				(type solid)
			)
			(fill no)
			(layer "F.SilkS")
		)
		(fp_line
			(start 1.25 0.625)
			(end -1.25 0.625)
			(stroke
				(width 0.2)
				(type solid)
			)
			(layer "F.CrtYd")
		)
		(fp_line
			(start 1.25 -0.625)
			(end 1.25 0.625)
			(stroke
				(width 0.2)
				(type solid)
			)
			(layer "F.CrtYd")
		)
		(fp_line
			(start 1.25 -0.625)
			(end -1.25 -0.625)
			(stroke
				(width 0.2)
				(type solid)
			)
			(layer "F.CrtYd")
		)
		(fp_line
			(start -1.25 -0.625)
			(end -1.25 0.625)
			(stroke
				(width 0.2)
				(type solid)
			)
			(layer "F.CrtYd")
		)
		(fp_line
			(start 1.25 0.625)
			(end -1.25 0.625)
			(stroke
				(width 0.2)
				(type solid)
			)
			(layer "F.Fab")
		)
		(fp_line
			(start 1.25 -0.625)
			(end 1.25 0.625)
			(stroke
				(width 0.2)
				(type solid)
			)
			(layer "F.Fab")
		)
		(fp_line
			(start 1.25 -0.625)
			(end -1.25 -0.625)
			(stroke
				(width 0.2)
				(type solid)
			)
			(layer "F.Fab")
		)
		(fp_line
			(start 0.5 0)
			(end -0.5 0)
			(stroke
				(width 0.1)
				(type solid)
			)
			(layer "F.Fab")
		)
		(fp_line
			(start 0 -0.5)
			(end 0 0.5)
			(stroke
				(width 0.1)
				(type solid)
			)
			(layer "F.Fab")
		)
		(fp_line
			(start -1.25 -0.625)
			(end -1.25 0.625)
			(stroke
				(width 0.2)
				(type solid)
			)
			(layer "F.Fab")
		)
		(fp_text user "${REFERENCE}"
			(at 0 0.29534 180)
			(unlocked yes)
			(layer "F.Fab")
			(effects
				(font
					(face "Arial")
					(size 0.63 0.63)
					(thickness 0.1)
				)
				(justify left bottom)
			)
		)
		(pad "1" smd rect
			(at -0.75 0 180)
			(size 0.8 0.8)
			(layers "F.Cu" "F.Mask" "F.Paste")
			(net "NetD4_1")
			(solder_mask_margin 0)
			(solder_paste_margin 0)
		)
		(pad "2" smd rect
			(at 0.75 0 180)
			(size 0.8 0.8)
			(layers "F.Cu" "F.Mask" "F.Paste")
			(net "+5.0V")
			(solder_mask_margin 0)
			(solder_paste_margin 0)
		)
	)
	(footprint "Vault:RESC1005X40X25LL05T05"
		(layer "F.Cu")
		(at 202.9261 123.9162)
		(property "Reference" "R68"
			(at -3.1714 4.126921 0)
			(unlocked yes)
			(layer "F.SilkS")
			(effects
				(font
					(size 0.762 0.762)
					(thickness 0.2286)
				)
			)
		)
		(property "Value" "4.7K_0402"
			(at -2.389351 6.538405 270)
			(unlocked yes)
			(layer "F.SilkS")
			(hide yes)
			(effects
				(font
					(size 0.762 0.762)
					(thickness 0.2286)
				)
			)
		)
		(sheetname "POWER")
		(sheetfile "POWER.kicad_sch")
		(duplicate_pad_numbers_are_jumpers no)
		(pad "1" smd rect
			(at -0.4 0 90)
			(size 0.45 0.45)
			(layers "F.Cu" "F.Mask" "F.Paste")
			(net "+3.3V")
		)
		(pad "2" smd rect
			(at 0.4 0 90)
			(size 0.45 0.45)
			(layers "F.Cu" "F.Mask" "F.Paste")
			(net "NetR68_2")
		)
	)
	(footprint "Capacitors:CAPC1005X06N"
		(layer "B.Cu")
		(at 116.5781 151.7886 90)
		(property "Reference" "C45"
			(at 2.835 -0.445345 270)
			(unlocked yes)
			(layer "B.SilkS")
			(effects
				(font
					(size 0.762 0.762)
					(thickness 0.2286)
				)
				(justify left bottom mirror)
			)
		)
		(property "Value" "CAP_0402_0.1UF_50V"
			(at -3.382645 0.2921 0)
			(unlocked yes)
			(layer "B.SilkS")
			(hide yes)
			(effects
				(font
					(size 0.762 0.762)
					(thickness 0.2286)
				)
				(justify left bottom mirror)
			)
		)
		(sheetname "PCIe_JTAG")
		(sheetfile "PCIe_JTAG.kicad_sch")
		(duplicate_pad_numbers_are_jumpers no)
		(pad "1" smd rect
			(at -0.43 0)
			(size 0.64 0.68)
			(layers "B.Cu" "B.Mask" "B.Paste")
			(net "NetC45_1")
		)
		(pad "2" smd rect
			(at 0.43 0)
			(size 0.64 0.68)
			(layers "B.Cu" "B.Mask" "B.Paste")
			(net "PCIE_CLK_N")
		)
	)
	(footprint "Capacitors:CAPC1005X06N"
		(layer "B.Cu")
		(at 131.5641 151.7886 90)
		(property "Reference" "C52"
			(at 2.41349 -0.613855 270)
			(unlocked yes)
			(layer "B.SilkS")
			(effects
				(font
					(size 0.762 0.762)
					(thickness 0.2286)
				)
				(justify left bottom mirror)
			)
		)
		(property "Value" "CAP_0402_0.1UF_50V"
			(at -3.382645 0.2921 0)
			(unlocked yes)
			(layer "B.SilkS")
			(hide yes)
			(effects
				(font
					(size 0.762 0.762)
					(thickness 0.2286)
				)
				(justify left bottom mirror)
			)
		)
		(sheetname "PCIe_JTAG")
		(sheetfile "PCIe_JTAG.kicad_sch")
		(duplicate_pad_numbers_are_jumpers no)
		(pad "1" smd rect
			(at -0.43 0)
			(size 0.64 0.68)
			(layers "B.Cu" "B.Mask" "B.Paste")
			(net "NetC52_1")
		)
		(pad "2" smd rect
			(at 0.43 0)
			(size 0.64 0.68)
			(layers "B.Cu" "B.Mask" "B.Paste")
			(net "PCIE_TX3_P")
		)
	)
	(footprint "Capacitors:CAPC1005X06N"
		(layer "B.Cu")
		(at 128.3891 151.7886 90)
		(property "Reference" "C51"
			(at 2.41349 0.148145 270)
			(unlocked yes)
			(layer "B.SilkS")
			(effects
				(font
					(size 0.762 0.762)
					(thickness 0.2286)
				)
				(justify left bottom mirror)
			)
		)
		(property "Value" "CAP_0402_0.1UF_50V"
			(at -3.382645 0.2921 0)
			(unlocked yes)
			(layer "B.SilkS")
			(hide yes)
			(effects
				(font
					(size 0.762 0.762)
					(thickness 0.2286)
				)
				(justify left bottom mirror)
			)
		)
		(sheetname "PCIe_JTAG")
		(sheetfile "PCIe_JTAG.kicad_sch")
		(duplicate_pad_numbers_are_jumpers no)
		(pad "1" smd rect
			(at -0.43 0)
			(size 0.64 0.68)
			(layers "B.Cu" "B.Mask" "B.Paste")
			(net "NetC51_1")
		)
		(pad "2" smd rect
			(at 0.43 0)
			(size 0.64 0.68)
			(layers "B.Cu" "B.Mask" "B.Paste")
			(net "PCIE_TX2_N")
		)
	)
	(footprint "Capacitors:CAPC1005X06N"
		(layer "B.Cu")
		(at 132.5801 151.7886 90)
		(property "Reference" "C53"
			(at 2.41349 0.046545 270)
			(unlocked yes)
			(layer "B.SilkS")
			(effects
				(font
					(size 0.762 0.762)
					(thickness 0.2286)
				)
				(justify left bottom mirror)
			)
		)
		(property "Value" "CAP_0402_0.1UF_50V"
			(at -3.382645 0.2921 0)
			(unlocked yes)
			(layer "B.SilkS")
			(hide yes)
			(effects
				(font
					(size 0.762 0.762)
					(thickness 0.2286)
				)
				(justify left bottom mirror)
			)
		)
		(sheetname "PCIe_JTAG")
		(sheetfile "PCIe_JTAG.kicad_sch")
		(duplicate_pad_numbers_are_jumpers no)
		(pad "1" smd rect
			(at -0.43 0)
			(size 0.64 0.68)
			(layers "B.Cu" "B.Mask" "B.Paste")
			(net "NetC53_1")
		)
		(pad "2" smd rect
			(at 0.43 0)
			(size 0.64 0.68)
			(layers "B.Cu" "B.Mask" "B.Paste")
			(net "PCIE_TX3_N")
		)
	)
	(footprint "Capacitors:CAPC1005X06N"
		(layer "B.Cu")
		(at 124.5791 151.7886 90)
		(property "Reference" "C49"
			(at 2.41349 -0.156655 270)
			(unlocked yes)
			(layer "B.SilkS")
			(effects
				(font
					(size 0.762 0.762)
					(thickness 0.2286)
				)
				(justify left bottom mirror)
			)
		)
		(property "Value" "CAP_0402_0.1UF_50V"
			(at -3.382645 0.2921 0)
			(unlocked yes)
			(layer "B.SilkS")
			(hide yes)
			(effects
				(font
					(size 0.762 0.762)
					(thickness 0.2286)
				)
				(justify left bottom mirror)
			)
		)
		(sheetname "PCIe_JTAG")
		(sheetfile "PCIe_JTAG.kicad_sch")
		(duplicate_pad_numbers_are_jumpers no)
		(pad "1" smd rect
			(at -0.43 0)
			(size 0.64 0.68)
			(layers "B.Cu" "B.Mask" "B.Paste")
			(net "NetC49_1")
		)
		(pad "2" smd rect
			(at 0.43 0)
			(size 0.64 0.68)
			(layers "B.Cu" "B.Mask" "B.Paste")
			(net "PCIE_TX1_N")
		)
	)
	(footprint "Capacitors:CAPC1005X06N"
		(layer "B.Cu")
		(at 127.5001 151.7886 90)
		(property "Reference" "C50"
			(at 2.41349 -0.766255 270)
			(unlocked yes)
			(layer "B.SilkS")
			(effects
				(font
					(size 0.762 0.762)
					(thickness 0.2286)
				)
				(justify left bottom mirror)
			)
		)
		(property "Value" "CAP_0402_0.1UF_50V"
			(at -3.382645 0.2921 0)
			(unlocked yes)
			(layer "B.SilkS")
			(hide yes)
			(effects
				(font
					(size 0.762 0.762)
					(thickness 0.2286)
				)
				(justify left bottom mirror)
			)
		)
		(sheetname "PCIe_JTAG")
		(sheetfile "PCIe_JTAG.kicad_sch")
		(duplicate_pad_numbers_are_jumpers no)
		(pad "1" smd rect
			(at -0.43 0)
			(size 0.64 0.68)
			(layers "B.Cu" "B.Mask" "B.Paste")
			(net "NetC50_1")
		)
		(pad "2" smd rect
			(at 0.43 0)
			(size 0.64 0.68)
			(layers "B.Cu" "B.Mask" "B.Paste")
			(net "PCIE_TX2_P")
		)
	)
	(footprint "Capacitors:CAPC1005X06N"
		(layer "B.Cu")
		(at 119.6769 151.7886 90)
		(property "Reference" "C47"
			(at 2.41349 0.097345 270)
			(unlocked yes)
			(layer "B.SilkS")
			(effects
				(font
					(size 0.762 0.762)
					(thickness 0.2286)
				)
				(justify left bottom mirror)
			)
		)
		(property "Value" "CAP_0402_0.1UF_50V"
			(at -3.382645 0.2921 0)
			(unlocked yes)
			(layer "B.SilkS")
			(hide yes)
			(effects
				(font
					(size 0.762 0.762)
					(thickness 0.2286)
				)
				(justify left bottom mirror)
			)
		)
		(sheetname "PCIe_JTAG")
		(sheetfile "PCIe_JTAG.kicad_sch")
		(duplicate_pad_numbers_are_jumpers no)
		(pad "1" smd rect
			(at -0.43 0)
			(size 0.64 0.68)
			(layers "B.Cu" "B.Mask" "B.Paste")
			(net "NetC47_1")
		)
		(pad "2" smd rect
			(at 0.43 0)
			(size 0.64 0.68)
			(layers "B.Cu" "B.Mask" "B.Paste")
			(net "PCIE_TX0_N")
		)
	)
	(footprint "Capacitors:CAPC1005X06N"
		(layer "B.Cu")
		(at 115.5621 151.7886 90)
		(property "Reference" "C44"
			(at 2.885 -1.204345 270)
			(unlocked yes)
			(layer "B.SilkS")
			(effects
				(font
					(size 0.762 0.762)
					(thickness 0.2286)
				)
				(justify left bottom mirror)
			)
		)
		(property "Value" "CAP_0402_0.1UF_50V"
			(at -3.382645 0.2921 0)
			(unlocked yes)
			(layer "B.SilkS")
			(hide yes)
			(effects
				(font
					(size 0.762 0.762)
					(thickness 0.2286)
				)
				(justify left bottom mirror)
			)
		)
		(sheetname "PCIe_JTAG")
		(sheetfile "PCIe_JTAG.kicad_sch")
		(duplicate_pad_numbers_are_jumpers no)
		(pad "1" smd rect
			(at -0.43 0)
			(size 0.64 0.68)
			(layers "B.Cu" "B.Mask" "B.Paste")
			(net "NetC44_1")
		)
		(pad "2" smd rect
			(at 0.43 0)
			(size 0.64 0.68)
			(layers "B.Cu" "B.Mask" "B.Paste")
			(net "PCIE_CLK_P")
		)
	)
	(footprint "Capacitors:CAPC1005X06N"
		(layer "B.Cu")
		(at 118.5847 151.7886 90)
		(property "Reference" "C46"
			(at 2.41349 -0.563055 270)
			(unlocked yes)
			(layer "B.SilkS")
			(effects
				(font
					(size 0.762 0.762)
					(thickness 0.2286)
				)
				(justify left bottom mirror)
			)
		)
		(property "Value" "CAP_0402_0.1UF_50V"
			(at -3.382645 0.2921 0)
			(unlocked yes)
			(layer "B.SilkS")
			(hide yes)
			(effects
				(font
					(size 0.762 0.762)
					(thickness 0.2286)
				)
				(justify left bottom mirror)
			)
		)
		(sheetname "PCIe_JTAG")
		(sheetfile "PCIe_JTAG.kicad_sch")
		(duplicate_pad_numbers_are_jumpers no)
		(pad "1" smd rect
			(at -0.43 0)
			(size 0.64 0.68)
			(layers "B.Cu" "B.Mask" "B.Paste")
			(net "NetC46_1")
		)
		(pad "2" smd rect
			(at 0.43 0)
			(size 0.64 0.68)
			(layers "B.Cu" "B.Mask" "B.Paste")
			(net "PCIE_TX0_P")
		)
	)
	(footprint "Capacitors:CAPC1005X06N"
		(layer "B.Cu")
		(at 123.5631 151.7886 90)
		(property "Reference" "C48"
			(at 2.41349 -0.867855 270)
			(unlocked yes)
			(layer "B.SilkS")
			(effects
				(font
					(size 0.762 0.762)
					(thickness 0.2286)
				)
				(justify left bottom mirror)
			)
		)
		(property "Value" "CAP_0402_0.1UF_50V"
			(at -3.382645 0.2921 0)
			(unlocked yes)
			(layer "B.SilkS")
			(hide yes)
			(effects
				(font
					(size 0.762 0.762)
					(thickness 0.2286)
				)
				(justify left bottom mirror)
			)
		)
		(sheetname "PCIe_JTAG")
		(sheetfile "PCIe_JTAG.kicad_sch")
		(duplicate_pad_numbers_are_jumpers no)
		(pad "1" smd rect
			(at -0.43 0)
			(size 0.64 0.68)
			(layers "B.Cu" "B.Mask" "B.Paste")
			(net "NetC48_1")
		)
		(pad "2" smd rect
			(at 0.43 0)
			(size 0.64 0.68)
			(layers "B.Cu" "B.Mask" "B.Paste")
			(net "PCIE_TX1_P")
		)
	)
	(gr_poly
		(pts
			(xy 159.9364 142.21969) (xy 159.9364 142.22789) (xy 159.9364 142.23608) (xy 159.9364 142.24428) (xy 159.9364 142.25247)
			(xy 159.9364 142.26067) (xy 159.9364 142.26886) (xy 159.9364 142.27706) (xy 159.9364 142.28525) (xy 159.9364 142.29344)
			(xy 159.9364 142.30164) (xy 159.9364 142.30984) (xy 159.9364 142.31803) (xy 159.9364 142.32622) (xy 159.9364 142.33442)
			(xy 159.9364 142.34261) (xy 159.9364 142.35081) (xy 159.9364 142.359) (xy 159.9364 142.3672) (xy 159.9364 142.37539)
			(xy 159.9364 142.38359) (xy 159.9364 142.39178) (xy 159.9364 142.39997) (xy 159.9364 142.40817) (xy 159.9364 142.41636)
			(xy 159.9364 142.42456) (xy 159.9364 142.43275) (xy 159.9364 142.44095) (xy 159.9364 142.44914) (xy 159.9364 142.45734)
			(xy 159.9364 142.46553) (xy 159.9364 142.47372) (xy 159.9364 142.48192) (xy 159.9364 142.49011) (xy 159.9364 142.49831)
			(xy 159.9364 142.5065) (xy 159.9364 142.5147) (xy 159.9364 142.52289) (xy 159.9364 142.53108) (xy 159.9364 142.53928)
			(xy 159.9364 142.54747) (xy 159.9364 142.55567) (xy 159.9364 142.56387) (xy 159.9364 142.57206) (xy 159.9364 142.58025)
			(xy 159.9364 142.58845) (xy 159.9364 142.59664) (xy 159.9364 142.60484) (xy 159.9364 142.61303) (xy 159.9364 142.62123)
			(xy 159.9364 142.62942) (xy 159.9364 142.63761) (xy 159.9364 142.64581) (xy 159.32181 142.64581)
			(xy 159.32181 142.63761) (xy 159.32181 142.62942) (xy 159.32181 142.62123) (xy 159.32181 142.61303)
			(xy 159.32181 142.60484) (xy 159.32181 142.59664) (xy 159.32181 142.58845) (xy 159.32181 142.58025)
			(xy 159.32181 142.57206) (xy 159.32181 142.56387) (xy 159.32181 142.55567) (xy 159.32181 142.54747)
			(xy 159.32181 142.53928) (xy 159.32181 142.53108) (xy 159.32181 142.52289) (xy 159.32181 142.5147)
			(xy 159.32181 142.5065) (xy 159.32181 142.49831) (xy 159.32181 142.49011) (xy 159.32181 142.48192)
			(xy 159.32181 142.47372) (xy 159.32181 142.46553) (xy 159.32181 142.45734) (xy 159.32181 142.44914)
			(xy 159.32181 142.44095) (xy 159.32181 142.43275) (xy 159.32181 142.42456) (xy 159.32181 142.41636)
			(xy 159.32181 142.40817) (xy 159.32181 142.39997) (xy 159.32181 142.39178) (xy 159.32181 142.38359)
			(xy 159.32181 142.37539) (xy 159.32181 142.3672) (xy 159.32181 142.359) (xy 159.32181 142.35081)
			(xy 159.32181 142.34261) (xy 159.32181 142.33442) (xy 159.32181 142.32622) (xy 159.32181 142.31803)
			(xy 159.32181 142.30984) (xy 159.32181 142.30164) (xy 159.32181 142.29344) (xy 159.32181 142.28525)
			(xy 159.32181 142.27706) (xy 159.32181 142.26886) (xy 159.32181 142.26067) (xy 159.32181 142.25247)
			(xy 159.32181 142.24428) (xy 159.32181 142.23608) (xy 159.32181 142.22789) (xy 159.32181 142.21969)
			(xy 159.32181 142.2115) (xy 159.9364 142.2115)
		)
		(stroke
			(width 0)
			(type default)
		)
		(fill yes)
		(layer "F.Cu")
	)
	(gr_poly
		(pts
			(xy 153.31525 144.62068) (xy 153.34803 144.62068) (xy 153.34803 144.62888) (xy 153.36442 144.62888)
			(xy 153.36442 144.63707) (xy 153.3808 144.63707) (xy 153.3808 144.64527) (xy 153.39719 144.64527)
			(xy 153.39719 144.65346) (xy 153.41358 144.65346) (xy 153.41358 144.66165) (xy 153.42178 144.66165)
			(xy 153.42178 144.66985) (xy 153.43816 144.66985) (xy 153.43816 144.67804) (xy 153.44636 144.67804)
			(xy 153.44636 144.68624) (xy 153.45455 144.68624) (xy 153.45455 144.69443) (xy 153.46275 144.69443)
			(xy 153.46275 144.70262) (xy 153.47095 144.70262) (xy 153.47095 144.71082) (xy 153.47914 144.71082)
			(xy 153.47914 144.71901) (xy 153.48733 144.71901) (xy 153.48733 144.72721) (xy 153.49553 144.72721)
			(xy 153.49553 144.73541) (xy 153.49553 144.7436) (xy 153.50372 144.7436) (xy 153.50372 144.75179)
			(xy 153.51192 144.75179) (xy 153.51192 144.75999) (xy 153.51192 144.76818) (xy 153.52011 144.76818)
			(xy 153.52011 144.77638) (xy 153.52011 144.78457) (xy 153.52831 144.78457) (xy 153.52831 144.79277)
			(xy 153.52831 144.80096) (xy 153.5365 144.80096) (xy 153.5365 144.80915) (xy 153.5365 144.81735)
			(xy 153.5365 144.82554) (xy 153.54469 144.82554) (xy 153.54469 144.83374) (xy 153.54469 144.84193)
			(xy 153.54469 144.85013) (xy 153.54469 144.85832) (xy 153.54469 144.86652) (xy 153.55289 144.86652)
			(xy 153.55289 144.87471) (xy 153.55289 144.8829) (xy 153.55289 144.8911) (xy 153.55289 144.89929)
			(xy 153.55289 144.90749) (xy 153.55289 144.91568) (xy 153.55289 144.92388) (xy 153.55289 144.93207)
			(xy 153.55289 144.94027) (xy 153.55289 144.94846) (xy 153.55289 144.95665) (xy 153.55289 144.96485)
			(xy 153.54469 144.96485) (xy 153.54469 144.97305) (xy 153.54469 144.98124) (xy 153.54469 144.98943)
			(xy 153.54469 144.99763) (xy 153.54469 145.00582) (xy 153.5365 145.00582) (xy 153.5365 145.01402)
			(xy 153.5365 145.02221) (xy 153.5365 145.03041) (xy 153.52831 145.03041) (xy 153.52831 145.0386)
			(xy 153.52831 145.04679) (xy 153.52011 145.04679) (xy 153.52011 145.05499) (xy 153.52011 145.06318)
			(xy 153.51192 145.06318) (xy 153.51192 145.07138) (xy 153.51192 145.07957) (xy 153.50372 145.07957)
			(xy 153.50372 145.08777) (xy 153.49553 145.08777) (xy 153.49553 145.09596) (xy 153.49553 145.10416)
			(xy 153.48733 145.10416) (xy 153.48733 145.11235) (xy 153.47914 145.11235) (xy 153.47914 145.12054)
			(xy 153.47095 145.12054) (xy 153.47095 145.12874) (xy 153.46275 145.12874) (xy 153.46275 145.13693)
			(xy 153.45455 145.13693) (xy 153.45455 145.14513) (xy 153.44636 145.14513) (xy 153.44636 145.15332)
			(xy 153.43816 145.15332) (xy 153.43816 145.16152) (xy 153.42178 145.16152) (xy 153.42178 145.16971)
			(xy 153.41358 145.16971) (xy 153.41358 145.17791) (xy 153.39719 145.17791) (xy 153.39719 145.1861)
			(xy 153.3808 145.1861) (xy 153.3808 145.19429) (xy 153.36442 145.19429) (xy 153.36442 145.20249)
			(xy 153.33983 145.20249) (xy 153.33983 145.21069) (xy 153.31525 145.21069) (xy 153.31525 145.21888)
			(xy 153.17594 145.21888) (xy 153.17594 145.21069) (xy 153.15136 145.21069) (xy 153.15136 145.20249)
			(xy 153.12677 145.20249) (xy 153.12677 145.19429) (xy 153.11039 145.19429) (xy 153.11039 145.1861)
			(xy 153.094 145.1861) (xy 153.094 145.17791) (xy 153.07761 145.17791) (xy 153.07761 145.16971) (xy 153.06941 145.16971)
			(xy 153.06941 145.16152) (xy 153.06122 145.16152) (xy 153.06122 145.15332) (xy 153.04483 145.15332)
			(xy 153.04483 145.14513) (xy 153.03664 145.14513) (xy 153.03664 145.13693) (xy 153.02844 145.13693)
			(xy 153.02844 145.12874) (xy 153.02025 145.12874) (xy 153.02025 145.12054) (xy 153.01205 145.12054)
			(xy 153.01205 145.11235) (xy 153.00386 145.11235) (xy 153.00386 145.10416) (xy 153.00386 145.09596)
			(xy 152.99566 145.09596) (xy 152.99566 145.08777) (xy 152.98747 145.08777) (xy 152.98747 145.07957)
			(xy 152.98747 145.07138) (xy 152.97927 145.07138) (xy 152.97927 145.06318) (xy 152.97927 145.05499)
			(xy 152.97108 145.05499) (xy 152.97108 145.04679) (xy 152.97108 145.0386) (xy 152.96288 145.0386)
			(xy 152.96288 145.03041) (xy 152.96288 145.02221) (xy 152.95469 145.02221) (xy 152.95469 145.01402)
			(xy 152.95469 145.00582) (xy 152.95469 144.99763) (xy 152.9465 144.99763) (xy 152.9465 144.98943)
			(xy 152.9465 144.98124) (xy 152.9465 144.97305) (xy 152.9465 144.96485) (xy 152.9465 144.95665) (xy 152.9383 144.95665)
			(xy 152.9383 144.94846) (xy 152.9383 144.94027) (xy 152.9383 144.93207) (xy 152.9383 144.92388) (xy 152.9383 144.91568)
			(xy 152.9383 144.90749) (xy 152.9383 144.89929) (xy 152.9383 144.8911) (xy 152.9383 144.8829) (xy 152.9383 144.87471)
			(xy 152.9465 144.87471) (xy 152.9465 144.86652) (xy 152.9465 144.85832) (xy 152.9465 144.85013) (xy 152.9465 144.84193)
			(xy 152.9465 144.83374) (xy 152.95469 144.83374) (xy 152.95469 144.82554) (xy 152.95469 144.81735)
			(xy 152.95469 144.80915) (xy 152.96288 144.80915) (xy 152.96288 144.80096) (xy 152.96288 144.79277)
			(xy 152.97108 144.79277) (xy 152.97108 144.78457) (xy 152.97108 144.77638) (xy 152.97927 144.77638)
			(xy 152.97927 144.76818) (xy 152.97927 144.75999) (xy 152.98747 144.75999) (xy 152.98747 144.75179)
			(xy 152.98747 144.7436) (xy 152.99566 144.7436) (xy 152.99566 144.73541) (xy 153.00386 144.73541)
			(xy 153.00386 144.72721) (xy 153.00386 144.71901) (xy 153.01205 144.71901) (xy 153.01205 144.71082)
			(xy 153.02025 144.71082) (xy 153.02025 144.70262) (xy 153.02844 144.70262) (xy 153.02844 144.69443)
			(xy 153.03664 144.69443) (xy 153.03664 144.68624) (xy 153.04483 144.68624) (xy 153.04483 144.67804)
			(xy 153.05302 144.67804) (xy 153.05302 144.66985) (xy 153.06941 144.66985) (xy 153.06941 144.66165)
			(xy 153.07761 144.66165) (xy 153.07761 144.65346) (xy 153.094 144.65346) (xy 153.094 144.64527) (xy 153.11039 144.64527)
			(xy 153.11039 144.63707) (xy 153.12677 144.63707) (xy 153.12677 144.62888) (xy 153.15136 144.62888)
			(xy 153.15136 144.62068) (xy 153.17594 144.62068) (xy 153.17594 144.61249) (xy 153.31525 144.61249)
		)
		(stroke
			(width 0)
			(type default)
		)
		(fill yes)
		(layer "F.Cu")
	)
	(gr_poly
		(pts
			(xy 161.66544 142.23608) (xy 161.68183 142.23608) (xy 161.68183 142.24428) (xy 161.68183 142.25247)
			(xy 161.68183 142.26067) (xy 161.68183 142.26886) (xy 161.68183 142.27706) (xy 161.68183 142.28525)
			(xy 161.68183 142.29344) (xy 161.68183 142.30164) (xy 161.68183 142.30984) (xy 161.68183 142.31803)
			(xy 161.68183 142.32622) (xy 161.68183 142.33442) (xy 161.68183 142.34261) (xy 161.68183 142.35081)
			(xy 161.68183 142.359) (xy 161.68183 142.3672) (xy 161.68183 142.37539) (xy 161.68183 142.38359)
			(xy 161.68183 142.39178) (xy 161.68183 142.39997) (xy 161.68183 142.40817) (xy 161.68183 142.41636)
			(xy 161.68183 142.42456) (xy 161.68183 142.43275) (xy 161.68183 142.44095) (xy 161.68183 142.44914)
			(xy 161.68183 142.45734) (xy 161.68183 142.46553) (xy 161.68183 142.47372) (xy 161.68183 142.48192)
			(xy 161.68183 142.49011) (xy 161.68183 142.49831) (xy 161.68183 142.5065) (xy 161.68183 142.5147)
			(xy 161.68183 142.52289) (xy 161.68183 142.53108) (xy 161.68183 142.53928) (xy 161.68183 142.54747)
			(xy 161.68183 142.55567) (xy 161.68183 142.56387) (xy 161.68183 142.57206) (xy 161.68183 142.58025)
			(xy 161.68183 142.58845) (xy 161.68183 142.59664) (xy 161.68183 142.60484) (xy 161.68183 142.61303)
			(xy 161.68183 142.62123) (xy 161.68183 142.62942) (xy 161.68183 142.63761) (xy 161.68183 142.64581)
			(xy 161.68183 142.654) (xy 161.68183 142.6622) (xy 161.68183 142.67039) (xy 161.68183 142.67859)
			(xy 161.68183 142.68678) (xy 161.68183 142.69498) (xy 161.68183 142.70317) (xy 161.68183 142.71136)
			(xy 161.68183 142.71956) (xy 161.68183 142.72775) (xy 161.68183 142.73595) (xy 161.68183 142.74414)
			(xy 161.68183 142.75234) (xy 161.68183 142.76053) (xy 161.68183 142.76873) (xy 161.68183 142.77692)
			(xy 161.68183 142.78511) (xy 161.68183 142.79331) (xy 161.68183 142.8015) (xy 161.68183 142.8097)
			(xy 161.68183 142.81789) (xy 161.68183 142.82609) (xy 161.68183 142.83428) (xy 161.68183 142.84248)
			(xy 161.68183 142.85067) (xy 161.68183 142.85887) (xy 161.68183 142.86706) (xy 161.68183 142.87525)
			(xy 161.68183 142.88345) (xy 161.68183 142.89164) (xy 161.68183 142.89984) (xy 161.68183 142.90803)
			(xy 161.68183 142.91623) (xy 161.68183 142.92442) (xy 161.68183 142.93262) (xy 161.68183 142.94081)
			(xy 161.68183 142.949) (xy 161.68183 142.9572) (xy 161.68183 142.96539) (xy 161.68183 142.97359)
			(xy 161.68183 142.98178) (xy 161.68183 142.98998) (xy 161.68183 142.99817) (xy 161.68183 143.00637)
			(xy 161.68183 143.01456) (xy 161.68183 143.02275) (xy 161.68183 143.03095) (xy 161.68183 143.03915)
			(xy 161.68183 143.04734) (xy 161.68183 143.05553) (xy 161.68183 143.06373) (xy 161.68183 143.07192)
			(xy 161.68183 143.08012) (xy 161.68183 143.08831) (xy 161.68183 143.09651) (xy 161.68183 143.1047)
			(xy 161.68183 143.1129) (xy 161.68183 143.12109) (xy 161.68183 143.12928) (xy 161.68183 143.13748)
			(xy 161.68183 143.14567) (xy 161.08363 143.14567) (xy 161.08363 143.13748) (xy 161.08363 143.12928)
			(xy 161.08363 143.12109) (xy 161.08363 143.1129) (xy 161.08363 143.1047) (xy 161.08363 143.09651)
			(xy 161.08363 143.08831) (xy 161.08363 143.08012) (xy 161.08363 143.07192) (xy 161.08363 143.06373)
			(xy 161.08363 143.05553) (xy 161.08363 143.04734) (xy 161.08363 143.03915) (xy 161.08363 143.03095)
			(xy 161.08363 143.02275) (xy 161.08363 143.01456) (xy 161.08363 143.00637) (xy 161.08363 142.99817)
			(xy 161.08363 142.98998) (xy 161.08363 142.98178) (xy 161.08363 142.97359) (xy 161.08363 142.96539)
			(xy 161.08363 142.9572) (xy 161.08363 142.949) (xy 161.08363 142.94081) (xy 161.08363 142.93262)
			(xy 161.08363 142.92442) (xy 161.08363 142.91623) (xy 161.08363 142.90803) (xy 161.08363 142.89984)
			(xy 161.08363 142.89164) (xy 161.08363 142.88345) (xy 161.08363 142.87525) (xy 161.08363 142.86706)
			(xy 161.08363 142.85887) (xy 161.08363 142.85067) (xy 161.08363 142.84248) (xy 161.08363 142.83428)
			(xy 161.08363 142.82609) (xy 161.08363 142.81789) (xy 161.08363 142.8097) (xy 161.08363 142.8015)
			(xy 161.08363 142.79331) (xy 161.08363 142.78511) (xy 161.08363 142.77692) (xy 161.08363 142.76873)
			(xy 161.08363 142.76053) (xy 161.08363 142.75234) (xy 161.08363 142.74414) (xy 161.08363 142.73595)
			(xy 161.08363 142.72775) (xy 161.08363 142.71956) (xy 161.08363 142.71136) (xy 161.08363 142.70317)
			(xy 161.08363 142.69498) (xy 161.08363 142.68678) (xy 161.08363 142.67859) (xy 161.08363 142.67039)
			(xy 161.08363 142.6622) (xy 161.08363 142.654) (xy 161.08363 142.64581) (xy 161.08363 142.63761)
			(xy 161.08363 142.62942) (xy 161.08363 142.62123) (xy 161.08363 142.61303) (xy 161.08363 142.60484)
			(xy 161.08363 142.59664) (xy 161.08363 142.58845) (xy 161.08363 142.58025) (xy 161.08363 142.57206)
			(xy 161.08363 142.56387) (xy 161.08363 142.55567) (xy 161.08363 142.54747) (xy 161.08363 142.53928)
			(xy 161.08363 142.53108) (xy 161.08363 142.52289) (xy 161.08363 142.5147) (xy 161.08363 142.5065)
			(xy 161.08363 142.49831) (xy 161.08363 142.49011) (xy 161.08363 142.48192) (xy 161.08363 142.47372)
			(xy 161.08363 142.46553) (xy 161.08363 142.45734) (xy 161.08363 142.44914) (xy 161.08363 142.44095)
			(xy 161.08363 142.43275) (xy 161.08363 142.42456) (xy 161.08363 142.41636) (xy 161.08363 142.40817)
			(xy 161.08363 142.39997) (xy 161.08363 142.39178) (xy 161.08363 142.38359) (xy 161.08363 142.37539)
			(xy 161.08363 142.3672) (xy 161.08363 142.359) (xy 161.08363 142.35081) (xy 161.08363 142.34261)
			(xy 161.08363 142.33442) (xy 161.08363 142.32622) (xy 161.08363 142.31803) (xy 161.08363 142.30984)
			(xy 161.08363 142.30164) (xy 161.08363 142.29344) (xy 161.08363 142.28525) (xy 161.08363 142.27706)
			(xy 161.08363 142.26886) (xy 161.08363 142.26067) (xy 161.08363 142.25247) (xy 161.08363 142.24428)
			(xy 161.08363 142.23608) (xy 161.09182 142.23608) (xy 161.09182 142.22789) (xy 161.10002 142.22789)
			(xy 161.10002 142.23608) (xy 161.63266 142.23608) (xy 161.63266 142.22789) (xy 161.64085 142.22789)
			(xy 161.64085 142.23608) (xy 161.65724 142.23608) (xy 161.65724 142.22789) (xy 161.66544 142.22789)
		)
		(stroke
			(width 0)
			(type default)
		)
		(fill yes)
		(layer "F.Cu")
	)
	(gr_poly
		(pts
			(xy 153.28247 143.50623) (xy 153.32344 143.50623) (xy 153.32344 143.51443) (xy 153.34803 143.51443)
			(xy 153.34803 143.52262) (xy 153.37261 143.52262) (xy 153.37261 143.53082) (xy 153.389 143.53082)
			(xy 153.389 143.53901) (xy 153.40539 143.53901) (xy 153.40539 143.5472) (xy 153.41358 143.5472) (xy 153.41358 143.5554)
			(xy 153.42997 143.5554) (xy 153.42997 143.56359) (xy 153.43816 143.56359) (xy 153.43816 143.57179)
			(xy 153.44636 143.57179) (xy 153.44636 143.57998) (xy 153.45455 143.57998) (xy 153.45455 143.58818)
			(xy 153.46275 143.58818) (xy 153.46275 143.59637) (xy 153.47095 143.59637) (xy 153.47095 143.60456)
			(xy 153.47914 143.60456) (xy 153.47914 143.61276) (xy 153.48733 143.61276) (xy 153.48733 143.62095)
			(xy 153.49553 143.62095) (xy 153.49553 143.62915) (xy 153.49553 143.63734) (xy 153.50372 143.63734)
			(xy 153.50372 143.64554) (xy 153.51192 143.64554) (xy 153.51192 143.65373) (xy 153.51192 143.66193)
			(xy 153.52011 143.66193) (xy 153.52011 143.67012) (xy 153.52011 143.67831) (xy 153.52831 143.67831)
			(xy 153.52831 143.68651) (xy 153.52831 143.6947) (xy 153.5365 143.6947) (xy 153.5365 143.7029) (xy 153.5365 143.71109)
			(xy 153.5365 143.71929) (xy 153.54469 143.71929) (xy 153.54469 143.72748) (xy 153.54469 143.73567)
			(xy 153.54469 143.74387) (xy 153.54469 143.75206) (xy 153.55289 143.75206) (xy 153.55289 143.76026)
			(xy 153.55289 143.76846) (xy 153.55289 143.77665) (xy 153.55289 143.78484) (xy 153.55289 143.79304)
			(xy 153.55289 143.80123) (xy 153.55289 143.80943) (xy 153.55289 143.81762) (xy 153.55289 143.82582)
			(xy 153.55289 143.83401) (xy 153.55289 143.8422) (xy 153.55289 143.8504) (xy 153.55289 143.85859)
			(xy 153.54469 143.85859) (xy 153.54469 143.86679) (xy 153.54469 143.87498) (xy 153.54469 143.88318)
			(xy 153.54469 143.89137) (xy 153.5365 143.89137) (xy 153.5365 143.89957) (xy 153.5365 143.90776)
			(xy 153.5365 143.91596) (xy 153.52831 143.91596) (xy 153.52831 143.92415) (xy 153.52831 143.93234)
			(xy 153.52831 143.94054) (xy 153.52011 143.94054) (xy 153.52011 143.94873) (xy 153.52011 143.95693)
			(xy 153.51192 143.95693) (xy 153.51192 143.96512) (xy 153.50372 143.96512) (xy 153.50372 143.97332)
			(xy 153.50372 143.98151) (xy 153.49553 143.98151) (xy 153.49553 143.9897) (xy 153.48733 143.9897)
			(xy 153.48733 143.9979) (xy 153.48733 144.0061) (xy 153.47914 144.0061) (xy 153.47914 144.01429)
			(xy 153.47095 144.01429) (xy 153.47095 144.02248) (xy 153.46275 144.02248) (xy 153.46275 144.03068)
			(xy 153.45455 144.03068) (xy 153.45455 144.03887) (xy 153.44636 144.03887) (xy 153.44636 144.04707)
			(xy 153.42997 144.04707) (xy 153.42997 144.05526) (xy 153.42178 144.05526) (xy 153.42178 144.06346)
			(xy 153.40539 144.06346) (xy 153.40539 144.07165) (xy 153.39719 144.07165) (xy 153.39719 144.07985)
			(xy 153.3808 144.07985) (xy 153.3808 144.08804) (xy 153.35622 144.08804) (xy 153.35622 144.09623)
			(xy 153.33983 144.09623) (xy 153.33983 144.10443) (xy 153.30705 144.10443) (xy 153.30705 144.11262)
			(xy 153.18414 144.11262) (xy 153.18414 144.10443) (xy 153.15955 144.10443) (xy 153.15955 144.09623)
			(xy 153.13497 144.09623) (xy 153.13497 144.08804) (xy 153.11039 144.08804) (xy 153.11039 144.07985)
			(xy 153.10219 144.07985) (xy 153.10219 144.07165) (xy 153.0858 144.07165) (xy 153.0858 144.06346)
			(xy 153.06941 144.06346) (xy 153.06941 144.05526) (xy 153.06122 144.05526) (xy 153.06122 144.04707)
			(xy 153.05302 144.04707) (xy 153.05302 144.03887) (xy 153.03664 144.03887) (xy 153.03664 144.03068)
			(xy 153.02844 144.03068) (xy 153.02844 144.02248) (xy 153.02025 144.02248) (xy 153.02025 144.01429)
			(xy 153.01205 144.01429) (xy 153.01205 144.0061) (xy 153.01205 143.9979) (xy 153.00386 143.9979)
			(xy 153.00386 143.9897) (xy 152.99566 143.9897) (xy 152.99566 143.98151) (xy 152.98747 143.98151)
			(xy 152.98747 143.97332) (xy 152.98747 143.96512) (xy 152.97927 143.96512) (xy 152.97927 143.95693)
			(xy 152.97927 143.94873) (xy 152.97108 143.94873) (xy 152.97108 143.94054) (xy 152.97108 143.93234)
			(xy 152.96288 143.93234) (xy 152.96288 143.92415) (xy 152.96288 143.91596) (xy 152.95469 143.91596)
			(xy 152.95469 143.90776) (xy 152.95469 143.89957) (xy 152.95469 143.89137) (xy 152.9465 143.89137)
			(xy 152.9465 143.88318) (xy 152.9465 143.87498) (xy 152.9465 143.86679) (xy 152.9465 143.85859) (xy 152.9465 143.8504)
			(xy 152.9383 143.8504) (xy 152.9383 143.8422) (xy 152.9383 143.83401) (xy 152.9383 143.82582) (xy 152.9383 143.81762)
			(xy 152.9383 143.80943) (xy 152.9383 143.80123) (xy 152.9383 143.79304) (xy 152.9383 143.78484) (xy 152.9383 143.77665)
			(xy 152.9383 143.76846) (xy 152.9465 143.76846) (xy 152.9465 143.76026) (xy 152.9465 143.75206) (xy 152.9465 143.74387)
			(xy 152.9465 143.73567) (xy 152.9465 143.72748) (xy 152.95469 143.72748) (xy 152.95469 143.71929)
			(xy 152.95469 143.71109) (xy 152.95469 143.7029) (xy 152.96288 143.7029) (xy 152.96288 143.6947)
			(xy 152.96288 143.68651) (xy 152.96288 143.67831) (xy 152.97108 143.67831) (xy 152.97108 143.67012)
			(xy 152.97108 143.66193) (xy 152.97927 143.66193) (xy 152.97927 143.65373) (xy 152.97927 143.64554)
			(xy 152.98747 143.64554) (xy 152.98747 143.63734) (xy 152.99566 143.63734) (xy 152.99566 143.62915)
			(xy 152.99566 143.62095) (xy 153.00386 143.62095) (xy 153.00386 143.61276) (xy 153.01205 143.61276)
			(xy 153.01205 143.60456) (xy 153.02025 143.60456) (xy 153.02025 143.59637) (xy 153.02844 143.59637)
			(xy 153.02844 143.58818) (xy 153.03664 143.58818) (xy 153.03664 143.57998) (xy 153.04483 143.57998)
			(xy 153.04483 143.57179) (xy 153.05302 143.57179) (xy 153.05302 143.56359) (xy 153.06122 143.56359)
			(xy 153.06122 143.5554) (xy 153.07761 143.5554) (xy 153.07761 143.5472) (xy 153.094 143.5472) (xy 153.094 143.53901)
			(xy 153.10219 143.53901) (xy 153.10219 143.53082) (xy 153.11858 143.53082) (xy 153.11858 143.52262)
			(xy 153.14316 143.52262) (xy 153.14316 143.51443) (xy 153.16775 143.51443) (xy 153.16775 143.50623)
			(xy 153.20872 143.50623) (xy 153.20872 143.49803) (xy 153.28247 143.49803)
		)
		(stroke
			(width 0)
			(type default)
		)
		(fill yes)
		(layer "F.Cu")
	)
	(gr_poly
		(pts
			(xy 153.29886 142.39997) (xy 153.33164 142.39997) (xy 153.33164 142.40817) (xy 153.35622 142.40817)
			(xy 153.35622 142.41636) (xy 153.37261 142.41636) (xy 153.37261 142.42456) (xy 153.389 142.42456)
			(xy 153.389 142.43275) (xy 153.40539 142.43275) (xy 153.40539 142.44095) (xy 153.42178 142.44095)
			(xy 153.42178 142.44914) (xy 153.42997 142.44914) (xy 153.42997 142.45734) (xy 153.43816 142.45734)
			(xy 153.43816 142.46553) (xy 153.45455 142.46553) (xy 153.45455 142.47372) (xy 153.46275 142.47372)
			(xy 153.46275 142.48192) (xy 153.47095 142.48192) (xy 153.47095 142.49011) (xy 153.47914 142.49011)
			(xy 153.47914 142.49831) (xy 153.47914 142.5065) (xy 153.48733 142.5065) (xy 153.48733 142.5147)
			(xy 153.49553 142.5147) (xy 153.49553 142.52289) (xy 153.50372 142.52289) (xy 153.50372 142.53108)
			(xy 153.50372 142.53928) (xy 153.51192 142.53928) (xy 153.51192 142.54747) (xy 153.51192 142.55567)
			(xy 153.52011 142.55567) (xy 153.52011 142.56387) (xy 153.52011 142.57206) (xy 153.52831 142.57206)
			(xy 153.52831 142.58025) (xy 153.52831 142.58845) (xy 153.5365 142.58845) (xy 153.5365 142.59664)
			(xy 153.5365 142.60484) (xy 153.5365 142.61303) (xy 153.54469 142.61303) (xy 153.54469 142.62123)
			(xy 153.54469 142.62942) (xy 153.54469 142.63761) (xy 153.54469 142.64581) (xy 153.55289 142.64581)
			(xy 153.55289 142.654) (xy 153.55289 142.6622) (xy 153.55289 142.67039) (xy 153.55289 142.67859)
			(xy 153.55289 142.68678) (xy 153.55289 142.69498) (xy 153.55289 142.70317) (xy 153.55289 142.71136)
			(xy 153.55289 142.71956) (xy 153.55289 142.72775) (xy 153.55289 142.73595) (xy 153.55289 142.74414)
			(xy 153.55289 142.75234) (xy 153.54469 142.75234) (xy 153.54469 142.76053) (xy 153.54469 142.76873)
			(xy 153.54469 142.77692) (xy 153.54469 142.78511) (xy 153.5365 142.78511) (xy 153.5365 142.79331)
			(xy 153.5365 142.8015) (xy 153.5365 142.8097) (xy 153.52831 142.8097) (xy 153.52831 142.81789) (xy 153.52831 142.82609)
			(xy 153.52011 142.82609) (xy 153.52011 142.83428) (xy 153.52011 142.84248) (xy 153.51192 142.84248)
			(xy 153.51192 142.85067) (xy 153.51192 142.85887) (xy 153.50372 142.85887) (xy 153.50372 142.86706)
			(xy 153.50372 142.87525) (xy 153.49553 142.87525) (xy 153.49553 142.88345) (xy 153.48733 142.88345)
			(xy 153.48733 142.89164) (xy 153.47914 142.89164) (xy 153.47914 142.89984) (xy 153.47914 142.90803)
			(xy 153.47095 142.90803) (xy 153.47095 142.91623) (xy 153.46275 142.91623) (xy 153.46275 142.92442)
			(xy 153.44636 142.92442) (xy 153.44636 142.93262) (xy 153.43816 142.93262) (xy 153.43816 142.94081)
			(xy 153.42997 142.94081) (xy 153.42997 142.949) (xy 153.42178 142.949) (xy 153.42178 142.9572) (xy 153.40539 142.9572)
			(xy 153.40539 142.96539) (xy 153.389 142.96539) (xy 153.389 142.97359) (xy 153.37261 142.97359) (xy 153.37261 142.98178)
			(xy 153.35622 142.98178) (xy 153.35622 142.98998) (xy 153.33164 142.98998) (xy 153.33164 142.99817)
			(xy 153.29066 142.99817) (xy 153.29066 143.00637) (xy 153.20052 143.00637) (xy 153.20052 142.99817)
			(xy 153.15955 142.99817) (xy 153.15955 142.98998) (xy 153.13497 142.98998) (xy 153.13497 142.98178)
			(xy 153.11858 142.98178) (xy 153.11858 142.97359) (xy 153.10219 142.97359) (xy 153.10219 142.96539)
			(xy 153.0858 142.96539) (xy 153.0858 142.9572) (xy 153.07761 142.9572) (xy 153.07761 142.949) (xy 153.06122 142.949)
			(xy 153.06122 142.94081) (xy 153.05302 142.94081) (xy 153.05302 142.93262) (xy 153.04483 142.93262)
			(xy 153.04483 142.92442) (xy 153.03664 142.92442) (xy 153.03664 142.91623) (xy 153.02844 142.91623)
			(xy 153.02844 142.90803) (xy 153.02025 142.90803) (xy 153.02025 142.89984) (xy 153.01205 142.89984)
			(xy 153.01205 142.89164) (xy 153.00386 142.89164) (xy 153.00386 142.88345) (xy 152.99566 142.88345)
			(xy 152.99566 142.87525) (xy 152.99566 142.86706) (xy 152.98747 142.86706) (xy 152.98747 142.85887)
			(xy 152.97927 142.85887) (xy 152.97927 142.85067) (xy 152.97927 142.84248) (xy 152.97108 142.84248)
			(xy 152.97108 142.83428) (xy 152.97108 142.82609) (xy 152.96288 142.82609) (xy 152.96288 142.81789)
			(xy 152.96288 142.8097) (xy 152.96288 142.8015) (xy 152.95469 142.8015) (xy 152.95469 142.79331)
			(xy 152.95469 142.78511) (xy 152.95469 142.77692) (xy 152.9465 142.77692) (xy 152.9465 142.76873)
			(xy 152.9465 142.76053) (xy 152.9465 142.75234) (xy 152.9465 142.74414) (xy 152.9383 142.74414) (xy 152.9383 142.73595)
			(xy 152.9383 142.72775) (xy 152.9383 142.71956) (xy 152.9383 142.71136) (xy 152.9383 142.70317) (xy 152.9383 142.69498)
			(xy 152.9383 142.68678) (xy 152.9383 142.67859) (xy 152.9383 142.67039) (xy 152.9383 142.6622) (xy 152.9383 142.654)
			(xy 152.9465 142.654) (xy 152.9465 142.64581) (xy 152.9465 142.63761) (xy 152.9465 142.62942) (xy 152.9465 142.62123)
			(xy 152.95469 142.62123) (xy 152.95469 142.61303) (xy 152.95469 142.60484) (xy 152.95469 142.59664)
			(xy 152.95469 142.58845) (xy 152.96288 142.58845) (xy 152.96288 142.58025) (xy 152.96288 142.57206)
			(xy 152.97108 142.57206) (xy 152.97108 142.56387) (xy 152.97108 142.55567) (xy 152.97927 142.55567)
			(xy 152.97927 142.54747) (xy 152.97927 142.53928) (xy 152.98747 142.53928) (xy 152.98747 142.53108)
			(xy 152.99566 142.53108) (xy 152.99566 142.52289) (xy 152.99566 142.5147) (xy 153.00386 142.5147)
			(xy 153.00386 142.5065) (xy 153.01205 142.5065) (xy 153.01205 142.49831) (xy 153.02025 142.49831)
			(xy 153.02025 142.49011) (xy 153.02844 142.49011) (xy 153.02844 142.48192) (xy 153.03664 142.48192)
			(xy 153.03664 142.47372) (xy 153.04483 142.47372) (xy 153.04483 142.46553) (xy 153.05302 142.46553)
			(xy 153.05302 142.45734) (xy 153.06122 142.45734) (xy 153.06122 142.44914) (xy 153.07761 142.44914)
			(xy 153.07761 142.44095) (xy 153.0858 142.44095) (xy 153.0858 142.43275) (xy 153.10219 142.43275)
			(xy 153.10219 142.42456) (xy 153.11858 142.42456) (xy 153.11858 142.41636) (xy 153.13497 142.41636)
			(xy 153.13497 142.40817) (xy 153.15955 142.40817) (xy 153.15955 142.39997) (xy 153.20052 142.39997)
			(xy 153.20052 142.39178) (xy 153.29886 142.39178)
		)
		(stroke
			(width 0)
			(type default)
		)
		(fill yes)
		(layer "F.Cu")
	)
	(gr_poly
		(pts
			(xy 153.30705 141.29372) (xy 153.33983 141.29372) (xy 153.33983 141.30191) (xy 153.36442 141.30191)
			(xy 153.36442 141.31011) (xy 153.3808 141.31011) (xy 153.3808 141.3183) (xy 153.39719 141.3183) (xy 153.39719 141.32649)
			(xy 153.40539 141.32649) (xy 153.40539 141.33469) (xy 153.42178 141.33469) (xy 153.42178 141.34289)
			(xy 153.42997 141.34289) (xy 153.42997 141.35108) (xy 153.44636 141.35108) (xy 153.44636 141.35927)
			(xy 153.45455 141.35927) (xy 153.45455 141.36747) (xy 153.46275 141.36747) (xy 153.46275 141.37566)
			(xy 153.47095 141.37566) (xy 153.47095 141.38386) (xy 153.47914 141.38386) (xy 153.47914 141.39205)
			(xy 153.48733 141.39205) (xy 153.48733 141.40025) (xy 153.48733 141.40844) (xy 153.49553 141.40844)
			(xy 153.49553 141.41663) (xy 153.50372 141.41663) (xy 153.50372 141.42483) (xy 153.50372 141.43302)
			(xy 153.51192 141.43302) (xy 153.51192 141.44122) (xy 153.52011 141.44122) (xy 153.52011 141.44941)
			(xy 153.52011 141.45761) (xy 153.52831 141.45761) (xy 153.52831 141.4658) (xy 153.52831 141.474)
			(xy 153.52831 141.48219) (xy 153.5365 141.48219) (xy 153.5365 141.49039) (xy 153.5365 141.49858)
			(xy 153.5365 141.50677) (xy 153.54469 141.50677) (xy 153.54469 141.51497) (xy 153.54469 141.52316)
			(xy 153.54469 141.53136) (xy 153.54469 141.53955) (xy 153.55289 141.53955) (xy 153.55289 141.54775)
			(xy 153.55289 141.55594) (xy 153.55289 141.56413) (xy 153.55289 141.57233) (xy 153.55289 141.58052)
			(xy 153.55289 141.58872) (xy 153.55289 141.59692) (xy 153.55289 141.60511) (xy 153.55289 141.6133)
			(xy 153.55289 141.6215) (xy 153.55289 141.62969) (xy 153.55289 141.63789) (xy 153.55289 141.64608)
			(xy 153.54469 141.64608) (xy 153.54469 141.65427) (xy 153.54469 141.66247) (xy 153.54469 141.67066)
			(xy 153.54469 141.67886) (xy 153.5365 141.67886) (xy 153.5365 141.68705) (xy 153.5365 141.69525)
			(xy 153.5365 141.70344) (xy 153.52831 141.70344) (xy 153.52831 141.71164) (xy 153.52831 141.71983)
			(xy 153.52011 141.71983) (xy 153.52011 141.72803) (xy 153.52011 141.73622) (xy 153.51192 141.73622)
			(xy 153.51192 141.74441) (xy 153.51192 141.75261) (xy 153.50372 141.75261) (xy 153.50372 141.7608)
			(xy 153.49553 141.7608) (xy 153.49553 141.769) (xy 153.49553 141.77719) (xy 153.48733 141.77719)
			(xy 153.48733 141.78539) (xy 153.47914 141.78539) (xy 153.47914 141.79358) (xy 153.47095 141.79358)
			(xy 153.47095 141.80177) (xy 153.46275 141.80177) (xy 153.46275 141.80997) (xy 153.45455 141.80997)
			(xy 153.45455 141.81816) (xy 153.44636 141.81816) (xy 153.44636 141.82636) (xy 153.43816 141.82636)
			(xy 153.43816 141.83456) (xy 153.42997 141.83456) (xy 153.42997 141.84275) (xy 153.41358 141.84275)
			(xy 153.41358 141.85094) (xy 153.40539 141.85094) (xy 153.40539 141.85914) (xy 153.389 141.85914)
			(xy 153.389 141.86733) (xy 153.37261 141.86733) (xy 153.37261 141.87553) (xy 153.34803 141.87553)
			(xy 153.34803 141.88372) (xy 153.32344 141.88372) (xy 153.32344 141.89192) (xy 153.27428 141.89192)
			(xy 153.27428 141.90011) (xy 153.21691 141.90011) (xy 153.21691 141.89192) (xy 153.16775 141.89192)
			(xy 153.16775 141.88372) (xy 153.14316 141.88372) (xy 153.14316 141.87553) (xy 153.12677 141.87553)
			(xy 153.12677 141.86733) (xy 153.10219 141.86733) (xy 153.10219 141.85914) (xy 153.094 141.85914)
			(xy 153.094 141.85094) (xy 153.07761 141.85094) (xy 153.07761 141.84275) (xy 153.06941 141.84275)
			(xy 153.06941 141.83456) (xy 153.05302 141.83456) (xy 153.05302 141.82636) (xy 153.04483 141.82636)
			(xy 153.04483 141.81816) (xy 153.03664 141.81816) (xy 153.03664 141.80997) (xy 153.02844 141.80997)
			(xy 153.02844 141.80177) (xy 153.02025 141.80177) (xy 153.02025 141.79358) (xy 153.01205 141.79358)
			(xy 153.01205 141.78539) (xy 153.00386 141.78539) (xy 153.00386 141.77719) (xy 152.99566 141.77719)
			(xy 152.99566 141.769) (xy 152.99566 141.7608) (xy 152.98747 141.7608) (xy 152.98747 141.75261) (xy 152.98747 141.74441)
			(xy 152.97927 141.74441) (xy 152.97927 141.73622) (xy 152.97108 141.73622) (xy 152.97108 141.72803)
			(xy 152.97108 141.71983) (xy 152.96288 141.71983) (xy 152.96288 141.71164) (xy 152.96288 141.70344)
			(xy 152.96288 141.69525) (xy 152.95469 141.69525) (xy 152.95469 141.68705) (xy 152.95469 141.67886)
			(xy 152.95469 141.67066) (xy 152.9465 141.67066) (xy 152.9465 141.66247) (xy 152.9465 141.65427)
			(xy 152.9465 141.64608) (xy 152.9465 141.63789) (xy 152.9465 141.62969) (xy 152.9383 141.62969) (xy 152.9383 141.6215)
			(xy 152.9383 141.6133) (xy 152.9383 141.60511) (xy 152.9383 141.59692) (xy 152.9383 141.58872) (xy 152.9383 141.58052)
			(xy 152.9383 141.57233) (xy 152.9383 141.56413) (xy 152.9383 141.55594) (xy 152.9383 141.54775) (xy 152.9465 141.54775)
			(xy 152.9465 141.53955) (xy 152.9465 141.53136) (xy 152.9465 141.52316) (xy 152.9465 141.51497) (xy 152.9465 141.50677)
			(xy 152.95469 141.50677) (xy 152.95469 141.49858) (xy 152.95469 141.49039) (xy 152.95469 141.48219)
			(xy 152.96288 141.48219) (xy 152.96288 141.474) (xy 152.96288 141.4658) (xy 152.97108 141.4658) (xy 152.97108 141.45761)
			(xy 152.97108 141.44941) (xy 152.97927 141.44941) (xy 152.97927 141.44122) (xy 152.97927 141.43302)
			(xy 152.98747 141.43302) (xy 152.98747 141.42483) (xy 152.98747 141.41663) (xy 152.99566 141.41663)
			(xy 152.99566 141.40844) (xy 153.00386 141.40844) (xy 153.00386 141.40025) (xy 153.01205 141.40025)
			(xy 153.01205 141.39205) (xy 153.01205 141.38386) (xy 153.02025 141.38386) (xy 153.02025 141.37566)
			(xy 153.02844 141.37566) (xy 153.02844 141.36747) (xy 153.03664 141.36747) (xy 153.03664 141.35927)
			(xy 153.05302 141.35927) (xy 153.05302 141.35108) (xy 153.06122 141.35108) (xy 153.06122 141.34289)
			(xy 153.06941 141.34289) (xy 153.06941 141.33469) (xy 153.0858 141.33469) (xy 153.0858 141.32649)
			(xy 153.094 141.32649) (xy 153.094 141.3183) (xy 153.11039 141.3183) (xy 153.11039 141.31011) (xy 153.13497 141.31011)
			(xy 153.13497 141.30191) (xy 153.15136 141.30191) (xy 153.15136 141.29372) (xy 153.18414 141.29372)
			(xy 153.18414 141.28552) (xy 153.30705 141.28552)
		)
		(stroke
			(width 0)
			(type default)
		)
		(fill yes)
		(layer "F.Cu")
	)
	(gr_poly
		(pts
			(xy 165.72171 137.86842) (xy 165.80366 137.86842) (xy 165.80366 137.87661) (xy 165.84463 137.87661)
			(xy 165.84463 137.88481) (xy 165.87741 137.88481) (xy 165.87741 137.893) (xy 165.8938 137.893) (xy 165.8938 137.9012)
			(xy 165.91838 137.9012) (xy 165.91838 137.90939) (xy 165.93477 137.90939) (xy 165.93477 137.91759)
			(xy 165.95935 137.91759) (xy 165.95935 137.92578) (xy 165.96755 137.92578) (xy 165.96755 137.93397)
			(xy 165.98394 137.93397) (xy 165.98394 137.94217) (xy 166.00032 137.94217) (xy 166.00032 137.95036)
			(xy 166.00852 137.95036) (xy 166.00852 137.95856) (xy 166.02491 137.95856) (xy 166.02491 137.96675)
			(xy 166.0331 137.96675) (xy 166.0331 137.97495) (xy 166.04949 137.97495) (xy 166.04949 137.98314)
			(xy 166.05769 137.98314) (xy 166.05769 137.99134) (xy 166.06588 137.99134) (xy 166.06588 137.99953)
			(xy 166.07407 137.99953) (xy 166.07407 138.00773) (xy 166.08227 138.00773) (xy 166.08227 138.01592)
			(xy 166.09046 138.01592) (xy 166.09046 138.02411) (xy 166.09866 138.02411) (xy 166.09866 138.03231)
			(xy 166.10685 138.03231) (xy 166.10685 138.0405) (xy 166.11504 138.0405) (xy 166.11504 138.0487)
			(xy 166.12324 138.0487) (xy 166.12324 138.05689) (xy 166.13144 138.05689) (xy 166.13144 138.06509)
			(xy 166.13963 138.06509) (xy 166.13963 138.07328) (xy 166.13963 138.08147) (xy 166.14783 138.08147)
			(xy 166.14783 138.08967) (xy 166.15602 138.08967) (xy 166.15602 138.09786) (xy 166.15602 138.10606)
			(xy 166.16421 138.10606) (xy 166.16421 138.11425) (xy 166.17241 138.11425) (xy 166.17241 138.12245)
			(xy 166.17241 138.13064) (xy 166.1806 138.13064) (xy 166.1806 138.13884) (xy 166.1806 138.14703)
			(xy 166.1888 138.14703) (xy 166.1888 138.15523) (xy 166.19699 138.15523) (xy 166.19699 138.16342)
			(xy 166.19699 138.17162) (xy 166.20519 138.17162) (xy 166.20519 138.17981) (xy 166.20519 138.188)
			(xy 166.20519 138.1962) (xy 166.21338 138.1962) (xy 166.21338 138.20439) (xy 166.21338 138.21259)
			(xy 166.22158 138.21259) (xy 166.22158 138.22078) (xy 166.22158 138.22898) (xy 166.22158 138.23717)
			(xy 166.22977 138.23717) (xy 166.22977 138.24537) (xy 166.22977 138.25356) (xy 166.22977 138.26175)
			(xy 166.22977 138.26995) (xy 166.23796 138.26995) (xy 166.23796 138.27814) (xy 166.23796 138.28634)
			(xy 166.23796 138.29453) (xy 166.23796 138.30273) (xy 166.24616 138.30273) (xy 166.24616 138.31092)
			(xy 166.24616 138.31911) (xy 166.24616 138.32731) (xy 166.24616 138.3355) (xy 166.24616 138.3437)
			(xy 166.24616 138.35189) (xy 166.24616 138.36009) (xy 166.24616 138.36828) (xy 166.24616 138.37648)
			(xy 166.24616 138.38467) (xy 166.25435 138.38467) (xy 166.25435 138.39287) (xy 166.25435 138.40106)
			(xy 166.25435 138.40926) (xy 166.25435 138.41745) (xy 166.24616 138.41745) (xy 166.24616 138.42564)
			(xy 166.24616 138.43384) (xy 166.24616 138.44203) (xy 166.24616 138.45023) (xy 166.24616 138.45842)
			(xy 166.24616 138.46662) (xy 166.24616 138.47481) (xy 166.24616 138.48301) (xy 166.24616 138.4912)
			(xy 166.23796 138.4912) (xy 166.23796 138.4994) (xy 166.23796 138.50759) (xy 166.23796 138.51578)
			(xy 166.23796 138.52398) (xy 166.23796 138.53217) (xy 166.22977 138.53217) (xy 166.22977 138.54037)
			(xy 166.22977 138.54856) (xy 166.22977 138.55675) (xy 166.22158 138.55675) (xy 166.22158 138.56495)
			(xy 166.22158 138.57315) (xy 166.22158 138.58134) (xy 166.21338 138.58134) (xy 166.21338 138.58954)
			(xy 166.21338 138.59773) (xy 166.21338 138.60592) (xy 166.20519 138.60592) (xy 166.20519 138.61412)
			(xy 166.20519 138.62231) (xy 166.19699 138.62231) (xy 166.19699 138.63051) (xy 166.19699 138.6387)
			(xy 166.1888 138.6387) (xy 166.1888 138.6469) (xy 166.1888 138.65509) (xy 166.1806 138.65509) (xy 166.1806 138.66328)
			(xy 166.1806 138.67148) (xy 166.17241 138.67148) (xy 166.17241 138.67967) (xy 166.17241 138.68787)
			(xy 166.16421 138.68787) (xy 166.16421 138.69607) (xy 166.15602 138.69607) (xy 166.15602 138.70426)
			(xy 166.15602 138.71245) (xy 166.14783 138.71245) (xy 166.14783 138.72065) (xy 166.13963 138.72065)
			(xy 166.13963 138.72884) (xy 166.13144 138.72884) (xy 166.13144 138.73704) (xy 166.13144 138.74523)
			(xy 166.12324 138.74523) (xy 166.12324 138.75342) (xy 166.11504 138.75342) (xy 166.11504 138.76162)
			(xy 166.10685 138.76162) (xy 166.10685 138.76981) (xy 166.09866 138.76981) (xy 166.09866 138.77801)
			(xy 166.09046 138.77801) (xy 166.09046 138.7862) (xy 166.08227 138.7862) (xy 166.08227 138.7944)
			(xy 166.07407 138.7944) (xy 166.07407 138.80259) (xy 166.06588 138.80259) (xy 166.06588 138.81078)
			(xy 166.04949 138.81078) (xy 166.04949 138.81898) (xy 166.0413 138.81898) (xy 166.0413 138.82718)
			(xy 166.0331 138.82718) (xy 166.0331 138.83537) (xy 166.02491 138.83537) (xy 166.02491 138.84356)
			(xy 166.00852 138.84356) (xy 166.00852 138.85176) (xy 166.00032 138.85176) (xy 166.00032 138.85995)
			(xy 165.98394 138.85995) (xy 165.98394 138.86815) (xy 165.96755 138.86815) (xy 165.96755 138.87634)
			(xy 165.95116 138.87634) (xy 165.95116 138.88454) (xy 165.93477 138.88454) (xy 165.93477 138.89273)
			(xy 165.91838 138.89273) (xy 165.91838 138.90092) (xy 165.8938 138.90092) (xy 165.8938 138.90912)
			(xy 165.86921 138.90912) (xy 165.86921 138.91731) (xy 165.83643 138.91731) (xy 165.83643 138.92551)
			(xy 165.79546 138.92551) (xy 165.79546 138.9337) (xy 165.0006 138.9337) (xy 165.0006 138.92551) (xy 164.95962 138.92551)
			(xy 164.95962 138.91731) (xy 164.93504 138.91731) (xy 164.93504 138.90912) (xy 164.91046 138.90912)
			(xy 164.91046 138.90092) (xy 164.88587 138.90092) (xy 164.88587 138.89273) (xy 164.86948 138.89273)
			(xy 164.86948 138.88454) (xy 164.8449 138.88454) (xy 164.8449 138.87634) (xy 164.83671 138.87634)
			(xy 164.83671 138.86815) (xy 164.82032 138.86815) (xy 164.82032 138.85995) (xy 164.80393 138.85995)
			(xy 164.80393 138.85176) (xy 164.79573 138.85176) (xy 164.79573 138.84356) (xy 164.77934 138.84356)
			(xy 164.77934 138.83537) (xy 164.77115 138.83537) (xy 164.77115 138.82718) (xy 164.75476 138.82718)
			(xy 164.75476 138.81898) (xy 164.74657 138.81898) (xy 164.74657 138.81078) (xy 164.73837 138.81078)
			(xy 164.73837 138.80259) (xy 164.73018 138.80259) (xy 164.73018 138.7944) (xy 164.72198 138.7944)
			(xy 164.72198 138.7862) (xy 164.71379 138.7862) (xy 164.71379 138.77801) (xy 164.70559 138.77801)
			(xy 164.70559 138.76981) (xy 164.6974 138.76981) (xy 164.6974 138.76162) (xy 164.68921 138.76162)
			(xy 164.68921 138.75342) (xy 164.68101 138.75342) (xy 164.68101 138.74523) (xy 164.67282 138.74523)
			(xy 164.67282 138.73704) (xy 164.66462 138.73704) (xy 164.66462 138.72884) (xy 164.66462 138.72065)
			(xy 164.65643 138.72065) (xy 164.65643 138.71245) (xy 164.64823 138.71245) (xy 164.64823 138.70426)
			(xy 164.64004 138.70426) (xy 164.64004 138.69607) (xy 164.64004 138.68787) (xy 164.63184 138.68787)
			(xy 164.63184 138.67967) (xy 164.63184 138.67148) (xy 164.62365 138.67148) (xy 164.62365 138.66328)
			(xy 164.61545 138.66328) (xy 164.61545 138.65509) (xy 164.61545 138.6469) (xy 164.60726 138.6469)
			(xy 164.60726 138.6387) (xy 164.60726 138.63051) (xy 164.59906 138.63051) (xy 164.59906 138.62231)
			(xy 164.59906 138.61412) (xy 164.59087 138.61412) (xy 164.59087 138.60592) (xy 164.59087 138.59773)
			(xy 164.59087 138.58954) (xy 164.58268 138.58954) (xy 164.58268 138.58134) (xy 164.58268 138.57315)
			(xy 164.58268 138.56495) (xy 164.57448 138.56495) (xy 164.57448 138.55675) (xy 164.57448 138.54856)
			(xy 164.57448 138.54037) (xy 164.56629 138.54037) (xy 164.56629 138.53217) (xy 164.56629 138.52398)
			(xy 164.56629 138.51578) (xy 164.56629 138.50759) (xy 164.56629 138.4994) (xy 164.55809 138.4994)
			(xy 164.55809 138.4912) (xy 164.55809 138.48301) (xy 164.55809 138.47481) (xy 164.55809 138.46662)
			(xy 164.55809 138.45842) (xy 164.5499 138.45842) (xy 164.5499 138.45023) (xy 164.5499 138.44203)
			(xy 164.5499 138.43384) (xy 164.5499 138.42564) (xy 164.5499 138.41745) (xy 164.5499 138.40926) (xy 164.5499 138.40106)
			(xy 164.5499 138.39287) (xy 164.5499 138.38467) (xy 164.5499 138.37648) (xy 164.5499 138.36828) (xy 164.5499 138.36009)
			(xy 164.5499 138.35189) (xy 164.55809 138.35189) (xy 164.55809 138.3437) (xy 164.55809 138.3355)
			(xy 164.55809 138.32731) (xy 164.55809 138.31911) (xy 164.55809 138.31092) (xy 164.55809 138.30273)
			(xy 164.55809 138.29453) (xy 164.56629 138.29453) (xy 164.56629 138.28634) (xy 164.56629 138.27814)
			(xy 164.56629 138.26995) (xy 164.56629 138.26175) (xy 164.57448 138.26175) (xy 164.57448 138.25356)
			(xy 164.57448 138.24537) (xy 164.57448 138.23717) (xy 164.57448 138.22898) (xy 164.58268 138.22898)
			(xy 164.58268 138.22078) (xy 164.58268 138.21259) (xy 164.59087 138.21259) (xy 164.59087 138.20439)
			(xy 164.59087 138.1962) (xy 164.59087 138.188) (xy 164.59906 138.188) (xy 164.59906 138.17981) (xy 164.59906 138.17162)
			(xy 164.60726 138.17162) (xy 164.60726 138.16342) (xy 164.60726 138.15523) (xy 164.61545 138.15523)
			(xy 164.61545 138.14703) (xy 164.61545 138.13884) (xy 164.62365 138.13884) (xy 164.62365 138.13064)
			(xy 164.62365 138.12245) (xy 164.63184 138.12245) (xy 164.63184 138.11425) (xy 164.64004 138.11425)
			(xy 164.64004 138.10606) (xy 164.64004 138.09786) (xy 164.64823 138.09786) (xy 164.64823 138.08967)
			(xy 164.65643 138.08967) (xy 164.65643 138.08147) (xy 164.65643 138.07328) (xy 164.66462 138.07328)
			(xy 164.66462 138.06509) (xy 164.67282 138.06509) (xy 164.67282 138.05689) (xy 164.68101 138.05689)
			(xy 164.68101 138.0487) (xy 164.68921 138.0487) (xy 164.68921 138.0405) (xy 164.6974 138.0405) (xy 164.6974 138.03231)
			(xy 164.70559 138.03231) (xy 164.70559 138.02411) (xy 164.71379 138.02411) (xy 164.71379 138.01592)
			(xy 164.72198 138.01592) (xy 164.72198 138.00773) (xy 164.73018 138.00773) (xy 164.73018 137.99953)
			(xy 164.73837 137.99953) (xy 164.73837 137.99134) (xy 164.74657 137.99134) (xy 164.74657 137.98314)
			(xy 164.75476 137.98314) (xy 164.75476 137.97495) (xy 164.76296 137.97495) (xy 164.76296 137.96675)
			(xy 164.77934 137.96675) (xy 164.77934 137.95856) (xy 164.78754 137.95856) (xy 164.78754 137.95036)
			(xy 164.80393 137.95036) (xy 164.80393 137.94217) (xy 164.81212 137.94217) (xy 164.81212 137.93397)
			(xy 164.82851 137.93397) (xy 164.82851 137.92578) (xy 164.8449 137.92578) (xy 164.8449 137.91759)
			(xy 164.86129 137.91759) (xy 164.86129 137.90939) (xy 164.88587 137.90939) (xy 164.88587 137.9012)
			(xy 164.90226 137.9012) (xy 164.90226 137.893) (xy 164.92685 137.893) (xy 164.92685 137.88481) (xy 164.95962 137.88481)
			(xy 164.95962 137.87661) (xy 164.9924 137.87661) (xy 164.9924 137.86842) (xy 165.08254 137.86842)
			(xy 165.08254 137.86023) (xy 165.70532 137.86023) (xy 165.70532 137.86842) (xy 165.71352 137.86842)
			(xy 165.71352 137.86023) (xy 165.72171 137.86023)
		)
		(stroke
			(width 0)
			(type default)
		)
		(fill yes)
		(layer "F.Cu")
	)
	(gr_poly
		(pts
			(xy 167.60644 142.14594) (xy 167.65561 142.14594) (xy 167.65561 142.15414) (xy 167.68839 142.15414)
			(xy 167.68839 142.16233) (xy 167.71297 142.16233) (xy 167.71297 142.17053) (xy 167.73756 142.17053)
			(xy 167.73756 142.17872) (xy 167.75394 142.17872) (xy 167.75394 142.18692) (xy 167.77853 142.18692)
			(xy 167.77853 142.19511) (xy 167.79492 142.19511) (xy 167.79492 142.20331) (xy 167.80311 142.20331)
			(xy 167.80311 142.2115) (xy 167.8195 142.2115) (xy 167.8195 142.21969) (xy 167.83589 142.21969) (xy 167.83589 142.22789)
			(xy 167.84409 142.22789) (xy 167.84409 142.23608) (xy 167.86047 142.23608) (xy 167.86047 142.24428)
			(xy 167.86867 142.24428) (xy 167.86867 142.25247) (xy 167.87686 142.25247) (xy 167.87686 142.26067)
			(xy 167.88506 142.26067) (xy 167.88506 142.26886) (xy 167.90145 142.26886) (xy 167.90145 142.27706)
			(xy 167.90964 142.27706) (xy 167.90964 142.28525) (xy 167.91784 142.28525) (xy 167.91784 142.29344)
			(xy 167.92603 142.29344) (xy 167.92603 142.30164) (xy 167.93423 142.30164) (xy 167.93423 142.30984)
			(xy 167.94242 142.30984) (xy 167.94242 142.31803) (xy 167.95061 142.31803) (xy 167.95061 142.32622)
			(xy 167.95881 142.32622) (xy 167.95881 142.33442) (xy 167.95881 142.34261) (xy 167.967 142.34261)
			(xy 167.967 142.35081) (xy 167.9752 142.35081) (xy 167.9752 142.359) (xy 167.98339 142.359) (xy 167.98339 142.3672)
			(xy 167.98339 142.37539) (xy 167.99158 142.37539) (xy 167.99158 142.38359) (xy 167.99978 142.38359)
			(xy 167.99978 142.39178) (xy 167.99978 142.39997) (xy 168.00798 142.39997) (xy 168.00798 142.40817)
			(xy 168.00798 142.41636) (xy 168.01617 142.41636) (xy 168.01617 142.42456) (xy 168.02436 142.42456)
			(xy 168.02436 142.43275) (xy 168.02436 142.44095) (xy 168.03256 142.44095) (xy 168.03256 142.44914)
			(xy 168.03256 142.45734) (xy 168.03256 142.46553) (xy 168.04075 142.46553) (xy 168.04075 142.47372)
			(xy 168.04075 142.48192) (xy 168.04895 142.48192) (xy 168.04895 142.49011) (xy 168.04895 142.49831)
			(xy 168.04895 142.5065) (xy 168.05714 142.5065) (xy 168.05714 142.5147) (xy 168.05714 142.52289)
			(xy 168.05714 142.53108) (xy 168.06534 142.53108) (xy 168.06534 142.53928) (xy 168.06534 142.54747)
			(xy 168.06534 142.55567) (xy 168.06534 142.56387) (xy 168.07353 142.56387) (xy 168.07353 142.57206)
			(xy 168.07353 142.58025) (xy 168.07353 142.58845) (xy 168.07353 142.59664) (xy 168.07353 142.60484)
			(xy 168.07353 142.61303) (xy 168.08173 142.61303) (xy 168.08173 142.62123) (xy 168.08173 142.62942)
			(xy 168.08173 142.63761) (xy 168.08173 142.64581) (xy 168.08173 142.654) (xy 168.08173 142.6622)
			(xy 168.08173 142.67039) (xy 168.08173 142.67859) (xy 168.08173 142.68678) (xy 168.08173 142.69498)
			(xy 168.08173 142.70317) (xy 168.08173 142.71136) (xy 168.08173 142.71956) (xy 168.08173 142.72775)
			(xy 168.08173 142.73595) (xy 168.07353 142.73595) (xy 168.07353 142.74414) (xy 168.07353 142.75234)
			(xy 168.07353 142.76053) (xy 168.07353 142.76873) (xy 168.07353 142.77692) (xy 168.07353 142.78511)
			(xy 168.06534 142.78511) (xy 168.06534 142.79331) (xy 168.06534 142.8015) (xy 168.06534 142.8097)
			(xy 168.06534 142.81789) (xy 168.05714 142.81789) (xy 168.05714 142.82609) (xy 168.05714 142.83428)
			(xy 168.05714 142.84248) (xy 168.04895 142.84248) (xy 168.04895 142.85067) (xy 168.04895 142.85887)
			(xy 168.04895 142.86706) (xy 168.04075 142.86706) (xy 168.04075 142.87525) (xy 168.04075 142.88345)
			(xy 168.03256 142.88345) (xy 168.03256 142.89164) (xy 168.03256 142.89984) (xy 168.02436 142.89984)
			(xy 168.02436 142.90803) (xy 168.02436 142.91623) (xy 168.01617 142.91623) (xy 168.01617 142.92442)
			(xy 168.01617 142.93262) (xy 168.00798 142.93262) (xy 168.00798 142.94081) (xy 168.00798 142.949)
			(xy 167.99978 142.949) (xy 167.99978 142.9572) (xy 167.99158 142.9572) (xy 167.99158 142.96539) (xy 167.99158 142.97359)
			(xy 167.98339 142.97359) (xy 167.98339 142.98178) (xy 167.9752 142.98178) (xy 167.9752 142.98998)
			(xy 167.9752 142.99817) (xy 167.967 142.99817) (xy 167.967 143.00637) (xy 167.95881 143.00637) (xy 167.95881 143.01456)
			(xy 167.95061 143.01456) (xy 167.95061 143.02275) (xy 167.94242 143.02275) (xy 167.94242 143.03095)
			(xy 167.93423 143.03095) (xy 167.93423 143.03915) (xy 167.92603 143.03915) (xy 167.92603 143.04734)
			(xy 167.91784 143.04734) (xy 167.91784 143.05553) (xy 167.90964 143.05553) (xy 167.90964 143.06373)
			(xy 167.90145 143.06373) (xy 167.90145 143.07192) (xy 167.89325 143.07192) (xy 167.89325 143.08012)
			(xy 167.88506 143.08012) (xy 167.88506 143.08831) (xy 167.87686 143.08831) (xy 167.87686 143.09651)
			(xy 167.86047 143.09651) (xy 167.86047 143.1047) (xy 167.85228 143.1047) (xy 167.85228 143.1129)
			(xy 167.84409 143.1129) (xy 167.84409 143.12109) (xy 167.8277 143.12109) (xy 167.8277 143.12928)
			(xy 167.81131 143.12928) (xy 167.81131 143.13748) (xy 167.80311 143.13748) (xy 167.80311 143.14567)
			(xy 167.78672 143.14567) (xy 167.78672 143.15387) (xy 167.77033 143.15387) (xy 167.77033 143.16206)
			(xy 167.74575 143.16206) (xy 167.74575 143.17026) (xy 167.72936 143.17026) (xy 167.72936 143.17845)
			(xy 167.70478 143.17845) (xy 167.70478 143.18664) (xy 167.672 143.18664) (xy 167.672 143.19484) (xy 167.63103 143.19484)
			(xy 167.63103 143.20303) (xy 167.58186 143.20303) (xy 167.58186 143.21123) (xy 167.57367 143.21123)
			(xy 167.57367 143.20303) (xy 167.56547 143.20303) (xy 167.56547 143.21123) (xy 167.55728 143.21123)
			(xy 167.55728 143.20303) (xy 167.54908 143.20303) (xy 167.54908 143.21123) (xy 167.49172 143.21123)
			(xy 167.49172 143.20303) (xy 167.43436 143.20303) (xy 167.43436 143.19484) (xy 167.39339 143.19484)
			(xy 167.39339 143.18664) (xy 167.3688 143.18664) (xy 167.3688 143.17845) (xy 167.34422 143.17845)
			(xy 167.34422 143.17026) (xy 167.31964 143.17026) (xy 167.31964 143.16206) (xy 167.30325 143.16206)
			(xy 167.30325 143.15387) (xy 167.28686 143.15387) (xy 167.28686 143.14567) (xy 167.27047 143.14567)
			(xy 167.27047 143.13748) (xy 167.25408 143.13748) (xy 167.25408 143.12928) (xy 167.24589 143.12928)
			(xy 167.24589 143.12109) (xy 167.2295 143.12109) (xy 167.2295 143.1129) (xy 167.2213 143.1129) (xy 167.2213 143.1047)
			(xy 167.20492 143.1047) (xy 167.20492 143.09651) (xy 167.19672 143.09651) (xy 167.19672 143.08831)
			(xy 167.18853 143.08831) (xy 167.18853 143.08012) (xy 167.18033 143.08012) (xy 167.18033 143.07192)
			(xy 167.16394 143.07192) (xy 167.16394 143.06373) (xy 167.15575 143.06373) (xy 167.15575 143.05553)
			(xy 167.14755 143.05553) (xy 167.14755 143.04734) (xy 167.13936 143.04734) (xy 167.13936 143.03915)
			(xy 167.13116 143.03915) (xy 167.13116 143.03095) (xy 167.12297 143.03095) (xy 167.12297 143.02275)
			(xy 167.12297 143.01456) (xy 167.11478 143.01456) (xy 167.11478 143.00637) (xy 167.10658 143.00637)
			(xy 167.10658 142.99817) (xy 167.09839 142.99817) (xy 167.09839 142.98998) (xy 167.09019 142.98998)
			(xy 167.09019 142.98178) (xy 167.09019 142.97359) (xy 167.082 142.97359) (xy 167.082 142.96539) (xy 167.0738 142.96539)
			(xy 167.0738 142.9572) (xy 167.0738 142.949) (xy 167.06561 142.949) (xy 167.06561 142.94081) (xy 167.06561 142.93262)
			(xy 167.05741 142.93262) (xy 167.05741 142.92442) (xy 167.04922 142.92442) (xy 167.04922 142.91623)
			(xy 167.04922 142.90803) (xy 167.04102 142.90803) (xy 167.04102 142.89984) (xy 167.04102 142.89164)
			(xy 167.03283 142.89164) (xy 167.03283 142.88345) (xy 167.03283 142.87525) (xy 167.03283 142.86706)
			(xy 167.02464 142.86706) (xy 167.02464 142.85887) (xy 167.02464 142.85067) (xy 167.01644 142.85067)
			(xy 167.01644 142.84248) (xy 167.01644 142.83428) (xy 167.01644 142.82609) (xy 167.00825 142.82609)
			(xy 167.00825 142.81789) (xy 167.00825 142.8097) (xy 167.00825 142.8015) (xy 167.00825 142.79331)
			(xy 167.00005 142.79331) (xy 167.00005 142.78511) (xy 167.00005 142.77692) (xy 167.00005 142.76873)
			(xy 167.00005 142.76053) (xy 167.00005 142.75234) (xy 166.99186 142.75234) (xy 166.99186 142.74414)
			(xy 166.99186 142.73595) (xy 166.99186 142.72775) (xy 166.99186 142.71956) (xy 166.99186 142.71136)
			(xy 166.99186 142.70317) (xy 166.99186 142.69498) (xy 166.99186 142.68678) (xy 166.99186 142.67859)
			(xy 166.99186 142.67039) (xy 166.99186 142.6622) (xy 166.99186 142.654) (xy 166.99186 142.64581)
			(xy 166.99186 142.63761) (xy 166.99186 142.62942) (xy 166.99186 142.62123) (xy 166.99186 142.61303)
			(xy 166.99186 142.60484) (xy 166.99186 142.59664) (xy 167.00005 142.59664) (xy 167.00005 142.58845)
			(xy 167.00005 142.58025) (xy 167.00005 142.57206) (xy 167.00005 142.56387) (xy 167.00005 142.55567)
			(xy 167.00825 142.55567) (xy 167.00825 142.54747) (xy 167.00825 142.53928) (xy 167.00825 142.53108)
			(xy 167.00825 142.52289) (xy 167.01644 142.52289) (xy 167.01644 142.5147) (xy 167.01644 142.5065)
			(xy 167.01644 142.49831) (xy 167.02464 142.49831) (xy 167.02464 142.49011) (xy 167.02464 142.48192)
			(xy 167.02464 142.47372) (xy 167.03283 142.47372) (xy 167.03283 142.46553) (xy 167.03283 142.45734)
			(xy 167.04102 142.45734) (xy 167.04102 142.44914) (xy 167.04102 142.44095) (xy 167.04922 142.44095)
			(xy 167.04922 142.43275) (xy 167.04922 142.42456) (xy 167.05741 142.42456) (xy 167.05741 142.41636)
			(xy 167.05741 142.40817) (xy 167.06561 142.40817) (xy 167.06561 142.39997) (xy 167.06561 142.39178)
			(xy 167.0738 142.39178) (xy 167.0738 142.38359) (xy 167.082 142.38359) (xy 167.082 142.37539) (xy 167.082 142.3672)
			(xy 167.09019 142.3672) (xy 167.09019 142.359) (xy 167.09839 142.359) (xy 167.09839 142.35081) (xy 167.10658 142.35081)
			(xy 167.10658 142.34261) (xy 167.10658 142.33442) (xy 167.11478 142.33442) (xy 167.11478 142.32622)
			(xy 167.12297 142.32622) (xy 167.12297 142.31803) (xy 167.13116 142.31803) (xy 167.13116 142.30984)
			(xy 167.13936 142.30984) (xy 167.13936 142.30164) (xy 167.14755 142.30164) (xy 167.14755 142.29344)
			(xy 167.15575 142.29344) (xy 167.15575 142.28525) (xy 167.16394 142.28525) (xy 167.16394 142.27706)
			(xy 167.17214 142.27706) (xy 167.17214 142.26886) (xy 167.18033 142.26886) (xy 167.18033 142.26067)
			(xy 167.18853 142.26067) (xy 167.18853 142.25247) (xy 167.20492 142.25247) (xy 167.20492 142.24428)
			(xy 167.21311 142.24428) (xy 167.21311 142.23608) (xy 167.2295 142.23608) (xy 167.2295 142.22789)
			(xy 167.23769 142.22789) (xy 167.23769 142.21969) (xy 167.25408 142.21969) (xy 167.25408 142.2115)
			(xy 167.26227 142.2115) (xy 167.26227 142.20331) (xy 167.27867 142.20331) (xy 167.27867 142.19511)
			(xy 167.29506 142.19511) (xy 167.29506 142.18692) (xy 167.31144 142.18692) (xy 167.31144 142.17872)
			(xy 167.33603 142.17872) (xy 167.33603 142.17053) (xy 167.36061 142.17053) (xy 167.36061 142.16233)
			(xy 167.38519 142.16233) (xy 167.38519 142.15414) (xy 167.41797 142.15414) (xy 167.41797 142.14594)
			(xy 167.45894 142.14594) (xy 167.45894 142.13775) (xy 167.60644 142.13775)
		)
		(stroke
			(width 0)
			(type default)
		)
		(fill yes)
		(layer "F.Cu")
	)
	(gr_poly
		(pts
			(xy 152.11885 137.86842) (xy 152.2008 137.86842) (xy 152.2008 137.87661) (xy 152.23357 137.87661)
			(xy 152.23357 137.88481) (xy 152.26635 137.88481) (xy 152.26635 137.893) (xy 152.28274 137.893) (xy 152.28274 137.9012)
			(xy 152.30733 137.9012) (xy 152.30733 137.90939) (xy 152.32372 137.90939) (xy 152.32372 137.91759)
			(xy 152.3401 137.91759) (xy 152.3401 137.92578) (xy 152.35649 137.92578) (xy 152.35649 137.93397)
			(xy 152.37288 137.93397) (xy 152.37288 137.94217) (xy 152.38108 137.94217) (xy 152.38108 137.95036)
			(xy 152.39746 137.95036) (xy 152.39746 137.95856) (xy 152.40566 137.95856) (xy 152.40566 137.96675)
			(xy 152.41385 137.96675) (xy 152.41385 137.97495) (xy 152.43024 137.97495) (xy 152.43024 137.98314)
			(xy 152.43844 137.98314) (xy 152.43844 137.99134) (xy 152.44663 137.99134) (xy 152.44663 137.99953)
			(xy 152.45483 137.99953) (xy 152.45483 138.00773) (xy 152.46302 138.00773) (xy 152.46302 138.01592)
			(xy 152.47121 138.01592) (xy 152.47121 138.02411) (xy 152.47941 138.02411) (xy 152.47941 138.03231)
			(xy 152.4876 138.03231) (xy 152.4876 138.0405) (xy 152.4958 138.0405) (xy 152.4958 138.0487) (xy 152.4958 138.05689)
			(xy 152.504 138.05689) (xy 152.504 138.06509) (xy 152.51219 138.06509) (xy 152.51219 138.07328) (xy 152.52038 138.07328)
			(xy 152.52038 138.08147) (xy 152.52038 138.08967) (xy 152.52858 138.08967) (xy 152.52858 138.09786)
			(xy 152.53677 138.09786) (xy 152.53677 138.10606) (xy 152.53677 138.11425) (xy 152.54497 138.11425)
			(xy 152.54497 138.12245) (xy 152.54497 138.13064) (xy 152.55316 138.13064) (xy 152.55316 138.13884)
			(xy 152.55316 138.14703) (xy 152.56135 138.14703) (xy 152.56135 138.15523) (xy 152.56135 138.16342)
			(xy 152.56955 138.16342) (xy 152.56955 138.17162) (xy 152.56955 138.17981) (xy 152.56955 138.188)
			(xy 152.57774 138.188) (xy 152.57774 138.1962) (xy 152.57774 138.20439) (xy 152.58594 138.20439)
			(xy 152.58594 138.21259) (xy 152.58594 138.22078) (xy 152.58594 138.22898) (xy 152.58594 138.23717)
			(xy 152.59413 138.23717) (xy 152.59413 138.24537) (xy 152.59413 138.25356) (xy 152.59413 138.26175)
			(xy 152.59413 138.26995) (xy 152.59413 138.27814) (xy 152.60233 138.27814) (xy 152.60233 138.28634)
			(xy 152.60233 138.29453) (xy 152.60233 138.30273) (xy 152.60233 138.31092) (xy 152.60233 138.31911)
			(xy 152.60233 138.32731) (xy 152.60233 138.3355) (xy 152.60233 138.3437) (xy 152.60233 138.35189)
			(xy 152.60233 138.36009) (xy 152.60233 138.36828) (xy 152.60233 138.37648) (xy 152.60233 138.38467)
			(xy 152.60233 138.39287) (xy 152.60233 138.40106) (xy 152.60233 138.40926) (xy 152.60233 138.41745)
			(xy 152.60233 138.42564) (xy 152.60233 138.43384) (xy 152.60233 138.44203) (xy 152.60233 138.45023)
			(xy 152.60233 138.45842) (xy 152.60233 138.46662) (xy 152.60233 138.47481) (xy 152.60233 138.48301)
			(xy 152.60233 138.4912) (xy 152.60233 138.4994) (xy 152.60233 138.50759) (xy 152.60233 138.51578)
			(xy 152.60233 138.52398) (xy 152.60233 138.53217) (xy 152.60233 138.54037) (xy 152.60233 138.54856)
			(xy 152.60233 138.55675) (xy 152.60233 138.56495) (xy 152.60233 138.57315) (xy 152.60233 138.58134)
			(xy 152.60233 138.58954) (xy 152.60233 138.59773) (xy 152.60233 138.60592) (xy 152.60233 138.61412)
			(xy 152.60233 138.62231) (xy 152.60233 138.63051) (xy 152.60233 138.6387) (xy 152.60233 138.6469)
			(xy 152.60233 138.65509) (xy 152.60233 138.66328) (xy 152.60233 138.67148) (xy 152.60233 138.67967)
			(xy 152.60233 138.68787) (xy 152.60233 138.69607) (xy 152.60233 138.70426) (xy 152.60233 138.71245)
			(xy 152.60233 138.72065) (xy 152.60233 138.72884) (xy 152.60233 138.73704) (xy 152.60233 138.74523)
			(xy 152.60233 138.75342) (xy 152.60233 138.76162) (xy 152.60233 138.76981) (xy 152.60233 138.77801)
			(xy 152.60233 138.7862) (xy 152.60233 138.7944) (xy 152.60233 138.80259) (xy 152.60233 138.81078)
			(xy 152.60233 138.81898) (xy 152.60233 138.82718) (xy 152.60233 138.83537) (xy 152.60233 138.84356)
			(xy 152.60233 138.85176) (xy 152.60233 138.85995) (xy 152.60233 138.86815) (xy 152.60233 138.87634)
			(xy 152.60233 138.88454) (xy 152.60233 138.89273) (xy 152.60233 138.90092) (xy 152.60233 138.90912)
			(xy 152.60233 138.91731) (xy 152.60233 138.92551) (xy 152.60233 138.9337) (xy 152.60233 138.9419)
			(xy 152.60233 138.95009) (xy 152.60233 138.95829) (xy 152.60233 138.96648) (xy 152.60233 138.97467)
			(xy 152.60233 138.98287) (xy 152.60233 138.99107) (xy 152.60233 138.99926) (xy 152.60233 139.00745)
			(xy 152.60233 139.01565) (xy 152.60233 139.02384) (xy 152.60233 139.03204) (xy 152.60233 139.04023)
			(xy 152.60233 139.04842) (xy 152.60233 139.05662) (xy 152.60233 139.06481) (xy 152.60233 139.07301)
			(xy 152.60233 139.0812) (xy 152.60233 139.0894) (xy 152.60233 139.09759) (xy 152.60233 139.10579)
			(xy 152.60233 139.11398) (xy 152.60233 139.12218) (xy 152.60233 139.13037) (xy 152.60233 139.13857)
			(xy 152.60233 139.14676) (xy 152.60233 139.15495) (xy 152.60233 139.16315) (xy 152.60233 139.17134)
			(xy 152.60233 139.17954) (xy 152.60233 139.18773) (xy 152.60233 139.19593) (xy 152.60233 139.20412)
			(xy 152.60233 139.21232) (xy 152.60233 139.22051) (xy 152.60233 139.22871) (xy 152.60233 139.2369)
			(xy 152.60233 139.24509) (xy 152.60233 139.25329) (xy 152.60233 139.26148) (xy 152.60233 139.26968)
			(xy 152.60233 139.27787) (xy 152.60233 139.28607) (xy 152.60233 139.29426) (xy 152.60233 139.30245)
			(xy 152.60233 139.31065) (xy 152.60233 139.31884) (xy 152.60233 139.32704) (xy 152.60233 139.33523)
			(xy 152.60233 139.34342) (xy 152.60233 139.35162) (xy 152.60233 139.35982) (xy 152.60233 139.36801)
			(xy 152.60233 139.37621) (xy 152.60233 139.3844) (xy 152.60233 139.39259) (xy 152.60233 139.40079)
			(xy 152.60233 139.40898) (xy 152.60233 139.41718) (xy 152.60233 139.42537) (xy 152.60233 139.43357)
			(xy 152.60233 139.44176) (xy 152.60233 139.44996) (xy 152.60233 139.45815) (xy 152.60233 139.46634)
			(xy 152.60233 139.47454) (xy 152.60233 139.48273) (xy 152.60233 139.49093) (xy 152.60233 139.49912)
			(xy 152.60233 139.50732) (xy 152.60233 139.51551) (xy 152.60233 139.52371) (xy 152.60233 139.5319)
			(xy 152.60233 139.54009) (xy 152.60233 139.54829) (xy 152.60233 139.55649) (xy 152.60233 139.56468)
			(xy 152.60233 139.57287) (xy 152.60233 139.58107) (xy 152.60233 139.58926) (xy 152.60233 139.59746)
			(xy 152.60233 139.60565) (xy 152.60233 139.61385) (xy 152.60233 139.62204) (xy 152.60233 139.63023)
			(xy 152.60233 139.63843) (xy 152.60233 139.64662) (xy 152.60233 139.65482) (xy 152.60233 139.66301)
			(xy 152.60233 139.67121) (xy 152.60233 139.6794) (xy 152.60233 139.6876) (xy 152.60233 139.69579)
			(xy 152.60233 139.70398) (xy 152.60233 139.71218) (xy 152.60233 139.72038) (xy 152.60233 139.72857)
			(xy 152.60233 139.73676) (xy 152.60233 139.74496) (xy 152.60233 139.75315) (xy 152.60233 139.76135)
			(xy 152.60233 139.76954) (xy 152.60233 139.77773) (xy 152.60233 139.78593) (xy 152.60233 139.79413)
			(xy 152.60233 139.80232) (xy 152.60233 139.81051) (xy 152.60233 139.81871) (xy 152.60233 139.8269)
			(xy 152.60233 139.8351) (xy 152.60233 139.84329) (xy 152.60233 139.85149) (xy 152.60233 139.85968)
			(xy 152.60233 139.86787) (xy 152.60233 139.87607) (xy 152.60233 139.88426) (xy 152.60233 139.89246)
			(xy 152.60233 139.90065) (xy 152.60233 139.90885) (xy 152.60233 139.91704) (xy 152.60233 139.92524)
			(xy 152.60233 139.93343) (xy 152.60233 139.94163) (xy 152.60233 139.94982) (xy 152.60233 139.95802)
			(xy 152.60233 139.96621) (xy 152.60233 139.9744) (xy 152.60233 139.9826) (xy 152.60233 139.99079)
			(xy 152.60233 139.99899) (xy 152.60233 140.00718) (xy 152.60233 140.01538) (xy 152.60233 140.02357)
			(xy 152.60233 140.03176) (xy 152.60233 140.03996) (xy 152.60233 140.04815) (xy 152.60233 140.05635)
			(xy 152.60233 140.06454) (xy 152.60233 140.07274) (xy 152.60233 140.08093) (xy 152.60233 140.08913)
			(xy 152.60233 140.09732) (xy 152.60233 140.10552) (xy 152.60233 140.11371) (xy 152.60233 140.1219)
			(xy 152.60233 140.1301) (xy 152.60233 140.1383) (xy 152.60233 140.14649) (xy 152.60233 140.15468)
			(xy 152.60233 140.16288) (xy 152.60233 140.17107) (xy 152.60233 140.17927) (xy 152.60233 140.18746)
			(xy 152.60233 140.19565) (xy 152.60233 140.20385) (xy 152.60233 140.21204) (xy 152.60233 140.22024)
			(xy 152.60233 140.22843) (xy 152.60233 140.23663) (xy 152.60233 140.24482) (xy 152.60233 140.25302)
			(xy 152.60233 140.26121) (xy 152.60233 140.2694) (xy 152.60233 140.2776) (xy 152.60233 140.28579)
			(xy 152.60233 140.29399) (xy 152.60233 140.30218) (xy 152.60233 140.31038) (xy 152.60233 140.31857)
			(xy 152.60233 140.32677) (xy 152.60233 140.33496) (xy 152.60233 140.34316) (xy 152.60233 140.35135)
			(xy 152.60233 140.35954) (xy 152.60233 140.36774) (xy 152.60233 140.37593) (xy 152.60233 140.38413)
			(xy 152.60233 140.39232) (xy 152.60233 140.40052) (xy 152.60233 140.40871) (xy 152.60233 140.41691)
			(xy 152.60233 140.4251) (xy 152.60233 140.4333) (xy 152.60233 140.44149) (xy 152.60233 140.44969)
			(xy 152.60233 140.45788) (xy 152.60233 140.46607) (xy 152.60233 140.47427) (xy 152.60233 140.48246)
			(xy 152.60233 140.49066) (xy 152.60233 140.49885) (xy 152.60233 140.50704) (xy 152.60233 140.51524)
			(xy 152.60233 140.52344) (xy 152.60233 140.53163) (xy 152.60233 140.53982) (xy 152.60233 140.54802)
			(xy 152.60233 140.55621) (xy 152.60233 140.56441) (xy 152.60233 140.5726) (xy 152.60233 140.5808)
			(xy 152.60233 140.58899) (xy 152.60233 140.59718) (xy 152.60233 140.60538) (xy 152.60233 140.61357)
			(xy 152.60233 140.62177) (xy 152.60233 140.62996) (xy 152.60233 140.63816) (xy 152.60233 140.64635)
			(xy 152.60233 140.65455) (xy 152.60233 140.66274) (xy 152.60233 140.67094) (xy 152.60233 140.67913)
			(xy 152.60233 140.68732) (xy 152.60233 140.69552) (xy 152.60233 140.70371) (xy 152.60233 140.71191)
			(xy 152.60233 140.7201) (xy 152.60233 140.7283) (xy 152.60233 140.73649) (xy 152.60233 140.74469)
			(xy 152.60233 140.75288) (xy 152.60233 140.76108) (xy 152.60233 140.76927) (xy 152.60233 140.77746)
			(xy 152.60233 140.78566) (xy 152.60233 140.79385) (xy 152.60233 140.80205) (xy 152.60233 140.81024)
			(xy 152.60233 140.81844) (xy 152.60233 140.82663) (xy 152.60233 140.83482) (xy 152.60233 140.84302)
			(xy 152.60233 140.85121) (xy 152.60233 140.85941) (xy 152.60233 140.86761) (xy 152.60233 140.8758)
			(xy 152.60233 140.88399) (xy 152.60233 140.89219) (xy 152.60233 140.90038) (xy 152.60233 140.90858)
			(xy 152.60233 140.91677) (xy 152.60233 140.92496) (xy 152.60233 140.93316) (xy 152.60233 140.94135)
			(xy 152.60233 140.94955) (xy 152.60233 140.95774) (xy 152.60233 140.96594) (xy 152.60233 140.97413)
			(xy 152.60233 140.98233) (xy 152.60233 140.99052) (xy 152.60233 140.99872) (xy 152.60233 141.00691)
			(xy 152.60233 141.0151) (xy 152.60233 141.0233) (xy 152.60233 141.03149) (xy 152.60233 141.03969)
			(xy 152.60233 141.04788) (xy 152.60233 141.05608) (xy 152.60233 141.06427) (xy 152.60233 141.07247)
			(xy 152.60233 141.08066) (xy 152.60233 141.08885) (xy 152.60233 141.09705) (xy 152.60233 141.10525)
			(xy 152.60233 141.11344) (xy 152.60233 141.12163) (xy 152.60233 141.12983) (xy 152.60233 141.13802)
			(xy 152.60233 141.14622) (xy 152.60233 141.15441) (xy 152.60233 141.16261) (xy 152.60233 141.1708)
			(xy 152.60233 141.179) (xy 152.60233 141.18719) (xy 152.60233 141.19538) (xy 152.60233 141.20358)
			(xy 152.60233 141.21177) (xy 152.60233 141.21997) (xy 152.60233 141.22816) (xy 152.60233 141.23636)
			(xy 152.60233 141.24455) (xy 152.60233 141.25274) (xy 152.60233 141.26094) (xy 152.60233 141.26913)
			(xy 152.60233 141.27733) (xy 152.60233 141.28552) (xy 152.60233 141.29372) (xy 152.60233 141.30191)
			(xy 152.60233 141.31011) (xy 152.60233 141.3183) (xy 152.60233 141.32649) (xy 152.60233 141.33469)
			(xy 152.60233 141.34289) (xy 152.60233 141.35108) (xy 152.60233 141.35927) (xy 152.60233 141.36747)
			(xy 152.60233 141.37566) (xy 152.60233 141.38386) (xy 152.60233 141.39205) (xy 152.60233 141.40025)
			(xy 152.60233 141.40844) (xy 152.60233 141.41663) (xy 152.60233 141.42483) (xy 152.60233 141.43302)
			(xy 152.60233 141.44122) (xy 152.60233 141.44941) (xy 152.60233 141.45761) (xy 152.60233 141.4658)
			(xy 152.60233 141.474) (xy 152.60233 141.48219) (xy 152.60233 141.49039) (xy 152.60233 141.49858)
			(xy 152.60233 141.50677) (xy 152.60233 141.51497) (xy 152.60233 141.52316) (xy 152.60233 141.53136)
			(xy 152.60233 141.53955) (xy 152.60233 141.54775) (xy 152.60233 141.55594) (xy 152.60233 141.56413)
			(xy 152.60233 141.57233) (xy 152.60233 141.58052) (xy 152.60233 141.58872) (xy 152.60233 141.59692)
			(xy 152.60233 141.60511) (xy 152.60233 141.6133) (xy 152.60233 141.6215) (xy 152.60233 141.62969)
			(xy 152.60233 141.63789) (xy 152.60233 141.64608) (xy 152.60233 141.65427) (xy 152.60233 141.66247)
			(xy 152.60233 141.67066) (xy 152.60233 141.67886) (xy 152.60233 141.68705) (xy 152.60233 141.69525)
			(xy 152.60233 141.70344) (xy 152.60233 141.71164) (xy 152.60233 141.71983) (xy 152.60233 141.72803)
			(xy 152.60233 141.73622) (xy 152.60233 141.74441) (xy 152.60233 141.75261) (xy 152.60233 141.7608)
			(xy 152.60233 141.769) (xy 152.60233 141.77719) (xy 152.60233 141.78539) (xy 152.60233 141.79358)
			(xy 152.60233 141.80177) (xy 152.60233 141.80997) (xy 152.60233 141.81816) (xy 152.60233 141.82636)
			(xy 152.60233 141.83456) (xy 152.60233 141.84275) (xy 152.60233 141.85094) (xy 152.60233 141.85914)
			(xy 152.60233 141.86733) (xy 152.60233 141.87553) (xy 152.60233 141.88372) (xy 152.60233 141.89192)
			(xy 152.60233 141.90011) (xy 152.60233 141.9083) (xy 152.60233 141.9165) (xy 152.60233 141.92469)
			(xy 152.60233 141.93289) (xy 152.60233 141.94108) (xy 152.60233 141.94927) (xy 152.60233 141.95747)
			(xy 152.60233 141.96567) (xy 152.60233 141.97386) (xy 152.60233 141.98205) (xy 152.60233 141.99025)
			(xy 152.60233 141.99844) (xy 152.60233 142.00664) (xy 152.60233 142.01483) (xy 152.60233 142.02303)
			(xy 152.60233 142.03122) (xy 152.60233 142.03942) (xy 152.60233 142.04761) (xy 152.60233 142.0558)
			(xy 152.60233 142.064) (xy 152.60233 142.07219) (xy 152.60233 142.08039) (xy 152.60233 142.08858)
			(xy 152.60233 142.09678) (xy 152.60233 142.10497) (xy 152.60233 142.11317) (xy 152.60233 142.12136)
			(xy 152.60233 142.12956) (xy 152.60233 142.13775) (xy 152.60233 142.14594) (xy 152.60233 142.15414)
			(xy 152.60233 142.16233) (xy 152.60233 142.17053) (xy 152.60233 142.17872) (xy 152.60233 142.18692)
			(xy 152.60233 142.19511) (xy 152.60233 142.20331) (xy 152.60233 142.2115) (xy 152.60233 142.21969)
			(xy 152.60233 142.22789) (xy 152.60233 142.23608) (xy 152.60233 142.24428) (xy 152.60233 142.25247)
			(xy 152.60233 142.26067) (xy 152.60233 142.26886) (xy 152.60233 142.27706) (xy 152.60233 142.28525)
			(xy 152.60233 142.29344) (xy 152.60233 142.30164) (xy 152.60233 142.30984) (xy 152.60233 142.31803)
			(xy 152.60233 142.32622) (xy 152.60233 142.33442) (xy 152.60233 142.34261) (xy 152.60233 142.35081)
			(xy 152.60233 142.359) (xy 152.60233 142.3672) (xy 152.60233 142.37539) (xy 152.60233 142.38359)
			(xy 152.60233 142.39178) (xy 152.60233 142.39997) (xy 152.60233 142.40817) (xy 152.60233 142.41636)
			(xy 152.60233 142.42456) (xy 152.60233 142.43275) (xy 152.60233 142.44095) (xy 152.60233 142.44914)
			(xy 152.60233 142.45734) (xy 152.60233 142.46553) (xy 152.60233 142.47372) (xy 152.60233 142.48192)
			(xy 152.60233 142.49011) (xy 152.60233 142.49831) (xy 152.60233 142.5065) (xy 152.60233 142.5147)
			(xy 152.60233 142.52289) (xy 152.60233 142.53108) (xy 152.60233 142.53928) (xy 152.60233 142.54747)
			(xy 152.60233 142.55567) (xy 152.60233 142.56387) (xy 152.60233 142.57206) (xy 152.60233 142.58025)
			(xy 152.60233 142.58845) (xy 152.60233 142.59664) (xy 152.60233 142.60484) (xy 152.60233 142.61303)
			(xy 152.60233 142.62123) (xy 152.60233 142.62942) (xy 152.60233 142.63761) (xy 152.60233 142.64581)
			(xy 152.60233 142.654) (xy 152.60233 142.6622) (xy 152.60233 142.67039) (xy 152.60233 142.67859)
			(xy 152.60233 142.68678) (xy 152.60233 142.69498) (xy 152.60233 142.70317) (xy 152.60233 142.71136)
			(xy 152.60233 142.71956) (xy 152.60233 142.72775) (xy 152.60233 142.73595) (xy 152.60233 142.74414)
			(xy 152.60233 142.75234) (xy 152.60233 142.76053) (xy 152.60233 142.76873) (xy 152.60233 142.77692)
			(xy 152.60233 142.78511) (xy 152.60233 142.79331) (xy 152.60233 142.8015) (xy 152.60233 142.8097)
			(xy 152.60233 142.81789) (xy 152.60233 142.82609) (xy 152.60233 142.83428) (xy 152.60233 142.84248)
			(xy 152.60233 142.85067) (xy 152.60233 142.85887) (xy 152.60233 142.86706) (xy 152.60233 142.87525)
			(xy 152.60233 142.88345) (xy 152.60233 142.89164) (xy 152.60233 142.89984) (xy 152.60233 142.90803)
			(xy 152.60233 142.91623) (xy 152.60233 142.92442) (xy 152.60233 142.93262) (xy 152.60233 142.94081)
			(xy 152.60233 142.949) (xy 152.60233 142.9572) (xy 152.60233 142.96539) (xy 152.60233 142.97359)
			(xy 152.60233 142.98178) (xy 152.60233 142.98998) (xy 152.60233 142.99817) (xy 152.60233 143.00637)
			(xy 152.60233 143.01456) (xy 152.60233 143.02275) (xy 152.60233 143.03095) (xy 152.60233 143.03915)
			(xy 152.60233 143.04734) (xy 152.60233 143.05553) (xy 152.60233 143.06373) (xy 152.60233 143.07192)
			(xy 152.60233 143.08012) (xy 152.60233 143.08831) (xy 152.60233 143.09651) (xy 152.60233 143.1047)
			(xy 152.60233 143.1129) (xy 152.60233 143.12109) (xy 152.60233 143.12928) (xy 152.60233 143.13748)
			(xy 152.60233 143.14567) (xy 152.60233 143.15387) (xy 152.60233 143.16206) (xy 152.60233 143.17026)
			(xy 152.60233 143.17845) (xy 152.60233 143.18664) (xy 152.60233 143.19484) (xy 152.60233 143.20303)
			(xy 152.60233 143.21123) (xy 152.60233 143.21942) (xy 152.60233 143.22762) (xy 152.60233 143.23581)
			(xy 152.60233 143.24401) (xy 152.60233 143.2522) (xy 152.60233 143.26039) (xy 152.60233 143.26859)
			(xy 152.60233 143.27679) (xy 152.60233 143.28498) (xy 152.60233 143.29317) (xy 152.60233 143.30137)
			(xy 152.60233 143.30956) (xy 152.60233 143.31776) (xy 152.60233 143.32595) (xy 152.60233 143.33415)
			(xy 152.60233 143.34234) (xy 152.60233 143.35054) (xy 152.60233 143.35873) (xy 152.60233 143.36692)
			(xy 152.60233 143.37512) (xy 152.60233 143.38331) (xy 152.60233 143.39151) (xy 152.60233 143.3997)
			(xy 152.60233 143.4079) (xy 152.60233 143.41609) (xy 152.60233 143.42429) (xy 152.60233 143.43248)
			(xy 152.60233 143.44067) (xy 152.60233 143.44887) (xy 152.60233 143.45706) (xy 152.60233 143.46526)
			(xy 152.60233 143.47345) (xy 152.60233 143.48165) (xy 152.60233 143.48984) (xy 152.60233 143.49803)
			(xy 152.60233 143.50623) (xy 152.60233 143.51443) (xy 152.60233 143.52262) (xy 152.60233 143.53082)
			(xy 152.60233 143.53901) (xy 152.60233 143.5472) (xy 152.60233 143.5554) (xy 152.60233 143.56359)
			(xy 152.60233 143.57179) (xy 152.60233 143.57998) (xy 152.60233 143.58818) (xy 152.60233 143.59637)
			(xy 152.60233 143.60456) (xy 152.60233 143.61276) (xy 152.60233 143.62095) (xy 152.60233 143.62915)
			(xy 152.60233 143.63734) (xy 152.60233 143.64554) (xy 152.60233 143.65373) (xy 152.60233 143.66193)
			(xy 152.60233 143.67012) (xy 152.60233 143.67831) (xy 152.60233 143.68651) (xy 152.60233 143.6947)
			(xy 152.60233 143.7029) (xy 152.60233 143.71109) (xy 152.60233 143.71929) (xy 152.60233 143.72748)
			(xy 152.60233 143.73567) (xy 152.60233 143.74387) (xy 152.60233 143.75206) (xy 152.60233 143.76026)
			(xy 152.60233 143.76846) (xy 152.60233 143.77665) (xy 152.60233 143.78484) (xy 152.60233 143.79304)
			(xy 152.60233 143.80123) (xy 152.60233 143.80943) (xy 152.60233 143.81762) (xy 152.60233 143.82582)
			(xy 152.60233 143.83401) (xy 152.60233 143.8422) (xy 152.60233 143.8504) (xy 152.60233 143.85859)
			(xy 152.60233 143.86679) (xy 152.60233 143.87498) (xy 152.60233 143.88318) (xy 152.60233 143.89137)
			(xy 152.60233 143.89957) (xy 152.60233 143.90776) (xy 152.60233 143.91596) (xy 152.60233 143.92415)
			(xy 152.60233 143.93234) (xy 152.60233 143.94054) (xy 152.60233 143.94873) (xy 152.60233 143.95693)
			(xy 152.60233 143.96512) (xy 152.60233 143.97332) (xy 152.60233 143.98151) (xy 152.60233 143.9897)
			(xy 152.60233 143.9979) (xy 152.60233 144.0061) (xy 152.60233 144.01429) (xy 152.60233 144.02248)
			(xy 152.60233 144.03068) (xy 152.60233 144.03887) (xy 152.60233 144.04707) (xy 152.60233 144.05526)
			(xy 152.60233 144.06346) (xy 152.60233 144.07165) (xy 152.60233 144.07985) (xy 152.60233 144.08804)
			(xy 152.60233 144.09623) (xy 152.60233 144.10443) (xy 152.60233 144.11262) (xy 152.60233 144.12082)
			(xy 152.60233 144.12901) (xy 152.60233 144.13721) (xy 152.60233 144.1454) (xy 152.60233 144.1536)
			(xy 152.60233 144.16179) (xy 152.60233 144.16998) (xy 152.60233 144.17818) (xy 152.60233 144.18637)
			(xy 152.60233 144.19457) (xy 152.60233 144.20276) (xy 152.60233 144.21096) (xy 152.60233 144.21915)
			(xy 152.60233 144.22734) (xy 152.60233 144.23554) (xy 152.60233 144.24374) (xy 152.60233 144.25193)
			(xy 152.60233 144.26012) (xy 152.60233 144.26832) (xy 152.60233 144.27651) (xy 152.60233 144.28471)
			(xy 152.60233 144.2929) (xy 152.60233 144.3011) (xy 152.60233 144.30929) (xy 152.60233 144.31749)
			(xy 152.60233 144.32568) (xy 152.60233 144.33387) (xy 152.60233 144.34207) (xy 152.60233 144.35026)
			(xy 152.60233 144.35846) (xy 152.60233 144.36665) (xy 152.60233 144.37485) (xy 152.60233 144.38304)
			(xy 152.60233 144.39124) (xy 152.60233 144.39943) (xy 152.60233 144.40762) (xy 152.60233 144.41582)
			(xy 152.60233 144.42401) (xy 152.60233 144.43221) (xy 152.60233 144.4404) (xy 152.60233 144.4486)
			(xy 152.60233 144.45679) (xy 152.60233 144.46498) (xy 152.60233 144.47318) (xy 152.60233 144.48138)
			(xy 152.60233 144.48957) (xy 152.60233 144.49777) (xy 152.60233 144.50596) (xy 152.60233 144.51415)
			(xy 152.60233 144.52235) (xy 152.60233 144.53054) (xy 152.60233 144.53874) (xy 152.60233 144.54693)
			(xy 152.60233 144.55513) (xy 152.60233 144.56332) (xy 152.60233 144.57151) (xy 152.60233 144.57971)
			(xy 152.60233 144.5879) (xy 152.60233 144.5961) (xy 152.60233 144.60429) (xy 152.60233 144.61249)
			(xy 152.60233 144.62068) (xy 152.60233 144.62888) (xy 152.60233 144.63707) (xy 152.60233 144.64527)
			(xy 152.60233 144.65346) (xy 152.60233 144.66165) (xy 152.60233 144.66985) (xy 152.60233 144.67804)
			(xy 152.60233 144.68624) (xy 152.60233 144.69443) (xy 152.60233 144.70262) (xy 152.60233 144.71082)
			(xy 152.60233 144.71901) (xy 152.60233 144.72721) (xy 152.60233 144.73541) (xy 152.60233 144.7436)
			(xy 152.60233 144.75179) (xy 152.60233 144.75999) (xy 152.60233 144.76818) (xy 152.60233 144.77638)
			(xy 152.60233 144.78457) (xy 152.60233 144.79277) (xy 152.60233 144.80096) (xy 152.60233 144.80915)
			(xy 152.60233 144.81735) (xy 152.60233 144.82554) (xy 152.60233 144.83374) (xy 152.60233 144.84193)
			(xy 152.60233 144.85013) (xy 152.60233 144.85832) (xy 152.60233 144.86652) (xy 152.60233 144.87471)
			(xy 152.60233 144.8829) (xy 152.60233 144.8911) (xy 152.60233 144.89929) (xy 152.60233 144.90749)
			(xy 152.60233 144.91568) (xy 152.60233 144.92388) (xy 152.60233 144.93207) (xy 152.60233 144.94027)
			(xy 152.60233 144.94846) (xy 152.60233 144.95665) (xy 152.60233 144.96485) (xy 152.60233 144.97305)
			(xy 152.60233 144.98124) (xy 152.60233 144.98943) (xy 152.60233 144.99763) (xy 152.60233 145.00582)
			(xy 152.60233 145.01402) (xy 152.60233 145.02221) (xy 152.60233 145.03041) (xy 152.60233 145.0386)
			(xy 152.60233 145.04679) (xy 152.60233 145.05499) (xy 152.60233 145.06318) (xy 152.60233 145.07138)
			(xy 152.60233 145.07957) (xy 152.60233 145.08777) (xy 152.60233 145.09596) (xy 152.60233 145.10416)
			(xy 152.60233 145.11235) (xy 152.60233 145.12054) (xy 152.60233 145.12874) (xy 152.60233 145.13693)
			(xy 152.60233 145.14513) (xy 152.60233 145.15332) (xy 152.60233 145.16152) (xy 152.60233 145.16971)
			(xy 152.60233 145.17791) (xy 152.60233 145.1861) (xy 152.60233 145.19429) (xy 152.60233 145.20249)
			(xy 152.60233 145.21069) (xy 152.60233 145.21888) (xy 152.60233 145.22707) (xy 152.60233 145.23527)
			(xy 152.60233 145.24346) (xy 152.60233 145.25166) (xy 152.60233 145.25985) (xy 152.60233 145.26805)
			(xy 152.60233 145.27624) (xy 152.60233 145.28444) (xy 152.60233 145.29263) (xy 152.60233 145.30082)
			(xy 152.60233 145.30902) (xy 152.60233 145.31721) (xy 152.60233 145.32541) (xy 152.60233 145.3336)
			(xy 152.60233 145.3418) (xy 152.60233 145.34999) (xy 152.60233 145.35819) (xy 152.60233 145.36638)
			(xy 152.60233 145.37458) (xy 152.60233 145.38277) (xy 152.60233 145.39096) (xy 152.60233 145.39916)
			(xy 152.60233 145.40735) (xy 152.60233 145.41555) (xy 152.60233 145.42374) (xy 152.60233 145.43193)
			(xy 152.60233 145.44013) (xy 152.60233 145.44833) (xy 152.60233 145.45652) (xy 152.60233 145.46472)
			(xy 152.60233 145.47291) (xy 152.60233 145.4811) (xy 152.60233 145.4893) (xy 152.60233 145.49749)
			(xy 152.60233 145.50569) (xy 152.60233 145.51388) (xy 152.60233 145.52208) (xy 152.60233 145.53027)
			(xy 152.60233 145.53846) (xy 152.60233 145.54666) (xy 152.60233 145.55485) (xy 152.60233 145.56305)
			(xy 152.60233 145.57124) (xy 152.60233 145.57944) (xy 152.60233 145.58763) (xy 152.60233 145.59583)
			(xy 152.60233 145.60402) (xy 152.60233 145.61221) (xy 152.60233 145.62041) (xy 152.60233 145.6286)
			(xy 152.60233 145.6368) (xy 152.60233 145.64499) (xy 152.60233 145.65319) (xy 152.60233 145.66138)
			(xy 152.60233 145.66958) (xy 152.60233 145.67777) (xy 152.60233 145.68597) (xy 152.60233 145.69416)
			(xy 152.60233 145.70236) (xy 152.60233 145.71055) (xy 152.60233 145.71874) (xy 152.60233 145.72694)
			(xy 152.60233 145.73513) (xy 152.60233 145.74333) (xy 152.60233 145.75152) (xy 152.60233 145.75972)
			(xy 152.60233 145.76791) (xy 152.60233 145.7761) (xy 152.60233 145.7843) (xy 152.60233 145.7925)
			(xy 152.60233 145.80069) (xy 152.60233 145.80888) (xy 152.60233 145.81708) (xy 152.60233 145.82527)
			(xy 152.60233 145.83347) (xy 152.60233 145.84166) (xy 152.60233 145.84985) (xy 152.60233 145.85805)
			(xy 152.60233 145.86625) (xy 152.60233 145.87444) (xy 152.60233 145.88263) (xy 152.60233 145.89083)
			(xy 152.60233 145.89902) (xy 152.60233 145.90722) (xy 152.60233 145.91541) (xy 152.60233 145.9236)
			(xy 152.60233 145.9318) (xy 152.60233 145.94) (xy 152.60233 145.94819) (xy 152.60233 145.95638) (xy 152.60233 145.96458)
			(xy 152.60233 145.97277) (xy 152.60233 145.98097) (xy 152.60233 145.98916) (xy 152.60233 145.99736)
			(xy 152.60233 146.00555) (xy 152.60233 146.01375) (xy 152.60233 146.02194) (xy 152.60233 146.03014)
			(xy 152.60233 146.03833) (xy 152.60233 146.04652) (xy 152.60233 146.05472) (xy 152.60233 146.06291)
			(xy 152.60233 146.07111) (xy 152.60233 146.0793) (xy 152.60233 146.0875) (xy 152.60233 146.09569)
			(xy 152.60233 146.10388) (xy 152.60233 146.11208) (xy 152.60233 146.12027) (xy 152.60233 146.12847)
			(xy 152.60233 146.13666) (xy 152.60233 146.14486) (xy 152.60233 146.15305) (xy 152.60233 146.16125)
			(xy 152.60233 146.16944) (xy 152.60233 146.17764) (xy 152.60233 146.18583) (xy 152.60233 146.19402)
			(xy 152.60233 146.20222) (xy 152.60233 146.21041) (xy 152.60233 146.21861) (xy 152.60233 146.2268)
			(xy 152.60233 146.235) (xy 152.60233 146.24319) (xy 152.60233 146.25139) (xy 152.60233 146.25958)
			(xy 152.60233 146.26777) (xy 152.60233 146.27597) (xy 152.60233 146.28416) (xy 152.60233 146.29236)
			(xy 152.60233 146.30055) (xy 152.60233 146.30875) (xy 152.60233 146.31694) (xy 152.60233 146.32514)
			(xy 152.60233 146.33333) (xy 152.60233 146.34152) (xy 152.60233 146.34972) (xy 152.60233 146.35791)
			(xy 152.60233 146.36611) (xy 152.60233 146.3743) (xy 152.60233 146.3825) (xy 152.60233 146.39069)
			(xy 152.60233 146.39889) (xy 152.60233 146.40708) (xy 152.60233 146.41528) (xy 152.60233 146.42347)
			(xy 152.60233 146.43167) (xy 152.60233 146.43986) (xy 152.60233 146.44805) (xy 152.60233 146.45625)
			(xy 152.60233 146.46444) (xy 152.60233 146.47264) (xy 152.60233 146.48083) (xy 152.60233 146.48903)
			(xy 152.60233 146.49722) (xy 152.60233 146.50541) (xy 152.60233 146.51361) (xy 152.60233 146.52181)
			(xy 152.60233 146.53) (xy 152.60233 146.53819) (xy 152.60233 146.54639) (xy 152.60233 146.55458)
			(xy 152.60233 146.56278) (xy 152.60233 146.57097) (xy 152.60233 146.57916) (xy 152.60233 146.58736)
			(xy 152.60233 146.59556) (xy 152.60233 146.60375) (xy 152.60233 146.61194) (xy 152.60233 146.62014)
			(xy 152.60233 146.62833) (xy 152.60233 146.63653) (xy 152.60233 146.64472) (xy 152.60233 146.65292)
			(xy 152.60233 146.66111) (xy 152.60233 146.66931) (xy 152.60233 146.6775) (xy 152.60233 146.68569)
			(xy 152.60233 146.69389) (xy 152.60233 146.70208) (xy 152.60233 146.71028) (xy 152.60233 146.71848)
			(xy 152.60233 146.72667) (xy 152.60233 146.73486) (xy 152.60233 146.74305) (xy 152.60233 146.75125)
			(xy 152.60233 146.75945) (xy 152.60233 146.76764) (xy 152.60233 146.77583) (xy 152.60233 146.78403)
			(xy 152.60233 146.79222) (xy 152.60233 146.80042) (xy 152.60233 146.80861) (xy 152.60233 146.81681)
			(xy 152.60233 146.825) (xy 152.60233 146.83319) (xy 152.60233 146.84139) (xy 152.60233 146.84958)
			(xy 152.60233 146.85778) (xy 152.60233 146.86597) (xy 152.60233 146.87417) (xy 152.60233 146.88236)
			(xy 152.60233 146.89056) (xy 152.60233 146.89875) (xy 152.60233 146.90695) (xy 152.60233 146.91514)
			(xy 152.60233 146.92333) (xy 152.60233 146.93153) (xy 152.60233 146.93972) (xy 152.60233 146.94792)
			(xy 152.60233 146.95611) (xy 152.60233 146.96431) (xy 152.60233 146.9725) (xy 152.60233 146.9807)
			(xy 152.60233 146.98889) (xy 152.60233 146.99708) (xy 152.60233 147.00528) (xy 152.60233 147.01348)
			(xy 152.60233 147.02167) (xy 152.60233 147.02986) (xy 152.60233 147.03806) (xy 152.60233 147.04625)
			(xy 152.60233 147.05445) (xy 152.60233 147.06264) (xy 152.60233 147.07083) (xy 152.60233 147.07903)
			(xy 152.60233 147.08722) (xy 152.60233 147.09542) (xy 152.60233 147.10361) (xy 152.60233 147.11181)
			(xy 152.60233 147.12) (xy 152.60233 147.1282) (xy 152.60233 147.13639) (xy 152.60233 147.14459) (xy 152.60233 147.15278)
			(xy 152.60233 147.16097) (xy 152.60233 147.16917) (xy 152.60233 147.17736) (xy 152.60233 147.18556)
			(xy 152.60233 147.19375) (xy 152.60233 147.20195) (xy 152.60233 147.21014) (xy 152.60233 147.21834)
			(xy 152.60233 147.22653) (xy 152.29913 147.22653) (xy 152.29913 147.21834) (xy 152.29913 147.21014)
			(xy 152.29913 147.20195) (xy 152.29913 147.19375) (xy 152.29913 147.18556) (xy 152.29913 147.17736)
			(xy 152.29913 147.16917) (xy 152.29913 147.16097) (xy 152.29913 147.15278) (xy 152.29913 147.14459)
			(xy 152.29913 147.13639) (xy 152.29913 147.1282) (xy 152.29913 147.12) (xy 152.29913 147.11181) (xy 152.29913 147.10361)
			(xy 152.29913 147.09542) (xy 152.29913 147.08722) (xy 152.29913 147.07903) (xy 152.29913 147.07083)
			(xy 152.29913 147.06264) (xy 152.29913 147.05445) (xy 152.29913 147.04625) (xy 152.29913 147.03806)
			(xy 152.29913 147.02986) (xy 152.29913 147.02167) (xy 152.29913 147.01348) (xy 152.29913 147.00528)
			(xy 152.29913 146.99708) (xy 152.29913 146.98889) (xy 152.29913 146.9807) (xy 152.29913 146.9725)
			(xy 152.29913 146.96431) (xy 152.29913 146.95611) (xy 152.29913 146.94792) (xy 152.29913 146.93972)
			(xy 152.29913 146.93153) (xy 152.29913 146.92333) (xy 152.29913 146.91514) (xy 152.29913 146.90695)
			(xy 152.29913 146.89875) (xy 152.29913 146.89056) (xy 152.29913 146.88236) (xy 152.29913 146.87417)
			(xy 152.29913 146.86597) (xy 152.29913 146.85778) (xy 152.29913 146.84958) (xy 152.29913 146.84139)
			(xy 152.29913 146.83319) (xy 152.29913 146.825) (xy 152.29913 146.81681) (xy 152.29913 146.80861)
			(xy 152.29913 146.80042) (xy 152.29913 146.79222) (xy 152.29913 146.78403) (xy 152.29913 146.77583)
			(xy 152.29913 146.76764) (xy 152.29913 146.75945) (xy 152.29913 146.75125) (xy 152.29913 146.74305)
			(xy 152.29913 146.73486) (xy 152.29913 146.72667) (xy 152.29913 146.71848) (xy 152.29913 146.71028)
			(xy 152.29913 146.70208) (xy 152.29913 146.69389) (xy 152.29913 146.68569) (xy 152.29913 146.6775)
			(xy 152.29913 146.66931) (xy 152.29913 146.66111) (xy 152.29913 146.65292) (xy 152.29913 146.64472)
			(xy 152.29913 146.63653) (xy 152.29913 146.62833) (xy 152.29913 146.62014) (xy 152.29913 146.61194)
			(xy 152.29913 146.60375) (xy 152.29913 146.59556) (xy 152.29913 146.58736) (xy 152.29913 146.57916)
			(xy 152.29913 146.57097) (xy 152.29913 146.56278) (xy 152.29913 146.55458) (xy 152.29913 146.54639)
			(xy 152.29913 146.53819) (xy 152.29913 146.53) (xy 152.29913 146.52181) (xy 152.29913 146.51361)
			(xy 152.29913 146.50541) (xy 152.29913 146.49722) (xy 152.29913 146.48903) (xy 152.29913 146.48083)
			(xy 152.29913 146.47264) (xy 152.29913 146.46444) (xy 152.29913 146.45625) (xy 152.29913 146.44805)
			(xy 152.29913 146.43986) (xy 152.29913 146.43167) (xy 152.29913 146.42347) (xy 152.29913 146.41528)
			(xy 152.29913 146.40708) (xy 152.29913 146.39889) (xy 152.29913 146.39069) (xy 152.29913 146.3825)
			(xy 152.29913 146.3743) (xy 152.29913 146.36611) (xy 152.29913 146.35791) (xy 152.29913 146.34972)
			(xy 152.29913 146.34152) (xy 152.29913 146.33333) (xy 152.29913 146.32514) (xy 152.29913 146.31694)
			(xy 152.29913 146.30875) (xy 152.29913 146.30055) (xy 152.29913 146.29236) (xy 152.29913 146.28416)
			(xy 152.29913 146.27597) (xy 152.29913 146.26777) (xy 152.29913 146.25958) (xy 152.29913 146.25139)
			(xy 152.29913 146.24319) (xy 152.29913 146.235) (xy 152.29913 146.2268) (xy 152.29913 146.21861)
			(xy 152.29913 146.21041) (xy 152.29913 146.20222) (xy 152.29913 146.19402) (xy 152.29913 146.18583)
			(xy 152.29913 146.17764) (xy 152.29913 146.16944) (xy 152.29913 146.16125) (xy 152.29913 146.15305)
			(xy 152.29913 146.14486) (xy 152.29913 146.13666) (xy 152.29913 146.12847) (xy 152.29913 146.12027)
			(xy 152.29913 146.11208) (xy 152.29913 146.10388) (xy 152.29913 146.09569) (xy 152.29913 146.0875)
			(xy 152.29913 146.0793) (xy 152.29913 146.07111) (xy 152.29913 146.06291) (xy 152.29913 146.05472)
			(xy 152.29913 146.04652) (xy 152.29913 146.03833) (xy 152.29913 146.03014) (xy 152.29913 146.02194)
			(xy 152.29913 146.01375) (xy 152.29913 146.00555) (xy 152.29913 145.99736) (xy 152.29913 145.98916)
			(xy 152.29913 145.98097) (xy 152.29913 145.97277) (xy 152.29913 145.96458) (xy 152.29913 145.95638)
			(xy 152.29913 145.94819) (xy 152.29913 145.94) (xy 152.29913 145.9318) (xy 152.29913 145.9236) (xy 152.29913 145.91541)
			(xy 152.29913 145.90722) (xy 152.29913 145.89902) (xy 152.29913 145.89083) (xy 152.29913 145.88263)
			(xy 152.29913 145.87444) (xy 152.29913 145.86625) (xy 152.29913 145.85805) (xy 152.29913 145.84985)
			(xy 152.29913 145.84166) (xy 152.29913 145.83347) (xy 152.29913 145.82527) (xy 152.29913 145.81708)
			(xy 152.29913 145.80888) (xy 152.29913 145.80069) (xy 152.29913 145.7925) (xy 152.29913 145.7843)
			(xy 152.29913 145.7761) (xy 152.29913 145.76791) (xy 152.29913 145.75972) (xy 152.29913 145.75152)
			(xy 152.29913 145.74333) (xy 152.29913 145.73513) (xy 152.29913 145.72694) (xy 152.29913 145.71874)
			(xy 152.29913 145.71055) (xy 152.29913 145.70236) (xy 152.29913 145.69416) (xy 152.29913 145.68597)
			(xy 152.29913 145.67777) (xy 152.29913 145.66958) (xy 152.29913 145.66138) (xy 152.29913 145.65319)
			(xy 152.29913 145.64499) (xy 152.29913 145.6368) (xy 152.29913 145.6286) (xy 152.29913 145.62041)
			(xy 152.29913 145.61221) (xy 152.29913 145.60402) (xy 152.29913 145.59583) (xy 152.29913 145.58763)
			(xy 152.29913 145.57944) (xy 152.29913 145.57124) (xy 152.29913 145.56305) (xy 152.29913 145.55485)
			(xy 152.29913 145.54666) (xy 152.29913 145.53846) (xy 152.29913 145.53027) (xy 152.29913 145.52208)
			(xy 152.29913 145.51388) (xy 152.29913 145.50569) (xy 152.29913 145.49749) (xy 152.29913 145.4893)
			(xy 152.29913 145.4811) (xy 152.29913 145.47291) (xy 152.29913 145.46472) (xy 152.29913 145.45652)
			(xy 152.29913 145.44833) (xy 152.29913 145.44013) (xy 152.29913 145.43193) (xy 152.29913 145.42374)
			(xy 152.29913 145.41555) (xy 152.29913 145.40735) (xy 152.29913 145.39916) (xy 152.29913 145.39096)
			(xy 152.29913 145.38277) (xy 152.29913 145.37458) (xy 152.29913 145.36638) (xy 152.29913 145.35819)
			(xy 152.29913 145.34999) (xy 152.29913 145.3418) (xy 152.29913 145.3336) (xy 152.29913 145.32541)
			(xy 152.29913 145.31721) (xy 152.29913 145.30902) (xy 152.29913 145.30082) (xy 152.29913 145.29263)
			(xy 152.29913 145.28444) (xy 152.29913 145.27624) (xy 152.29913 145.26805) (xy 152.29913 145.25985)
			(xy 152.29913 145.25166) (xy 152.29913 145.24346) (xy 152.29913 145.23527) (xy 152.29913 145.22707)
			(xy 152.29913 145.21888) (xy 152.29913 145.21069) (xy 152.29913 145.20249) (xy 152.29913 145.19429)
			(xy 152.29913 145.1861) (xy 152.29913 145.17791) (xy 152.29913 145.16971) (xy 152.29913 145.16152)
			(xy 152.29913 145.15332) (xy 152.29913 145.14513) (xy 152.29913 145.13693) (xy 152.29913 145.12874)
			(xy 152.29913 145.12054) (xy 152.29913 145.11235) (xy 152.29913 145.10416) (xy 152.29913 145.09596)
			(xy 152.29913 145.08777) (xy 152.29913 145.07957) (xy 152.29913 145.07138) (xy 152.29913 145.06318)
			(xy 152.29913 145.05499) (xy 152.29913 145.04679) (xy 152.29913 145.0386) (xy 152.29913 145.03041)
			(xy 152.29913 145.02221) (xy 152.29913 145.01402) (xy 152.29913 145.00582) (xy 152.29913 144.99763)
			(xy 152.29913 144.98943) (xy 152.29913 144.98124) (xy 152.29913 144.97305) (xy 152.29913 144.96485)
			(xy 152.29913 144.95665) (xy 152.29913 144.94846) (xy 152.29913 144.94027) (xy 152.29913 144.93207)
			(xy 152.29913 144.92388) (xy 152.29913 144.91568) (xy 152.29913 144.90749) (xy 152.29913 144.89929)
			(xy 152.29913 144.8911) (xy 152.29913 144.8829) (xy 152.29913 144.87471) (xy 152.29913 144.86652)
			(xy 152.29913 144.85832) (xy 152.29913 144.85013) (xy 152.29913 144.84193) (xy 152.29913 144.83374)
			(xy 152.29913 144.82554) (xy 152.29913 144.81735) (xy 152.29913 144.80915) (xy 152.29913 144.80096)
			(xy 152.29913 144.79277) (xy 152.29913 144.78457) (xy 152.29913 144.77638) (xy 152.29913 144.76818)
			(xy 152.29913 144.75999) (xy 152.29913 144.75179) (xy 152.29913 144.7436) (xy 152.29913 144.73541)
			(xy 152.29913 144.72721) (xy 152.29913 144.71901) (xy 152.29913 144.71082) (xy 152.29913 144.70262)
			(xy 152.29913 144.69443) (xy 152.29913 144.68624) (xy 152.29913 144.67804) (xy 152.29913 144.66985)
			(xy 152.29913 144.66165) (xy 152.29913 144.65346) (xy 152.29913 144.64527) (xy 152.29913 144.63707)
			(xy 152.29913 144.62888) (xy 152.29913 144.62068) (xy 152.29913 144.61249) (xy 152.29913 144.60429)
			(xy 152.29913 144.5961) (xy 152.29913 144.5879) (xy 152.29913 144.57971) (xy 152.29913 144.57151)
			(xy 152.29913 144.56332) (xy 152.29913 144.55513) (xy 152.29913 144.54693) (xy 152.29913 144.53874)
			(xy 152.29913 144.53054) (xy 152.29913 144.52235) (xy 152.29913 144.51415) (xy 152.29913 144.50596)
			(xy 152.29913 144.49777) (xy 152.29913 144.48957) (xy 152.29913 144.48138) (xy 152.29913 144.47318)
			(xy 152.29913 144.46498) (xy 152.29913 144.45679) (xy 152.29913 144.4486) (xy 152.29913 144.4404)
			(xy 152.29913 144.43221) (xy 152.29913 144.42401) (xy 152.29913 144.41582) (xy 152.29913 144.40762)
			(xy 152.29913 144.39943) (xy 152.29913 144.39124) (xy 152.29913 144.38304) (xy 152.29913 144.37485)
			(xy 152.29913 144.36665) (xy 152.29913 144.35846) (xy 152.29913 144.35026) (xy 152.29913 144.34207)
			(xy 152.29913 144.33387) (xy 152.29913 144.32568) (xy 152.29913 144.31749) (xy 152.29913 144.30929)
			(xy 152.29913 144.3011) (xy 152.29913 144.2929) (xy 152.29913 144.28471) (xy 152.29913 144.27651)
			(xy 152.29913 144.26832) (xy 152.29913 144.26012) (xy 152.29913 144.25193) (xy 152.29913 144.24374)
			(xy 152.29913 144.23554) (xy 152.29913 144.22734) (xy 152.29913 144.21915) (xy 152.29913 144.21096)
			(xy 152.29913 144.20276) (xy 152.29913 144.19457) (xy 152.29913 144.18637) (xy 152.29913 144.17818)
			(xy 152.29913 144.16998) (xy 152.29913 144.16179) (xy 152.29913 144.1536) (xy 152.29913 144.1454)
			(xy 152.29913 144.13721) (xy 152.29913 144.12901) (xy 152.29913 144.12082) (xy 152.29913 144.11262)
			(xy 152.29913 144.10443) (xy 152.29913 144.09623) (xy 152.29913 144.08804) (xy 152.29913 144.07985)
			(xy 152.29913 144.07165) (xy 152.29913 144.06346) (xy 152.29913 144.05526) (xy 152.29913 144.04707)
			(xy 152.29913 144.03887) (xy 152.29913 144.03068) (xy 152.29913 144.02248) (xy 152.29913 144.01429)
			(xy 152.29913 144.0061) (xy 152.29913 143.9979) (xy 152.29913 143.9897) (xy 152.29913 143.98151)
			(xy 152.29913 143.97332) (xy 152.29913 143.96512) (xy 152.29913 143.95693) (xy 152.29913 143.94873)
			(xy 152.29913 143.94054) (xy 152.29913 143.93234) (xy 152.29913 143.92415) (xy 152.29913 143.91596)
			(xy 152.29913 143.90776) (xy 152.29913 143.89957) (xy 152.29913 143.89137) (xy 152.29913 143.88318)
			(xy 152.29913 143.87498) (xy 152.29913 143.86679) (xy 152.29913 143.85859) (xy 152.29913 143.8504)
			(xy 152.29913 143.8422) (xy 152.29913 143.83401) (xy 152.29913 143.82582) (xy 152.29913 143.81762)
			(xy 152.29913 143.80943) (xy 152.29913 143.80123) (xy 152.29913 143.79304) (xy 152.29913 143.78484)
			(xy 152.29913 143.77665) (xy 152.29913 143.76846) (xy 152.29913 143.76026) (xy 152.29913 143.75206)
			(xy 152.29913 143.74387) (xy 152.29913 143.73567) (xy 152.29913 143.72748) (xy 152.29913 143.71929)
			(xy 152.29913 143.71109) (xy 152.29913 143.7029) (xy 152.29913 143.6947) (xy 152.29913 143.68651)
			(xy 152.29913 143.67831) (xy 152.29913 143.67012) (xy 152.29913 143.66193) (xy 152.29913 143.65373)
			(xy 152.29913 143.64554) (xy 152.29913 143.63734) (xy 152.29913 143.62915) (xy 152.29913 143.62095)
			(xy 152.29913 143.61276) (xy 152.29913 143.60456) (xy 152.29913 143.59637) (xy 152.29913 143.58818)
			(xy 152.29913 143.57998) (xy 152.29913 143.57179) (xy 152.29913 143.56359) (xy 152.29913 143.5554)
			(xy 152.29913 143.5472) (xy 152.29913 143.53901) (xy 152.29913 143.53082) (xy 152.29913 143.52262)
			(xy 152.29913 143.51443) (xy 152.29913 143.50623) (xy 152.29913 143.49803) (xy 152.29913 143.48984)
			(xy 152.29913 143.48165) (xy 152.29913 143.47345) (xy 152.29913 143.46526) (xy 152.29913 143.45706)
			(xy 152.29913 143.44887) (xy 152.29913 143.44067) (xy 152.29913 143.43248) (xy 152.29913 143.42429)
			(xy 152.29913 143.41609) (xy 152.29913 143.4079) (xy 152.29913 143.3997) (xy 152.29913 143.39151)
			(xy 152.29913 143.38331) (xy 152.29913 143.37512) (xy 152.29913 143.36692) (xy 152.29913 143.35873)
			(xy 152.29913 143.35054) (xy 152.29913 143.34234) (xy 152.29913 143.33415) (xy 152.29913 143.32595)
			(xy 152.29913 143.31776) (xy 152.29913 143.30956) (xy 152.29913 143.30137) (xy 152.29913 143.29317)
			(xy 152.29913 143.28498) (xy 152.29913 143.27679) (xy 152.29913 143.26859) (xy 152.29913 143.26039)
			(xy 152.29913 143.2522) (xy 152.29913 143.24401) (xy 152.29913 143.23581) (xy 152.29913 143.22762)
			(xy 152.29913 143.21942) (xy 152.29913 143.21123) (xy 152.29913 143.20303) (xy 152.29913 143.19484)
			(xy 152.29913 143.18664) (xy 152.29913 143.17845) (xy 152.29913 143.17026) (xy 152.29913 143.16206)
			(xy 152.29913 143.15387) (xy 152.29913 143.14567) (xy 152.29913 143.13748) (xy 152.29913 143.12928)
			(xy 152.29913 143.12109) (xy 152.29913 143.1129) (xy 152.29913 143.1047) (xy 152.29913 143.09651)
			(xy 152.29913 143.08831) (xy 152.29913 143.08012) (xy 152.29913 143.07192) (xy 152.29913 143.06373)
			(xy 152.29913 143.05553) (xy 152.29913 143.04734) (xy 152.29913 143.03915) (xy 152.29913 143.03095)
			(xy 152.29913 143.02275) (xy 152.29913 143.01456) (xy 152.29913 143.00637) (xy 152.29913 142.99817)
			(xy 152.29913 142.98998) (xy 152.29913 142.98178) (xy 152.29913 142.97359) (xy 152.29913 142.96539)
			(xy 152.29913 142.9572) (xy 152.29913 142.949) (xy 152.29913 142.94081) (xy 152.29913 142.93262)
			(xy 152.29913 142.92442) (xy 152.29913 142.91623) (xy 152.29913 142.90803) (xy 152.29913 142.89984)
			(xy 152.29913 142.89164) (xy 152.29913 142.88345) (xy 152.29913 142.87525) (xy 152.29913 142.86706)
			(xy 152.29913 142.85887) (xy 152.29913 142.85067) (xy 152.29913 142.84248) (xy 152.29913 142.83428)
			(xy 152.29913 142.82609) (xy 152.29913 142.81789) (xy 152.29913 142.8097) (xy 152.29913 142.8015)
			(xy 152.29913 142.79331) (xy 152.29913 142.78511) (xy 152.29913 142.77692) (xy 152.29913 142.76873)
			(xy 152.29913 142.76053) (xy 152.29913 142.75234) (xy 152.29913 142.74414) (xy 152.29913 142.73595)
			(xy 152.29913 142.72775) (xy 152.29913 142.71956) (xy 152.29913 142.71136) (xy 152.29913 142.70317)
			(xy 152.29913 142.69498) (xy 152.29913 142.68678) (xy 152.29913 142.67859) (xy 152.29913 142.67039)
			(xy 152.29913 142.6622) (xy 152.29913 142.654) (xy 152.29913 142.64581) (xy 152.29913 142.63761)
			(xy 152.29913 142.62942) (xy 152.29913 142.62123) (xy 152.29913 142.61303) (xy 152.29913 142.60484)
			(xy 152.29913 142.59664) (xy 152.29913 142.58845) (xy 152.29913 142.58025) (xy 152.29913 142.57206)
			(xy 152.29913 142.56387) (xy 152.29913 142.55567) (xy 152.29913 142.54747) (xy 152.29913 142.53928)
			(xy 152.29913 142.53108) (xy 152.29913 142.52289) (xy 152.29913 142.5147) (xy 152.29913 142.5065)
			(xy 152.29913 142.49831) (xy 152.29913 142.49011) (xy 152.29913 142.48192) (xy 152.29913 142.47372)
			(xy 152.29913 142.46553) (xy 152.29913 142.45734) (xy 152.29913 142.44914) (xy 152.29913 142.44095)
			(xy 152.29913 142.43275) (xy 152.29913 142.42456) (xy 152.29913 142.41636) (xy 152.29913 142.40817)
			(xy 152.29913 142.39997) (xy 152.29913 142.39178) (xy 152.29913 142.38359) (xy 152.29913 142.37539)
			(xy 152.29913 142.3672) (xy 152.29913 142.359) (xy 152.29913 142.35081) (xy 152.29913 142.34261)
			(xy 152.29913 142.33442) (xy 152.29913 142.32622) (xy 152.29913 142.31803) (xy 152.29913 142.30984)
			(xy 152.29913 142.30164) (xy 152.29913 142.29344) (xy 152.29913 142.28525) (xy 152.29913 142.27706)
			(xy 152.29913 142.26886) (xy 152.29913 142.26067) (xy 152.29913 142.25247) (xy 152.29913 142.24428)
			(xy 152.29913 142.23608) (xy 152.29913 142.22789) (xy 152.29913 142.21969) (xy 152.29913 142.2115)
			(xy 152.29913 142.20331) (xy 152.29913 142.19511) (xy 152.29913 142.18692) (xy 152.29913 142.17872)
			(xy 152.29913 142.17053) (xy 152.29913 142.16233) (xy 152.29913 142.15414) (xy 152.29913 142.14594)
			(xy 152.29913 142.13775) (xy 152.29913 142.12956) (xy 152.29913 142.12136) (xy 152.29913 142.11317)
			(xy 152.29913 142.10497) (xy 152.29913 142.09678) (xy 152.29913 142.08858) (xy 152.29913 142.08039)
			(xy 152.29913 142.07219) (xy 152.29913 142.064) (xy 152.29913 142.0558) (xy 152.29913 142.04761)
			(xy 152.29913 142.03942) (xy 152.29913 142.03122) (xy 152.29913 142.02303) (xy 152.29913 142.01483)
			(xy 152.29913 142.00664) (xy 152.29913 141.99844) (xy 152.29913 141.99025) (xy 152.29913 141.98205)
			(xy 152.29913 141.97386) (xy 152.29913 141.96567) (xy 152.29913 141.95747) (xy 152.29913 141.94927)
			(xy 152.29913 141.94108) (xy 152.29913 141.93289) (xy 152.29913 141.92469) (xy 152.29913 141.9165)
			(xy 152.29913 141.9083) (xy 152.29913 141.90011) (xy 152.29913 141.89192) (xy 152.29913 141.88372)
			(xy 152.29913 141.87553) (xy 152.29913 141.86733) (xy 152.29913 141.85914) (xy 152.29913 141.85094)
			(xy 152.29913 141.84275) (xy 152.29913 141.83456) (xy 152.29913 141.82636) (xy 152.29913 141.81816)
			(xy 152.29913 141.80997) (xy 152.29913 141.80177) (xy 152.29913 141.79358) (xy 152.29913 141.78539)
			(xy 152.29913 141.77719) (xy 152.29913 141.769) (xy 152.29913 141.7608) (xy 152.29913 141.75261)
			(xy 152.29913 141.74441) (xy 152.29913 141.73622) (xy 152.29913 141.72803) (xy 152.29913 141.71983)
			(xy 152.29913 141.71164) (xy 152.29913 141.70344) (xy 152.29913 141.69525) (xy 152.29913 141.68705)
			(xy 152.29913 141.67886) (xy 152.29913 141.67066) (xy 152.29913 141.66247) (xy 152.29913 141.65427)
			(xy 152.29913 141.64608) (xy 152.29913 141.63789) (xy 152.29913 141.62969) (xy 152.29913 141.6215)
			(xy 152.29913 141.6133) (xy 152.29913 141.60511) (xy 152.29913 141.59692) (xy 152.29913 141.58872)
			(xy 152.29913 141.58052) (xy 152.29913 141.57233) (xy 152.29913 141.56413) (xy 152.29913 141.55594)
			(xy 152.29913 141.54775) (xy 152.29913 141.53955) (xy 152.29913 141.53136) (xy 152.29913 141.52316)
			(xy 152.29913 141.51497) (xy 152.29913 141.50677) (xy 152.29913 141.49858) (xy 152.29913 141.49039)
			(xy 152.29913 141.48219) (xy 152.29913 141.474) (xy 152.29913 141.4658) (xy 152.29913 141.45761)
			(xy 152.29913 141.44941) (xy 152.29913 141.44122) (xy 152.29913 141.43302) (xy 152.29913 141.42483)
			(xy 152.29913 141.41663) (xy 152.29913 141.40844) (xy 152.29913 141.40025) (xy 152.29913 141.39205)
			(xy 152.29913 141.38386) (xy 152.29913 141.37566) (xy 152.29913 141.36747) (xy 152.29913 141.35927)
			(xy 152.29913 141.35108) (xy 152.29913 141.34289) (xy 152.29913 141.33469) (xy 152.29913 141.32649)
			(xy 152.29913 141.3183) (xy 152.29913 141.31011) (xy 152.29913 141.30191) (xy 152.29913 141.29372)
			(xy 152.29913 141.28552) (xy 152.29913 141.27733) (xy 152.29913 141.26913) (xy 152.29913 141.26094)
			(xy 152.29913 141.25274) (xy 152.29913 141.24455) (xy 152.29913 141.23636) (xy 152.29913 141.22816)
			(xy 152.29913 141.21997) (xy 152.29913 141.21177) (xy 152.29913 141.20358) (xy 152.29913 141.19538)
			(xy 152.29913 141.18719) (xy 152.29913 141.179) (xy 152.29913 141.1708) (xy 152.29913 141.16261)
			(xy 152.29913 141.15441) (xy 152.29913 141.14622) (xy 152.29913 141.13802) (xy 152.29913 141.12983)
			(xy 152.29913 141.12163) (xy 152.29913 141.11344) (xy 152.29913 141.10525) (xy 152.29913 141.09705)
			(xy 152.29913 141.08885) (xy 152.29913 141.08066) (xy 152.29913 141.07247) (xy 152.29913 141.06427)
			(xy 152.29913 141.05608) (xy 152.29913 141.04788) (xy 152.29913 141.03969) (xy 152.29913 141.03149)
			(xy 152.29913 141.0233) (xy 152.29913 141.0151) (xy 152.29913 141.00691) (xy 152.29913 140.99872)
			(xy 152.29913 140.99052) (xy 152.29913 140.98233) (xy 152.29913 140.97413) (xy 152.29913 140.96594)
			(xy 152.29913 140.95774) (xy 152.29913 140.94955) (xy 152.29913 140.94135) (xy 152.29913 140.93316)
			(xy 152.29913 140.92496) (xy 152.29913 140.91677) (xy 152.29913 140.90858) (xy 152.29913 140.90038)
			(xy 152.29913 140.89219) (xy 152.29913 140.88399) (xy 152.29913 140.8758) (xy 152.29913 140.86761)
			(xy 152.29913 140.85941) (xy 152.29913 140.85121) (xy 152.29913 140.84302) (xy 152.29913 140.83482)
			(xy 152.29913 140.82663) (xy 152.29913 140.81844) (xy 152.29913 140.81024) (xy 152.29913 140.80205)
			(xy 152.29913 140.79385) (xy 152.29913 140.78566) (xy 152.29913 140.77746) (xy 152.29913 140.76927)
			(xy 152.29913 140.76108) (xy 152.29913 140.75288) (xy 152.29913 140.74469) (xy 152.29913 140.73649)
			(xy 152.29913 140.7283) (xy 152.29913 140.7201) (xy 152.29913 140.71191) (xy 152.29913 140.70371)
			(xy 152.29913 140.69552) (xy 152.29913 140.68732) (xy 152.29913 140.67913) (xy 152.29913 140.67094)
			(xy 152.29913 140.66274) (xy 152.29913 140.65455) (xy 152.29913 140.64635) (xy 152.29913 140.63816)
			(xy 152.29913 140.62996) (xy 152.29913 140.62177) (xy 152.29913 140.61357) (xy 152.29913 140.60538)
			(xy 152.29913 140.59718) (xy 152.29913 140.58899) (xy 152.29913 140.5808) (xy 152.29913 140.5726)
			(xy 152.29913 140.56441) (xy 152.29913 140.55621) (xy 152.29913 140.54802) (xy 152.29913 140.53982)
			(xy 152.29913 140.53163) (xy 152.29913 140.52344) (xy 152.29913 140.51524) (xy 152.29913 140.50704)
			(xy 152.29913 140.49885) (xy 152.29913 140.49066) (xy 152.29913 140.48246) (xy 152.29913 140.47427)
			(xy 152.29913 140.46607) (xy 152.29913 140.45788) (xy 152.29913 140.44969) (xy 152.29913 140.44149)
			(xy 152.29913 140.4333) (xy 152.29913 140.4251) (xy 152.29913 140.41691) (xy 152.29913 140.40871)
			(xy 152.29913 140.40052) (xy 152.29913 140.39232) (xy 152.29913 140.38413) (xy 152.29913 140.37593)
			(xy 152.29913 140.36774) (xy 152.29913 140.35954) (xy 152.29913 140.35135) (xy 152.29913 140.34316)
			(xy 152.29913 140.33496) (xy 152.29913 140.32677) (xy 152.29913 140.31857) (xy 152.29913 140.31038)
			(xy 152.29913 140.30218) (xy 152.29913 140.29399) (xy 152.29913 140.28579) (xy 152.29913 140.2776)
			(xy 152.29913 140.2694) (xy 152.29913 140.26121) (xy 152.29913 140.25302) (xy 152.29913 140.24482)
			(xy 152.29913 140.23663) (xy 152.29913 140.22843) (xy 152.29913 140.22024) (xy 152.29913 140.21204)
			(xy 152.29913 140.20385) (xy 152.29913 140.19565) (xy 152.29913 140.18746) (xy 152.29913 140.17927)
			(xy 152.29913 140.17107) (xy 152.29913 140.16288) (xy 152.29913 140.15468) (xy 152.29913 140.14649)
			(xy 152.29913 140.1383) (xy 152.29913 140.1301) (xy 152.29913 140.1219) (xy 152.29913 140.11371)
			(xy 152.29913 140.10552) (xy 152.29913 140.09732) (xy 152.29913 140.08913) (xy 152.29913 140.08093)
			(xy 152.29913 140.07274) (xy 152.29913 140.06454) (xy 152.29913 140.05635) (xy 152.29913 140.04815)
			(xy 152.29913 140.03996) (xy 152.29913 140.03176) (xy 152.29913 140.02357) (xy 152.29913 140.01538)
			(xy 152.29913 140.00718) (xy 152.29913 139.99899) (xy 152.29913 139.99079) (xy 152.29913 139.9826)
			(xy 152.29913 139.9744) (xy 152.29913 139.96621) (xy 152.29913 139.95802) (xy 152.29913 139.94982)
			(xy 152.29913 139.94163) (xy 152.29913 139.93343) (xy 152.29913 139.92524) (xy 152.29913 139.91704)
			(xy 152.29913 139.90885) (xy 152.29913 139.90065) (xy 152.29913 139.89246) (xy 152.29913 139.88426)
			(xy 152.29913 139.87607) (xy 152.29913 139.86787) (xy 152.29913 139.85968) (xy 152.29913 139.85149)
			(xy 152.29913 139.84329) (xy 152.29913 139.8351) (xy 152.29913 139.8269) (xy 152.29913 139.81871)
			(xy 152.29913 139.81051) (xy 152.29913 139.80232) (xy 152.29913 139.79413) (xy 152.29913 139.78593)
			(xy 152.29913 139.77773) (xy 152.29913 139.76954) (xy 152.29913 139.76135) (xy 152.29913 139.75315)
			(xy 152.29913 139.74496) (xy 152.29913 139.73676) (xy 152.29913 139.72857) (xy 152.29913 139.72038)
			(xy 152.29913 139.71218) (xy 152.29913 139.70398) (xy 152.29913 139.69579) (xy 152.29913 139.6876)
			(xy 152.29913 139.6794) (xy 152.29913 139.67121) (xy 152.29913 139.66301) (xy 152.29913 139.65482)
			(xy 152.29913 139.64662) (xy 152.29913 139.63843) (xy 152.29913 139.63023) (xy 152.29913 139.62204)
			(xy 152.29913 139.61385) (xy 152.29913 139.60565) (xy 152.29913 139.59746) (xy 152.29913 139.58926)
			(xy 152.29913 139.58107) (xy 152.29913 139.57287) (xy 152.29913 139.56468) (xy 152.29913 139.55649)
			(xy 152.29913 139.54829) (xy 152.29913 139.54009) (xy 152.29913 139.5319) (xy 152.29913 139.52371)
			(xy 152.29913 139.51551) (xy 152.29913 139.50732) (xy 152.29913 139.49912) (xy 152.29913 139.49093)
			(xy 152.29913 139.48273) (xy 152.29913 139.47454) (xy 152.29913 139.46634) (xy 152.29913 139.45815)
			(xy 152.29913 139.44996) (xy 152.29913 139.44176) (xy 152.29913 139.43357) (xy 152.29913 139.42537)
			(xy 152.29913 139.41718) (xy 152.29913 139.40898) (xy 152.29913 139.40079) (xy 152.29913 139.39259)
			(xy 152.29913 139.3844) (xy 152.29913 139.37621) (xy 152.29913 139.36801) (xy 152.29913 139.35982)
			(xy 152.29913 139.35162) (xy 152.29913 139.34342) (xy 152.29913 139.33523) (xy 152.29913 139.32704)
			(xy 152.29913 139.31884) (xy 152.29913 139.31065) (xy 152.29913 139.30245) (xy 152.29913 139.29426)
			(xy 152.29913 139.28607) (xy 152.29913 139.27787) (xy 152.29913 139.26968) (xy 152.29913 139.26148)
			(xy 152.29913 139.25329) (xy 152.29913 139.24509) (xy 152.29913 139.2369) (xy 152.29913 139.22871)
			(xy 152.29913 139.22051) (xy 152.29913 139.21232) (xy 152.29913 139.20412) (xy 152.29913 139.19593)
			(xy 152.29913 139.18773) (xy 152.29913 139.17954) (xy 152.29913 139.17134) (xy 152.29913 139.16315)
			(xy 152.29913 139.15495) (xy 152.29913 139.14676) (xy 152.29913 139.13857) (xy 152.29913 139.13037)
			(xy 152.29913 139.12218) (xy 152.29913 139.11398) (xy 152.29913 139.10579) (xy 152.29913 139.09759)
			(xy 152.29913 139.0894) (xy 152.29913 139.0812) (xy 152.29913 139.07301) (xy 152.29913 139.06481)
			(xy 152.29913 139.05662) (xy 152.29913 139.04842) (xy 152.29913 139.04023) (xy 152.29913 139.03204)
			(xy 152.29913 139.02384) (xy 152.29913 139.01565) (xy 152.29913 139.00745) (xy 152.29913 138.99926)
			(xy 152.29913 138.99107) (xy 152.29913 138.98287) (xy 152.29913 138.97467) (xy 152.29913 138.96648)
			(xy 152.29913 138.95829) (xy 152.29913 138.95009) (xy 152.29913 138.9419) (xy 152.29913 138.9337)
			(xy 152.29913 138.92551) (xy 152.29913 138.91731) (xy 152.29913 138.90912) (xy 152.29913 138.90092)
			(xy 152.29913 138.89273) (xy 152.29913 138.88454) (xy 152.29913 138.87634) (xy 152.29913 138.86815)
			(xy 152.29913 138.85995) (xy 152.29913 138.85176) (xy 152.29913 138.84356) (xy 152.29913 138.83537)
			(xy 152.29913 138.82718) (xy 152.29913 138.81898) (xy 152.29913 138.81078) (xy 152.29913 138.80259)
			(xy 152.29913 138.7944) (xy 152.29913 138.7862) (xy 152.29913 138.77801) (xy 152.29913 138.76981)
			(xy 152.29913 138.76162) (xy 152.29913 138.75342) (xy 152.29913 138.74523) (xy 152.29913 138.73704)
			(xy 152.29913 138.72884) (xy 152.29913 138.72065) (xy 152.29913 138.71245) (xy 152.29913 138.70426)
			(xy 152.29913 138.69607) (xy 152.29913 138.68787) (xy 152.29913 138.67967) (xy 152.29913 138.67148)
			(xy 152.29913 138.66328) (xy 152.29913 138.65509) (xy 152.29913 138.6469) (xy 152.29913 138.6387)
			(xy 152.29913 138.63051) (xy 152.29913 138.62231) (xy 152.29913 138.61412) (xy 152.29913 138.60592)
			(xy 152.29913 138.59773) (xy 152.29913 138.58954) (xy 152.29913 138.58134) (xy 152.29913 138.57315)
			(xy 152.29913 138.56495) (xy 152.29913 138.55675) (xy 152.29913 138.54856) (xy 152.29913 138.54037)
			(xy 152.29913 138.53217) (xy 152.29913 138.52398) (xy 152.29913 138.51578) (xy 152.29913 138.50759)
			(xy 152.29913 138.4994) (xy 152.29913 138.4912) (xy 152.29913 138.48301) (xy 152.29913 138.47481)
			(xy 152.29913 138.46662) (xy 152.29913 138.45842) (xy 152.29913 138.45023) (xy 152.29913 138.44203)
			(xy 152.29913 138.43384) (xy 152.29913 138.42564) (xy 152.29913 138.41745) (xy 152.29913 138.40926)
			(xy 152.29913 138.40106) (xy 152.29913 138.39287) (xy 152.29913 138.38467) (xy 152.29913 138.37648)
			(xy 152.29913 138.36828) (xy 152.29913 138.36009) (xy 152.29093 138.36009) (xy 152.29093 138.35189)
			(xy 152.29093 138.3437) (xy 152.29093 138.3355) (xy 152.29093 138.32731) (xy 152.29093 138.31911)
			(xy 152.28274 138.31911) (xy 152.28274 138.31092) (xy 152.28274 138.30273) (xy 152.27455 138.30273)
			(xy 152.27455 138.29453) (xy 152.27455 138.28634) (xy 152.26635 138.28634) (xy 152.26635 138.27814)
			(xy 152.26635 138.26995) (xy 152.25816 138.26995) (xy 152.25816 138.26175) (xy 152.24996 138.26175)
			(xy 152.24996 138.25356) (xy 152.24996 138.24537) (xy 152.24177 138.24537) (xy 152.24177 138.23717)
			(xy 152.23357 138.23717) (xy 152.23357 138.22898) (xy 152.22538 138.22898) (xy 152.22538 138.22078)
			(xy 152.20899 138.22078) (xy 152.20899 138.21259) (xy 152.2008 138.21259) (xy 152.2008 138.20439)
			(xy 152.18441 138.20439) (xy 152.18441 138.1962) (xy 152.16802 138.1962) (xy 152.16802 138.188) (xy 152.15163 138.188)
			(xy 152.15163 138.17981) (xy 152.11885 138.17981) (xy 152.11885 138.17162) (xy 151.07815 138.17162)
			(xy 151.07815 138.16342) (xy 151.07815 138.15523) (xy 151.07815 138.14703) (xy 151.07815 138.13884)
			(xy 151.07815 138.13064) (xy 151.07815 138.12245) (xy 151.07815 138.11425) (xy 151.07815 138.10606)
			(xy 151.07815 138.09786) (xy 151.07815 138.08967) (xy 151.07815 138.08147) (xy 151.07815 138.07328)
			(xy 151.07815 138.06509) (xy 151.07815 138.05689) (xy 151.07815 138.0487) (xy 151.07815 138.0405)
			(xy 151.07815 138.03231) (xy 151.07815 138.02411) (xy 151.07815 138.01592) (xy 151.07815 138.00773)
			(xy 151.07815 137.99953) (xy 151.07815 137.99134) (xy 151.07815 137.98314) (xy 151.07815 137.97495)
			(xy 151.07815 137.96675) (xy 151.07815 137.95856) (xy 151.07815 137.95036) (xy 151.07815 137.94217)
			(xy 151.07815 137.93397) (xy 151.07815 137.92578) (xy 151.07815 137.91759) (xy 151.07815 137.90939)
			(xy 151.07815 137.9012) (xy 151.07815 137.893) (xy 151.07815 137.88481) (xy 151.07815 137.87661)
			(xy 151.07815 137.86842) (xy 151.07815 137.86023) (xy 152.11885 137.86023)
		)
		(stroke
			(width 0)
			(type default)
		)
		(fill yes)
		(layer "F.Cu")
	)
	(gr_poly
		(pts
			(xy 163.25517 137.86842) (xy 163.34531 137.86842) (xy 163.34531 137.87661) (xy 163.37809 137.87661)
			(xy 163.37809 137.88481) (xy 163.41086 137.88481) (xy 163.41086 137.893) (xy 163.43545 137.893) (xy 163.43545 137.9012)
			(xy 163.46003 137.9012) (xy 163.46003 137.90939) (xy 163.47642 137.90939) (xy 163.47642 137.91759)
			(xy 163.49281 137.91759) (xy 163.49281 137.92578) (xy 163.5092 137.92578) (xy 163.5092 137.93397)
			(xy 163.52559 137.93397) (xy 163.52559 137.94217) (xy 163.54198 137.94217) (xy 163.54198 137.95036)
			(xy 163.55017 137.95036) (xy 163.55017 137.95856) (xy 163.56656 137.95856) (xy 163.56656 137.96675)
			(xy 163.57475 137.96675) (xy 163.57475 137.97495) (xy 163.58295 137.97495) (xy 163.58295 137.98314)
			(xy 163.59934 137.98314) (xy 163.59934 137.99134) (xy 163.60753 137.99134) (xy 163.60753 137.99953)
			(xy 163.61573 137.99953) (xy 163.61573 138.00773) (xy 163.62392 138.00773) (xy 163.62392 138.01592)
			(xy 163.63211 138.01592) (xy 163.63211 138.02411) (xy 163.64031 138.02411) (xy 163.64031 138.03231)
			(xy 163.6485 138.03231) (xy 163.6485 138.0405) (xy 163.6567 138.0405) (xy 163.6567 138.0487) (xy 163.66489 138.0487)
			(xy 163.66489 138.05689) (xy 163.67309 138.05689) (xy 163.67309 138.06509) (xy 163.68128 138.06509)
			(xy 163.68128 138.07328) (xy 163.68128 138.08147) (xy 163.68948 138.08147) (xy 163.68948 138.08967)
			(xy 163.69767 138.08967) (xy 163.69767 138.09786) (xy 163.70587 138.09786) (xy 163.70587 138.10606)
			(xy 163.70587 138.11425) (xy 163.71406 138.11425) (xy 163.71406 138.12245) (xy 163.71406 138.13064)
			(xy 163.72226 138.13064) (xy 163.72226 138.13884) (xy 163.73045 138.13884) (xy 163.73045 138.14703)
			(xy 163.73045 138.15523) (xy 163.73864 138.15523) (xy 163.73864 138.16342) (xy 163.73864 138.17162)
			(xy 163.74684 138.17162) (xy 163.74684 138.17981) (xy 163.74684 138.188) (xy 163.75503 138.188) (xy 163.75503 138.1962)
			(xy 163.75503 138.20439) (xy 163.75503 138.21259) (xy 163.76323 138.21259) (xy 163.76323 138.22078)
			(xy 163.76323 138.22898) (xy 163.76323 138.23717) (xy 163.77142 138.23717) (xy 163.77142 138.24537)
			(xy 163.77142 138.25356) (xy 163.77142 138.26175) (xy 163.77962 138.26175) (xy 163.77962 138.26995)
			(xy 163.77962 138.27814) (xy 163.77962 138.28634) (xy 163.77962 138.29453) (xy 163.78781 138.29453)
			(xy 163.78781 138.30273) (xy 163.78781 138.31092) (xy 163.78781 138.31911) (xy 163.78781 138.32731)
			(xy 163.78781 138.3355) (xy 163.78781 138.3437) (xy 163.79601 138.3437) (xy 163.79601 138.35189)
			(xy 163.79601 138.36009) (xy 163.79601 138.36828) (xy 163.79601 138.37648) (xy 163.79601 138.38467)
			(xy 163.79601 138.39287) (xy 163.79601 138.40106) (xy 163.79601 138.40926) (xy 163.79601 138.41745)
			(xy 163.79601 138.42564) (xy 163.79601 138.43384) (xy 163.78781 138.43384) (xy 163.78781 138.44203)
			(xy 163.79601 138.44203) (xy 163.79601 138.45023) (xy 163.78781 138.45023) (xy 163.78781 138.45842)
			(xy 163.78781 138.46662) (xy 163.78781 138.47481) (xy 163.78781 138.48301) (xy 163.78781 138.4912)
			(xy 163.78781 138.4994) (xy 163.78781 138.50759) (xy 163.77962 138.50759) (xy 163.77962 138.51578)
			(xy 163.77962 138.52398) (xy 163.77962 138.53217) (xy 163.77962 138.54037) (xy 163.77142 138.54037)
			(xy 163.77142 138.54856) (xy 163.77142 138.55675) (xy 163.77142 138.56495) (xy 163.76323 138.56495)
			(xy 163.76323 138.57315) (xy 163.76323 138.58134) (xy 163.76323 138.58954) (xy 163.75503 138.58954)
			(xy 163.75503 138.59773) (xy 163.75503 138.60592) (xy 163.75503 138.61412) (xy 163.74684 138.61412)
			(xy 163.74684 138.62231) (xy 163.74684 138.63051) (xy 163.73864 138.63051) (xy 163.73864 138.6387)
			(xy 163.73864 138.6469) (xy 163.73045 138.6469) (xy 163.73045 138.65509) (xy 163.73045 138.66328)
			(xy 163.72226 138.66328) (xy 163.72226 138.67148) (xy 163.71406 138.67148) (xy 163.71406 138.67967)
			(xy 163.71406 138.68787) (xy 163.70587 138.68787) (xy 163.70587 138.69607) (xy 163.69767 138.69607)
			(xy 163.69767 138.70426) (xy 163.69767 138.71245) (xy 163.68948 138.71245) (xy 163.68948 138.72065)
			(xy 163.68128 138.72065) (xy 163.68128 138.72884) (xy 163.67309 138.72884) (xy 163.67309 138.73704)
			(xy 163.67309 138.74523) (xy 163.66489 138.74523) (xy 163.66489 138.75342) (xy 163.6567 138.75342)
			(xy 163.6567 138.76162) (xy 163.6485 138.76162) (xy 163.6485 138.76981) (xy 163.64031 138.76981)
			(xy 163.64031 138.77801) (xy 163.63211 138.77801) (xy 163.63211 138.7862) (xy 163.62392 138.7862)
			(xy 163.62392 138.7944) (xy 163.61573 138.7944) (xy 163.61573 138.80259) (xy 163.60753 138.80259)
			(xy 163.60753 138.81078) (xy 163.59114 138.81078) (xy 163.59114 138.81898) (xy 163.58295 138.81898)
			(xy 163.58295 138.82718) (xy 163.57475 138.82718) (xy 163.57475 138.83537) (xy 163.55836 138.83537)
			(xy 163.55836 138.84356) (xy 163.55017 138.84356) (xy 163.55017 138.85176) (xy 163.53378 138.85176)
			(xy 163.53378 138.85995) (xy 163.52559 138.85995) (xy 163.52559 138.86815) (xy 163.5092 138.86815)
			(xy 163.5092 138.87634) (xy 163.49281 138.87634) (xy 163.49281 138.88454) (xy 163.47642 138.88454)
			(xy 163.47642 138.89273) (xy 163.45183 138.89273) (xy 163.45183 138.90092) (xy 163.43545 138.90092)
			(xy 163.43545 138.90912) (xy 163.40267 138.90912) (xy 163.40267 138.91731) (xy 163.37809 138.91731)
			(xy 163.37809 138.92551) (xy 163.32892 138.92551) (xy 163.32892 138.9337) (xy 162.09155 138.9337)
			(xy 162.09155 138.9419) (xy 162.026 138.9419) (xy 162.026 138.95009) (xy 161.99322 138.95009) (xy 161.99322 138.95829)
			(xy 161.96044 138.95829) (xy 161.96044 138.96648) (xy 161.94405 138.96648) (xy 161.94405 138.97467)
			(xy 161.91947 138.97467) (xy 161.91947 138.98287) (xy 161.90308 138.98287) (xy 161.90308 138.99107)
			(xy 161.88669 138.99107) (xy 161.88669 138.99926) (xy 161.8703 138.99926) (xy 161.8703 139.00745)
			(xy 161.85391 139.00745) (xy 161.85391 139.01565) (xy 161.84572 139.01565) (xy 161.84572 139.02384)
			(xy 161.82933 139.02384) (xy 161.82933 139.03204) (xy 161.81294 139.03204) (xy 161.81294 139.04023)
			(xy 161.80474 139.04023) (xy 161.80474 139.04842) (xy 161.79655 139.04842) (xy 161.79655 139.05662)
			(xy 161.78836 139.05662) (xy 161.78836 139.06481) (xy 161.77196 139.06481) (xy 161.77196 139.07301)
			(xy 161.76377 139.07301) (xy 161.76377 139.0812) (xy 161.75558 139.0812) (xy 161.75558 139.0894)
			(xy 161.74738 139.0894) (xy 161.74738 139.09759) (xy 161.73919 139.09759) (xy 161.73919 139.10579)
			(xy 161.73099 139.10579) (xy 161.73099 139.11398) (xy 161.7228 139.11398) (xy 161.7228 139.12218)
			(xy 161.7146 139.12218) (xy 161.7146 139.13037) (xy 161.7146 139.13857) (xy 161.70641 139.13857)
			(xy 161.70641 139.14676) (xy 161.69821 139.14676) (xy 161.69821 139.15495) (xy 161.69002 139.15495)
			(xy 161.69002 139.16315) (xy 161.69002 139.17134) (xy 161.68183 139.17134) (xy 161.68183 139.17954)
			(xy 161.67363 139.17954) (xy 161.67363 139.18773) (xy 161.67363 139.19593) (xy 161.66544 139.19593)
			(xy 161.66544 139.20412) (xy 161.65724 139.20412) (xy 161.65724 139.21232) (xy 161.65724 139.22051)
			(xy 161.64905 139.22051) (xy 161.64905 139.22871) (xy 161.64905 139.2369) (xy 161.64085 139.2369)
			(xy 161.64085 139.24509) (xy 161.64085 139.25329) (xy 161.63266 139.25329) (xy 161.63266 139.26148)
			(xy 161.63266 139.26968) (xy 161.63266 139.27787) (xy 161.62446 139.27787) (xy 161.62446 139.28607)
			(xy 161.62446 139.29426) (xy 161.61627 139.29426) (xy 161.61627 139.30245) (xy 161.61627 139.31065)
			(xy 161.61627 139.31884) (xy 161.60808 139.31884) (xy 161.60808 139.32704) (xy 161.60808 139.33523)
			(xy 161.60808 139.34342) (xy 161.60808 139.35162) (xy 161.59988 139.35162) (xy 161.59988 139.35982)
			(xy 161.59988 139.36801) (xy 161.59988 139.37621) (xy 161.59988 139.3844) (xy 161.59988 139.39259)
			(xy 161.59988 139.40079) (xy 161.59169 139.40079) (xy 161.59169 139.40898) (xy 161.59169 139.41718)
			(xy 161.59169 139.42537) (xy 161.59169 139.43357) (xy 161.59169 139.44176) (xy 161.59169 139.44996)
			(xy 161.59169 139.45815) (xy 161.59169 139.46634) (xy 161.59169 139.47454) (xy 161.59169 139.48273)
			(xy 161.59169 139.49093) (xy 161.59169 139.49912) (xy 161.59169 139.50732) (xy 161.59169 139.51551)
			(xy 161.59169 139.52371) (xy 161.59169 139.5319) (xy 161.59988 139.5319) (xy 161.59988 139.54009)
			(xy 161.59988 139.54829) (xy 161.59988 139.55649) (xy 161.59988 139.56468) (xy 161.59988 139.57287)
			(xy 161.59988 139.58107) (xy 161.60808 139.58107) (xy 161.60808 139.58926) (xy 161.60808 139.59746)
			(xy 161.60808 139.60565) (xy 161.60808 139.61385) (xy 161.61627 139.61385) (xy 161.61627 139.62204)
			(xy 161.61627 139.63023) (xy 161.61627 139.63843) (xy 161.62446 139.63843) (xy 161.62446 139.64662)
			(xy 161.62446 139.65482) (xy 161.62446 139.66301) (xy 161.63266 139.66301) (xy 161.63266 139.67121)
			(xy 161.63266 139.6794) (xy 161.64085 139.6794) (xy 161.64085 139.6876) (xy 161.64085 139.69579)
			(xy 161.64905 139.69579) (xy 161.64905 139.70398) (xy 161.64905 139.71218) (xy 161.65724 139.71218)
			(xy 161.65724 139.72038) (xy 161.65724 139.72857) (xy 161.66544 139.72857) (xy 161.66544 139.73676)
			(xy 161.66544 139.74496) (xy 161.67363 139.74496) (xy 161.67363 139.75315) (xy 161.68183 139.75315)
			(xy 161.68183 139.76135) (xy 161.68183 139.76954) (xy 161.69002 139.76954) (xy 161.69002 139.77773)
			(xy 161.69821 139.77773) (xy 161.69821 139.78593) (xy 161.69821 139.79413) (xy 161.70641 139.79413)
			(xy 161.70641 139.80232) (xy 161.7146 139.80232) (xy 161.7146 139.81051) (xy 161.7228 139.81051)
			(xy 161.7228 139.81871) (xy 161.73099 139.81871) (xy 161.73099 139.8269) (xy 161.73919 139.8269)
			(xy 161.73919 139.8351) (xy 161.74738 139.8351) (xy 161.74738 139.84329) (xy 161.75558 139.84329)
			(xy 161.75558 139.85149) (xy 161.76377 139.85149) (xy 161.76377 139.85968) (xy 161.77196 139.85968)
			(xy 161.77196 139.86787) (xy 161.78016 139.86787) (xy 161.78016 139.87607) (xy 161.78836 139.87607)
			(xy 161.78836 139.88426) (xy 161.79655 139.88426) (xy 161.79655 139.89246) (xy 161.81294 139.89246)
			(xy 161.81294 139.90065) (xy 161.82113 139.90065) (xy 161.82113 139.90885) (xy 161.83752 139.90885)
			(xy 161.83752 139.91704) (xy 161.84572 139.91704) (xy 161.84572 139.92524) (xy 161.86211 139.92524)
			(xy 161.86211 139.93343) (xy 161.87849 139.93343) (xy 161.87849 139.94163) (xy 161.89488 139.94163)
			(xy 161.89488 139.94982) (xy 161.91127 139.94982) (xy 161.91127 139.95802) (xy 161.92766 139.95802)
			(xy 161.92766 139.96621) (xy 161.95224 139.96621) (xy 161.95224 139.9744) (xy 161.97683 139.9744)
			(xy 161.97683 139.9826) (xy 162.0096 139.9826) (xy 162.0096 139.99079) (xy 162.05058 139.99079) (xy 162.05058 139.99899)
			(xy 168.53242 139.99899) (xy 168.53242 140.00718) (xy 168.54062 140.00718) (xy 168.54062 139.99899)
			(xy 168.54881 139.99899) (xy 168.54881 140.00718) (xy 168.60617 140.00718) (xy 168.60617 140.01538)
			(xy 168.63895 140.01538) (xy 168.63895 140.02357) (xy 168.66354 140.02357) (xy 168.66354 140.03176)
			(xy 168.68812 140.03176) (xy 168.68812 140.03996) (xy 168.7127 140.03996) (xy 168.7127 140.04815)
			(xy 168.72909 140.04815) (xy 168.72909 140.05635) (xy 168.74548 140.05635) (xy 168.74548 140.06454)
			(xy 168.76187 140.06454) (xy 168.76187 140.07274) (xy 168.77826 140.07274) (xy 168.77826 140.08093)
			(xy 168.78645 140.08093) (xy 168.78645 140.08913) (xy 168.80284 140.08913) (xy 168.80284 140.09732)
			(xy 168.81104 140.09732) (xy 168.81104 140.10552) (xy 168.82742 140.10552) (xy 168.82742 140.11371)
			(xy 168.83562 140.11371) (xy 168.83562 140.1219) (xy 168.84381 140.1219) (xy 168.84381 140.1301)
			(xy 168.85201 140.1301) (xy 168.85201 140.1383) (xy 168.8684 140.1383) (xy 168.8684 140.14649) (xy 168.87659 140.14649)
			(xy 168.87659 140.15468) (xy 168.88479 140.15468) (xy 168.88479 140.16288) (xy 168.89298 140.16288)
			(xy 168.89298 140.17107) (xy 168.90118 140.17107) (xy 168.90118 140.17927) (xy 168.90937 140.17927)
			(xy 168.90937 140.18746) (xy 168.90937 140.19565) (xy 168.91756 140.19565) (xy 168.91756 140.20385)
			(xy 168.92576 140.20385) (xy 168.92576 140.21204) (xy 168.93395 140.21204) (xy 168.93395 140.22024)
			(xy 168.94215 140.22024) (xy 168.94215 140.22843) (xy 168.94215 140.23663) (xy 168.95034 140.23663)
			(xy 168.95034 140.24482) (xy 168.95854 140.24482) (xy 168.95854 140.25302) (xy 168.95854 140.26121)
			(xy 168.96673 140.26121) (xy 168.96673 140.2694) (xy 168.97492 140.2694) (xy 168.97492 140.2776)
			(xy 168.97492 140.28579) (xy 168.98312 140.28579) (xy 168.98312 140.29399) (xy 168.98312 140.30218)
			(xy 168.99131 140.30218) (xy 168.99131 140.31038) (xy 168.99131 140.31857) (xy 168.99951 140.31857)
			(xy 168.99951 140.32677) (xy 168.99951 140.33496) (xy 168.99951 140.34316) (xy 169.0077 140.34316)
			(xy 169.0077 140.35135) (xy 169.0077 140.35954) (xy 169.0159 140.35954) (xy 169.0159 140.36774) (xy 169.0159 140.37593)
			(xy 169.0159 140.38413) (xy 169.02409 140.38413) (xy 169.02409 140.39232) (xy 169.02409 140.40052)
			(xy 169.02409 140.40871) (xy 169.02409 140.41691) (xy 169.03229 140.41691) (xy 169.03229 140.4251)
			(xy 169.03229 140.4333) (xy 169.03229 140.44149) (xy 169.03229 140.44969) (xy 169.03229 140.45788)
			(xy 169.04048 140.45788) (xy 169.04048 140.46607) (xy 169.04048 140.47427) (xy 169.04048 140.48246)
			(xy 169.04048 140.49066) (xy 169.04048 140.49885) (xy 169.04048 140.50704) (xy 169.04048 140.51524)
			(xy 169.04048 140.52344) (xy 169.04048 140.53163) (xy 169.04048 140.53982) (xy 169.04048 140.54802)
			(xy 169.04048 140.55621) (xy 169.04048 140.56441) (xy 169.04048 140.5726) (xy 169.04048 140.5808)
			(xy 169.04048 140.58899) (xy 169.04048 140.59718) (xy 169.04048 140.60538) (xy 169.04048 140.61357)
			(xy 169.03229 140.61357) (xy 169.03229 140.62177) (xy 169.03229 140.62996) (xy 169.03229 140.63816)
			(xy 169.03229 140.64635) (xy 169.03229 140.65455) (xy 169.02409 140.65455) (xy 169.02409 140.66274)
			(xy 169.02409 140.67094) (xy 169.02409 140.67913) (xy 169.02409 140.68732) (xy 169.0159 140.68732)
			(xy 169.0159 140.69552) (xy 169.0159 140.70371) (xy 169.0159 140.71191) (xy 169.0077 140.71191) (xy 169.0077 140.7201)
			(xy 169.0077 140.7283) (xy 169.0077 140.73649) (xy 168.99951 140.73649) (xy 168.99951 140.74469)
			(xy 168.99951 140.75288) (xy 168.99131 140.75288) (xy 168.99131 140.76108) (xy 168.99131 140.76927)
			(xy 168.98312 140.76927) (xy 168.98312 140.77746) (xy 168.98312 140.78566) (xy 168.97492 140.78566)
			(xy 168.97492 140.79385) (xy 168.97492 140.80205) (xy 168.96673 140.80205) (xy 168.96673 140.81024)
			(xy 168.96673 140.81844) (xy 168.95854 140.81844) (xy 168.95854 140.82663) (xy 168.95034 140.82663)
			(xy 168.95034 140.83482) (xy 168.95034 140.84302) (xy 168.94215 140.84302) (xy 168.94215 140.85121)
			(xy 168.93395 140.85121) (xy 168.93395 140.85941) (xy 168.92576 140.85941) (xy 168.92576 140.86761)
			(xy 168.91756 140.86761) (xy 168.91756 140.8758) (xy 168.91756 140.88399) (xy 168.90937 140.88399)
			(xy 168.90937 140.89219) (xy 168.90118 140.89219) (xy 168.90118 140.90038) (xy 168.89298 140.90038)
			(xy 168.89298 140.90858) (xy 168.88479 140.90858) (xy 168.88479 140.91677) (xy 168.87659 140.91677)
			(xy 168.87659 140.92496) (xy 168.8684 140.92496) (xy 168.8684 140.93316) (xy 168.8602 140.93316)
			(xy 168.8602 140.94135) (xy 168.85201 140.94135) (xy 168.85201 140.94955) (xy 168.83562 140.94955)
			(xy 168.83562 140.95774) (xy 168.82742 140.95774) (xy 168.82742 140.96594) (xy 168.81923 140.96594)
			(xy 168.81923 140.97413) (xy 168.80284 140.97413) (xy 168.80284 140.98233) (xy 168.79465 140.98233)
			(xy 168.79465 140.99052) (xy 168.77826 140.99052) (xy 168.77826 140.99872) (xy 168.76187 140.99872)
			(xy 168.76187 141.00691) (xy 168.75367 141.00691) (xy 168.75367 141.0151) (xy 168.72909 141.0151)
			(xy 168.72909 141.0233) (xy 168.7127 141.0233) (xy 168.7127 141.03149) (xy 168.69631 141.03149) (xy 168.69631 141.03969)
			(xy 168.67173 141.03969) (xy 168.67173 141.04788) (xy 168.64715 141.04788) (xy 168.64715 141.05608)
			(xy 168.61437 141.05608) (xy 168.61437 141.06427) (xy 168.5652 141.06427) (xy 168.5652 141.07247)
			(xy 164.31226 141.07247) (xy 164.31226 141.08066) (xy 164.26309 141.08066) (xy 164.26309 141.08885)
			(xy 164.23031 141.08885) (xy 164.23031 141.09705) (xy 164.19754 141.09705) (xy 164.19754 141.10525)
			(xy 164.18115 141.10525) (xy 164.18115 141.11344) (xy 164.15656 141.11344) (xy 164.15656 141.12163)
			(xy 164.14017 141.12163) (xy 164.14017 141.12983) (xy 164.12378 141.12983) (xy 164.12378 141.13802)
			(xy 164.1074 141.13802) (xy 164.1074 141.14622) (xy 164.09101 141.14622) (xy 164.09101 141.15441)
			(xy 164.08281 141.15441) (xy 164.08281 141.16261) (xy 164.06642 141.16261) (xy 164.06642 141.1708)
			(xy 164.05823 141.1708) (xy 164.05823 141.179) (xy 164.05003 141.179) (xy 164.05003 141.18719) (xy 164.03365 141.18719)
			(xy 164.03365 141.19538) (xy 164.02545 141.19538) (xy 164.02545 141.20358) (xy 164.01726 141.20358)
			(xy 164.01726 141.21177) (xy 164.00906 141.21177) (xy 164.00906 141.21997) (xy 164.00087 141.21997)
			(xy 164.00087 141.22816) (xy 163.99267 141.22816) (xy 163.99267 141.23636) (xy 163.98448 141.23636)
			(xy 163.98448 141.24455) (xy 163.97629 141.24455) (xy 163.97629 141.25274) (xy 163.96809 141.25274)
			(xy 163.96809 141.26094) (xy 163.9599 141.26094) (xy 163.9599 141.26913) (xy 163.9517 141.26913)
			(xy 163.9517 141.27733) (xy 163.9435 141.27733) (xy 163.9435 141.28552) (xy 163.9435 141.29372) (xy 163.93531 141.29372)
			(xy 163.93531 141.30191) (xy 163.92712 141.30191) (xy 163.92712 141.31011) (xy 163.92712 141.3183)
			(xy 163.91892 141.3183) (xy 163.91892 141.32649) (xy 163.91073 141.32649) (xy 163.91073 141.33469)
			(xy 163.91073 141.34289) (xy 163.90253 141.34289) (xy 163.90253 141.35108) (xy 163.90253 141.35927)
			(xy 163.89434 141.35927) (xy 163.89434 141.36747) (xy 163.89434 141.37566) (xy 163.88614 141.37566)
			(xy 163.88614 141.38386) (xy 163.88614 141.39205) (xy 163.87795 141.39205) (xy 163.87795 141.40025)
			(xy 163.87795 141.40844) (xy 163.86975 141.40844) (xy 163.86975 141.41663) (xy 163.86975 141.42483)
			(xy 163.86975 141.43302) (xy 163.86156 141.43302) (xy 163.86156 141.44122) (xy 163.86156 141.44941)
			(xy 163.86156 141.45761) (xy 163.85337 141.45761) (xy 163.85337 141.4658) (xy 163.85337 141.474)
			(xy 163.85337 141.48219) (xy 163.85337 141.49039) (xy 163.84517 141.49039) (xy 163.84517 141.49858)
			(xy 163.84517 141.50677) (xy 163.84517 141.51497) (xy 163.84517 141.52316) (xy 163.84517 141.53136)
			(xy 163.84517 141.53955) (xy 163.83698 141.53955) (xy 163.83698 141.54775) (xy 163.83698 141.55594)
			(xy 163.83698 141.56413) (xy 163.83698 141.57233) (xy 163.83698 141.58052) (xy 163.83698 141.58872)
			(xy 163.83698 141.59692) (xy 163.83698 141.60511) (xy 163.83698 141.6133) (xy 163.83698 141.6215)
			(xy 163.83698 141.62969) (xy 163.83698 141.63789) (xy 163.83698 141.64608) (xy 163.83698 141.65427)
			(xy 163.83698 141.66247) (xy 163.83698 141.67066) (xy 163.84517 141.67066) (xy 163.84517 141.67886)
			(xy 163.84517 141.68705) (xy 163.84517 141.69525) (xy 163.84517 141.70344) (xy 163.84517 141.71164)
			(xy 163.84517 141.71983) (xy 163.85337 141.71983) (xy 163.85337 141.72803) (xy 163.85337 141.73622)
			(xy 163.85337 141.74441) (xy 163.85337 141.75261) (xy 163.86156 141.75261) (xy 163.86156 141.7608)
			(xy 163.86156 141.769) (xy 163.86156 141.77719) (xy 163.86975 141.77719) (xy 163.86975 141.78539)
			(xy 163.86975 141.79358) (xy 163.86975 141.80177) (xy 163.87795 141.80177) (xy 163.87795 141.80997)
			(xy 163.87795 141.81816) (xy 163.88614 141.81816) (xy 163.88614 141.82636) (xy 163.88614 141.83456)
			(xy 163.89434 141.83456) (xy 163.89434 141.84275) (xy 163.89434 141.85094) (xy 163.90253 141.85094)
			(xy 163.90253 141.85914) (xy 163.90253 141.86733) (xy 163.91073 141.86733) (xy 163.91073 141.87553)
			(xy 163.91073 141.88372) (xy 163.91892 141.88372) (xy 163.91892 141.89192) (xy 163.92712 141.89192)
			(xy 163.92712 141.90011) (xy 163.92712 141.9083) (xy 163.93531 141.9083) (xy 163.93531 141.9165)
			(xy 163.9435 141.9165) (xy 163.9435 141.92469) (xy 163.9517 141.92469) (xy 163.9517 141.93289) (xy 163.9517 141.94108)
			(xy 163.9599 141.94108) (xy 163.9599 141.94927) (xy 163.96809 141.94927) (xy 163.96809 141.95747)
			(xy 163.97629 141.95747) (xy 163.97629 141.96567) (xy 163.98448 141.96567) (xy 163.98448 141.97386)
			(xy 163.99267 141.97386) (xy 163.99267 141.98205) (xy 164.00087 141.98205) (xy 164.00087 141.99025)
			(xy 164.00906 141.99025) (xy 164.00906 141.99844) (xy 164.01726 141.99844) (xy 164.01726 142.00664)
			(xy 164.02545 142.00664) (xy 164.02545 142.01483) (xy 164.04184 142.01483) (xy 164.04184 142.02303)
			(xy 164.05003 142.02303) (xy 164.05003 142.03122) (xy 164.05823 142.03122) (xy 164.05823 142.03942)
			(xy 164.07462 142.03942) (xy 164.07462 142.04761) (xy 164.08281 142.04761) (xy 164.08281 142.0558)
			(xy 164.0992 142.0558) (xy 164.0992 142.064) (xy 164.11559 142.064) (xy 164.11559 142.07219) (xy 164.12378 142.07219)
			(xy 164.12378 142.08039) (xy 164.14017 142.08039) (xy 164.14017 142.08858) (xy 164.16476 142.08858)
			(xy 164.16476 142.09678) (xy 164.18115 142.09678) (xy 164.18115 142.10497) (xy 164.20573 142.10497)
			(xy 164.20573 142.11317) (xy 164.23031 142.11317) (xy 164.23031 142.12136) (xy 164.26309 142.12136)
			(xy 164.26309 142.12956) (xy 164.32045 142.12956) (xy 164.32045 142.13775) (xy 165.8938 142.13775)
			(xy 165.8938 142.14594) (xy 165.93477 142.14594) (xy 165.93477 142.15414) (xy 165.96755 142.15414)
			(xy 165.96755 142.16233) (xy 165.99213 142.16233) (xy 165.99213 142.17053) (xy 166.01671 142.17053)
			(xy 166.01671 142.17872) (xy 166.0413 142.17872) (xy 166.0413 142.18692) (xy 166.05769 142.18692)
			(xy 166.05769 142.19511) (xy 166.07407 142.19511) (xy 166.07407 142.20331) (xy 166.09046 142.20331)
			(xy 166.09046 142.2115) (xy 166.10685 142.2115) (xy 166.10685 142.21969) (xy 166.11504 142.21969)
			(xy 166.11504 142.22789) (xy 166.13144 142.22789) (xy 166.13144 142.23608) (xy 166.13963 142.23608)
			(xy 166.13963 142.24428) (xy 166.14783 142.24428) (xy 166.14783 142.25247) (xy 166.16421 142.25247)
			(xy 166.16421 142.26067) (xy 166.17241 142.26067) (xy 166.17241 142.26886) (xy 166.1806 142.26886)
			(xy 166.1806 142.27706) (xy 166.1888 142.27706) (xy 166.1888 142.28525) (xy 166.19699 142.28525)
			(xy 166.19699 142.29344) (xy 166.20519 142.29344) (xy 166.20519 142.30164) (xy 166.21338 142.30164)
			(xy 166.21338 142.30984) (xy 166.22158 142.30984) (xy 166.22158 142.31803) (xy 166.22977 142.31803)
			(xy 166.22977 142.32622) (xy 166.23796 142.32622) (xy 166.23796 142.33442) (xy 166.24616 142.33442)
			(xy 166.24616 142.34261) (xy 166.25435 142.34261) (xy 166.25435 142.35081) (xy 166.25435 142.359)
			(xy 166.26255 142.359) (xy 166.26255 142.3672) (xy 166.27074 142.3672) (xy 166.27074 142.37539) (xy 166.27894 142.37539)
			(xy 166.27894 142.38359) (xy 166.27894 142.39178) (xy 166.28713 142.39178) (xy 166.28713 142.39997)
			(xy 166.28713 142.40817) (xy 166.29533 142.40817) (xy 166.29533 142.41636) (xy 166.30352 142.41636)
			(xy 166.30352 142.42456) (xy 166.30352 142.43275) (xy 166.31171 142.43275) (xy 166.31171 142.44095)
			(xy 166.31171 142.44914) (xy 166.31991 142.44914) (xy 166.31991 142.45734) (xy 166.31991 142.46553)
			(xy 166.31991 142.47372) (xy 166.32811 142.47372) (xy 166.32811 142.48192) (xy 166.32811 142.49011)
			(xy 166.3363 142.49011) (xy 166.3363 142.49831) (xy 166.3363 142.5065) (xy 166.3363 142.5147) (xy 166.34449 142.5147)
			(xy 166.34449 142.52289) (xy 166.34449 142.53108) (xy 166.34449 142.53928) (xy 166.34449 142.54747)
			(xy 166.35269 142.54747) (xy 166.35269 142.55567) (xy 166.35269 142.56387) (xy 166.35269 142.57206)
			(xy 166.35269 142.58025) (xy 166.35269 142.58845) (xy 166.36088 142.58845) (xy 166.36088 142.59664)
			(xy 166.36088 142.60484) (xy 166.36088 142.61303) (xy 166.36088 142.62123) (xy 166.36088 142.62942)
			(xy 166.36088 142.63761) (xy 166.36088 142.64581) (xy 166.36088 142.654) (xy 166.36088 142.6622)
			(xy 166.36088 142.67039) (xy 166.36088 142.67859) (xy 166.36088 142.68678) (xy 166.36088 142.69498)
			(xy 166.36088 142.70317) (xy 166.36088 142.71136) (xy 166.36088 142.71956) (xy 166.36088 142.72775)
			(xy 166.36088 142.73595) (xy 166.36088 142.74414) (xy 166.36088 142.75234) (xy 166.36088 142.76053)
			(xy 166.35269 142.76053) (xy 166.35269 142.76873) (xy 166.35269 142.77692) (xy 166.35269 142.78511)
			(xy 166.35269 142.79331) (xy 166.35269 142.8015) (xy 166.34449 142.8015) (xy 166.34449 142.8097)
			(xy 166.34449 142.81789) (xy 166.34449 142.82609) (xy 166.3363 142.82609) (xy 166.3363 142.83428)
			(xy 166.3363 142.84248) (xy 166.3363 142.85067) (xy 166.32811 142.85067) (xy 166.32811 142.85887)
			(xy 166.32811 142.86706) (xy 166.32811 142.87525) (xy 166.31991 142.87525) (xy 166.31991 142.88345)
			(xy 166.31991 142.89164) (xy 166.31171 142.89164) (xy 166.31171 142.89984) (xy 166.31171 142.90803)
			(xy 166.30352 142.90803) (xy 166.30352 142.91623) (xy 166.30352 142.92442) (xy 166.29533 142.92442)
			(xy 166.29533 142.93262) (xy 166.29533 142.94081) (xy 166.28713 142.94081) (xy 166.28713 142.949)
			(xy 166.28713 142.9572) (xy 166.27894 142.9572) (xy 166.27894 142.96539) (xy 166.27074 142.96539)
			(xy 166.27074 142.97359) (xy 166.27074 142.98178) (xy 166.26255 142.98178) (xy 166.26255 142.98998)
			(xy 166.25435 142.98998) (xy 166.25435 142.99817) (xy 166.24616 142.99817) (xy 166.24616 143.00637)
			(xy 166.23796 143.00637) (xy 166.23796 143.01456) (xy 166.23796 143.02275) (xy 166.22977 143.02275)
			(xy 166.22977 143.03095) (xy 166.22158 143.03095) (xy 166.22158 143.03915) (xy 166.21338 143.03915)
			(xy 166.21338 143.04734) (xy 166.20519 143.04734) (xy 166.20519 143.05553) (xy 166.19699 143.05553)
			(xy 166.19699 143.06373) (xy 166.1888 143.06373) (xy 166.1888 143.07192) (xy 166.1806 143.07192)
			(xy 166.1806 143.08012) (xy 166.16421 143.08012) (xy 166.16421 143.08831) (xy 166.15602 143.08831)
			(xy 166.15602 143.09651) (xy 166.14783 143.09651) (xy 166.14783 143.1047) (xy 166.13144 143.1047)
			(xy 166.13144 143.1129) (xy 166.12324 143.1129) (xy 166.12324 143.12109) (xy 166.10685 143.12109)
			(xy 166.10685 143.12928) (xy 166.09866 143.12928) (xy 166.09866 143.13748) (xy 166.08227 143.13748)
			(xy 166.08227 143.14567) (xy 166.06588 143.14567) (xy 166.06588 143.15387) (xy 166.04949 143.15387)
			(xy 166.04949 143.16206) (xy 166.0331 143.16206) (xy 166.0331 143.17026) (xy 166.00852 143.17026)
			(xy 166.00852 143.17845) (xy 165.98394 143.17845) (xy 165.98394 143.18664) (xy 165.95935 143.18664)
			(xy 165.95935 143.19484) (xy 165.91838 143.19484) (xy 165.91838 143.20303) (xy 165.86102 143.20303)
			(xy 165.86102 143.21123) (xy 165.84463 143.21123) (xy 165.84463 143.20303) (xy 165.83643 143.20303)
			(xy 165.83643 143.21123) (xy 163.37809 143.21123) (xy 163.37809 143.20303) (xy 163.36989 143.20303)
			(xy 163.36989 143.21123) (xy 163.28795 143.21123) (xy 163.28795 143.21942) (xy 163.24698 143.21942)
			(xy 163.24698 143.22762) (xy 163.21419 143.22762) (xy 163.21419 143.23581) (xy 163.18961 143.23581)
			(xy 163.18961 143.24401) (xy 163.17322 143.24401) (xy 163.17322 143.2522) (xy 163.14864 143.2522)
			(xy 163.14864 143.26039) (xy 163.13225 143.26039) (xy 163.13225 143.26859) (xy 163.11586 143.26859)
			(xy 163.11586 143.27679) (xy 163.10767 143.27679) (xy 163.10767 143.28498) (xy 163.09128 143.28498)
			(xy 163.09128 143.29317) (xy 163.07489 143.29317) (xy 163.07489 143.30137) (xy 163.06669 143.30137)
			(xy 163.06669 143.30956) (xy 163.05031 143.30956) (xy 163.05031 143.31776) (xy 163.04211 143.31776)
			(xy 163.04211 143.32595) (xy 163.03392 143.32595) (xy 163.03392 143.33415) (xy 163.02572 143.33415)
			(xy 163.02572 143.34234) (xy 163.00933 143.34234) (xy 163.00933 143.35054) (xy 163.00114 143.35054)
			(xy 163.00114 143.35873) (xy 162.99295 143.35873) (xy 162.99295 143.36692) (xy 162.98475 143.36692)
			(xy 162.98475 143.37512) (xy 162.97655 143.37512) (xy 162.97655 143.38331) (xy 162.96836 143.38331)
			(xy 162.96836 143.39151) (xy 162.96836 143.3997) (xy 162.96017 143.3997) (xy 162.96017 143.4079)
			(xy 162.95197 143.4079) (xy 162.95197 143.41609) (xy 162.94378 143.41609) (xy 162.94378 143.42429)
			(xy 162.93558 143.42429) (xy 162.93558 143.43248) (xy 162.93558 143.44067) (xy 162.92739 143.44067)
			(xy 162.92739 143.44887) (xy 162.91919 143.44887) (xy 162.91919 143.45706) (xy 162.91919 143.46526)
			(xy 162.911 143.46526) (xy 162.911 143.47345) (xy 162.9028 143.47345) (xy 162.9028 143.48165) (xy 162.9028 143.48984)
			(xy 162.89461 143.48984) (xy 162.89461 143.49803) (xy 162.89461 143.50623) (xy 162.88642 143.50623)
			(xy 162.88642 143.51443) (xy 162.88642 143.52262) (xy 162.87822 143.52262) (xy 162.87822 143.53082)
			(xy 162.87822 143.53901) (xy 162.87003 143.53901) (xy 162.87003 143.5472) (xy 162.87003 143.5554)
			(xy 162.87003 143.56359) (xy 162.86183 143.56359) (xy 162.86183 143.57179) (xy 162.86183 143.57998)
			(xy 162.86183 143.58818) (xy 162.85364 143.58818) (xy 162.85364 143.59637) (xy 162.85364 143.60456)
			(xy 162.85364 143.61276) (xy 162.84544 143.61276) (xy 162.84544 143.62095) (xy 162.84544 143.62915)
			(xy 162.84544 143.63734) (xy 162.84544 143.64554) (xy 162.84544 143.65373) (xy 162.83725 143.65373)
			(xy 162.83725 143.66193) (xy 162.83725 143.67012) (xy 162.83725 143.67831) (xy 162.83725 143.68651)
			(xy 162.83725 143.6947) (xy 162.83725 143.7029) (xy 162.83725 143.71109) (xy 162.83725 143.71929)
			(xy 162.83725 143.72748) (xy 162.83725 143.73567) (xy 162.83725 143.74387) (xy 162.83725 143.75206)
			(xy 162.83725 143.76026) (xy 162.83725 143.76846) (xy 162.83725 143.77665) (xy 162.83725 143.78484)
			(xy 162.83725 143.79304) (xy 162.83725 143.80123) (xy 162.83725 143.80943) (xy 162.83725 143.81762)
			(xy 162.83725 143.82582) (xy 162.84544 143.82582) (xy 162.84544 143.83401) (xy 162.84544 143.8422)
			(xy 162.84544 143.8504) (xy 162.84544 143.85859) (xy 162.84544 143.86679) (xy 162.85364 143.86679)
			(xy 162.85364 143.87498) (xy 162.85364 143.88318) (xy 162.85364 143.89137) (xy 162.86183 143.89137)
			(xy 162.86183 143.89957) (xy 162.86183 143.90776) (xy 162.86183 143.91596) (xy 162.87003 143.91596)
			(xy 162.87003 143.92415) (xy 162.87003 143.93234) (xy 162.87003 143.94054) (xy 162.87822 143.94054)
			(xy 162.87822 143.94873) (xy 162.87822 143.95693) (xy 162.88642 143.95693) (xy 162.88642 143.96512)
			(xy 162.88642 143.97332) (xy 162.89461 143.97332) (xy 162.89461 143.98151) (xy 162.89461 143.9897)
			(xy 162.9028 143.9897) (xy 162.9028 143.9979) (xy 162.9028 144.0061) (xy 162.911 144.0061) (xy 162.911 144.01429)
			(xy 162.911 144.02248) (xy 162.91919 144.02248) (xy 162.91919 144.03068) (xy 162.92739 144.03068)
			(xy 162.92739 144.03887) (xy 162.92739 144.04707) (xy 162.93558 144.04707) (xy 162.93558 144.05526)
			(xy 162.94378 144.05526) (xy 162.94378 144.06346) (xy 162.95197 144.06346) (xy 162.95197 144.07165)
			(xy 162.95197 144.07985) (xy 162.96017 144.07985) (xy 162.96017 144.08804) (xy 162.96836 144.08804)
			(xy 162.96836 144.09623) (xy 162.97655 144.09623) (xy 162.97655 144.10443) (xy 162.98475 144.10443)
			(xy 162.98475 144.11262) (xy 162.99295 144.11262) (xy 162.99295 144.12082) (xy 163.00114 144.12082)
			(xy 163.00114 144.12901) (xy 163.00933 144.12901) (xy 163.00933 144.13721) (xy 163.01753 144.13721)
			(xy 163.01753 144.1454) (xy 163.02572 144.1454) (xy 163.02572 144.1536) (xy 163.04211 144.1536) (xy 163.04211 144.16179)
			(xy 163.05031 144.16179) (xy 163.05031 144.16998) (xy 163.0585 144.16998) (xy 163.0585 144.17818)
			(xy 163.07489 144.17818) (xy 163.07489 144.18637) (xy 163.08308 144.18637) (xy 163.08308 144.19457)
			(xy 163.09947 144.19457) (xy 163.09947 144.20276) (xy 163.11586 144.20276) (xy 163.11586 144.21096)
			(xy 163.13225 144.21096) (xy 163.13225 144.21915) (xy 163.14864 144.21915) (xy 163.14864 144.22734)
			(xy 163.16503 144.22734) (xy 163.16503 144.23554) (xy 163.18961 144.23554) (xy 163.18961 144.24374)
			(xy 163.206 144.24374) (xy 163.206 144.25193) (xy 163.23878 144.25193) (xy 163.23878 144.26012) (xy 163.27975 144.26012)
			(xy 163.27975 144.26832) (xy 163.3535 144.26832) (xy 163.3535 144.27651) (xy 165.04976 144.27651)
			(xy 165.04976 144.28471) (xy 165.09073 144.28471) (xy 165.09073 144.2929) (xy 165.11532 144.2929)
			(xy 165.11532 144.3011) (xy 165.1399 144.3011) (xy 165.1399 144.30929) (xy 165.16449 144.30929) (xy 165.16449 144.31749)
			(xy 165.18907 144.31749) (xy 165.18907 144.32568) (xy 165.20546 144.32568) (xy 165.20546 144.33387)
			(xy 165.22185 144.33387) (xy 165.22185 144.34207) (xy 165.23004 144.34207) (xy 165.23004 144.35026)
			(xy 165.24643 144.35026) (xy 165.24643 144.35846) (xy 165.26282 144.35846) (xy 165.26282 144.36665)
			(xy 165.27101 144.36665) (xy 165.27101 144.37485) (xy 165.2874 144.37485) (xy 165.2874 144.38304)
			(xy 165.2956 144.38304) (xy 165.2956 144.39124) (xy 165.30379 144.39124) (xy 165.30379 144.39943)
			(xy 165.31199 144.39943) (xy 165.31199 144.40762) (xy 165.32838 144.40762) (xy 165.32838 144.41582)
			(xy 165.33657 144.41582) (xy 165.33657 144.42401) (xy 165.34476 144.42401) (xy 165.34476 144.43221)
			(xy 165.35296 144.43221) (xy 165.35296 144.4404) (xy 165.36116 144.4404) (xy 165.36116 144.4486)
			(xy 165.36935 144.4486) (xy 165.36935 144.45679) (xy 165.36935 144.46498) (xy 165.37754 144.46498)
			(xy 165.37754 144.47318) (xy 165.38573 144.47318) (xy 165.38573 144.48138) (xy 165.39393 144.48138)
			(xy 165.39393 144.48957) (xy 165.40213 144.48957) (xy 165.40213 144.49777) (xy 165.40213 144.50596)
			(xy 165.41032 144.50596) (xy 165.41032 144.51415) (xy 165.41852 144.51415) (xy 165.41852 144.52235)
			(xy 165.41852 144.53054) (xy 165.42671 144.53054) (xy 165.42671 144.53874) (xy 165.4349 144.53874)
			(xy 165.4349 144.54693) (xy 165.4349 144.55513) (xy 165.4431 144.55513) (xy 165.4431 144.56332) (xy 165.4431 144.57151)
			(xy 165.45129 144.57151) (xy 165.45129 144.57971) (xy 165.45129 144.5879) (xy 165.45949 144.5879)
			(xy 165.45949 144.5961) (xy 165.45949 144.60429) (xy 165.46768 144.60429) (xy 165.46768 144.61249)
			(xy 165.46768 144.62068) (xy 165.46768 144.62888) (xy 165.47588 144.62888) (xy 165.47588 144.63707)
			(xy 165.47588 144.64527) (xy 165.47588 144.65346) (xy 165.48407 144.65346) (xy 165.48407 144.66165)
			(xy 165.48407 144.66985) (xy 165.48407 144.67804) (xy 165.49227 144.67804) (xy 165.49227 144.68624)
			(xy 165.49227 144.69443) (xy 165.49227 144.70262) (xy 165.49227 144.71082) (xy 165.49227 144.71901)
			(xy 165.49227 144.72721) (xy 165.50046 144.72721) (xy 165.50046 144.73541) (xy 165.50046 144.7436)
			(xy 165.50046 144.75179) (xy 165.50046 144.75999) (xy 165.50046 144.76818) (xy 165.50046 144.77638)
			(xy 165.50046 144.78457) (xy 165.50046 144.79277) (xy 165.50046 144.80096) (xy 165.50865 144.80096)
			(xy 165.50865 144.80915) (xy 165.50865 144.81735) (xy 165.50046 144.81735) (xy 165.50046 144.82554)
			(xy 165.50046 144.83374) (xy 165.50046 144.84193) (xy 165.50046 144.85013) (xy 165.50046 144.85832)
			(xy 165.50046 144.86652) (xy 165.50046 144.87471) (xy 165.50046 144.8829) (xy 165.50046 144.8911)
			(xy 165.50046 144.89929) (xy 165.49227 144.89929) (xy 165.49227 144.90749) (xy 165.49227 144.91568)
			(xy 165.49227 144.92388) (xy 165.49227 144.93207) (xy 165.49227 144.94027) (xy 165.48407 144.94027)
			(xy 165.48407 144.94846) (xy 165.48407 144.95665) (xy 165.48407 144.96485) (xy 165.47588 144.96485)
			(xy 165.47588 144.97305) (xy 165.47588 144.98124) (xy 165.47588 144.98943) (xy 165.46768 144.98943)
			(xy 165.46768 144.99763) (xy 165.46768 145.00582) (xy 165.46768 145.01402) (xy 165.45949 145.01402)
			(xy 165.45949 145.02221) (xy 165.45949 145.03041) (xy 165.45949 145.0386) (xy 165.45129 145.0386)
			(xy 165.45129 145.04679) (xy 165.45129 145.05499) (xy 165.4431 145.05499) (xy 165.4431 145.06318)
			(xy 165.4431 145.07138) (xy 165.4349 145.07138) (xy 165.4349 145.07957) (xy 165.4349 145.08777) (xy 165.42671 145.08777)
			(xy 165.42671 145.09596) (xy 165.41852 145.09596) (xy 165.41852 145.10416) (xy 165.41852 145.11235)
			(xy 165.41032 145.11235) (xy 165.41032 145.12054) (xy 165.40213 145.12054) (xy 165.40213 145.12874)
			(xy 165.40213 145.13693) (xy 165.39393 145.13693) (xy 165.39393 145.14513) (xy 165.38573 145.14513)
			(xy 165.38573 145.15332) (xy 165.37754 145.15332) (xy 165.37754 145.16152) (xy 165.37754 145.16971)
			(xy 165.36935 145.16971) (xy 165.36935 145.17791) (xy 165.36116 145.17791) (xy 165.36116 145.1861)
			(xy 165.35296 145.1861) (xy 165.35296 145.19429) (xy 165.34476 145.19429) (xy 165.34476 145.20249)
			(xy 165.33657 145.20249) (xy 165.33657 145.21069) (xy 165.32838 145.21069) (xy 165.32838 145.21888)
			(xy 165.32018 145.21888) (xy 165.32018 145.22707) (xy 165.31199 145.22707) (xy 165.31199 145.23527)
			(xy 165.30379 145.23527) (xy 165.30379 145.24346) (xy 165.2956 145.24346) (xy 165.2956 145.25166)
			(xy 165.27921 145.25166) (xy 165.27921 145.25985) (xy 165.27101 145.25985) (xy 165.27101 145.26805)
			(xy 165.26282 145.26805) (xy 165.26282 145.27624) (xy 165.24643 145.27624) (xy 165.24643 145.28444)
			(xy 165.23824 145.28444) (xy 165.23824 145.29263) (xy 165.22185 145.29263) (xy 165.22185 145.30082)
			(xy 165.20546 145.30082) (xy 165.20546 145.30902) (xy 165.18907 145.30902) (xy 165.18907 145.31721)
			(xy 165.17268 145.31721) (xy 165.17268 145.32541) (xy 165.14809 145.32541) (xy 165.14809 145.3336)
			(xy 165.11532 145.3336) (xy 165.11532 145.3418) (xy 159.21528 145.3418) (xy 159.21528 145.34999)
			(xy 159.19889 145.34999) (xy 159.19889 145.35819) (xy 159.1907 145.35819) (xy 159.1907 145.36638)
			(xy 159.18251 145.36638) (xy 159.18251 145.37458) (xy 159.17431 145.37458) (xy 159.17431 145.38277)
			(xy 159.17431 145.39096) (xy 159.16612 145.39096) (xy 159.16612 145.39916) (xy 159.16612 145.40735)
			(xy 159.16612 145.41555) (xy 159.16612 145.42374) (xy 159.16612 145.43193) (xy 159.16612 145.44013)
			(xy 159.16612 145.44833) (xy 159.16612 145.45652) (xy 159.16612 145.46472) (xy 159.16612 145.47291)
			(xy 159.16612 145.4811) (xy 159.16612 145.4893) (xy 159.16612 145.49749) (xy 159.16612 145.50569)
			(xy 159.16612 145.51388) (xy 159.16612 145.52208) (xy 159.16612 145.53027) (xy 159.16612 145.53846)
			(xy 159.16612 145.54666) (xy 159.16612 145.55485) (xy 159.16612 145.56305) (xy 159.16612 145.57124)
			(xy 159.16612 145.57944) (xy 159.16612 145.58763) (xy 159.16612 145.59583) (xy 159.16612 145.60402)
			(xy 159.16612 145.61221) (xy 159.16612 145.62041) (xy 159.16612 145.6286) (xy 159.16612 145.6368)
			(xy 159.16612 145.64499) (xy 159.16612 145.65319) (xy 159.16612 145.66138) (xy 159.16612 145.66958)
			(xy 159.16612 145.67777) (xy 159.16612 145.68597) (xy 159.16612 145.69416) (xy 159.16612 145.70236)
			(xy 159.16612 145.71055) (xy 159.16612 145.71874) (xy 159.16612 145.72694) (xy 159.16612 145.73513)
			(xy 159.16612 145.74333) (xy 159.16612 145.75152) (xy 159.16612 145.75972) (xy 159.16612 145.76791)
			(xy 159.16612 145.7761) (xy 159.16612 145.7843) (xy 159.16612 145.7925) (xy 159.16612 145.80069)
			(xy 159.16612 145.80888) (xy 159.16612 145.81708) (xy 159.16612 145.82527) (xy 159.16612 145.83347)
			(xy 159.16612 145.84166) (xy 159.16612 145.84985) (xy 159.16612 145.85805) (xy 159.16612 145.86625)
			(xy 159.16612 145.87444) (xy 159.16612 145.88263) (xy 159.16612 145.89083) (xy 159.16612 145.89902)
			(xy 159.16612 145.90722) (xy 159.16612 145.91541) (xy 159.16612 145.9236) (xy 159.16612 145.9318)
			(xy 159.16612 145.94) (xy 159.16612 145.94819) (xy 159.16612 145.95638) (xy 159.16612 145.96458)
			(xy 159.16612 145.97277) (xy 159.16612 145.98097) (xy 159.16612 145.98916) (xy 159.16612 145.99736)
			(xy 159.16612 146.00555) (xy 159.16612 146.01375) (xy 159.16612 146.02194) (xy 159.16612 146.03014)
			(xy 159.16612 146.03833) (xy 159.16612 146.04652) (xy 159.16612 146.05472) (xy 159.16612 146.06291)
			(xy 159.16612 146.07111) (xy 159.16612 146.0793) (xy 159.16612 146.0875) (xy 159.16612 146.09569)
			(xy 159.16612 146.10388) (xy 159.16612 146.11208) (xy 159.16612 146.12027) (xy 159.16612 146.12847)
			(xy 159.16612 146.13666) (xy 159.16612 146.14486) (xy 159.16612 146.15305) (xy 159.16612 146.16125)
			(xy 159.16612 146.16944) (xy 159.16612 146.17764) (xy 159.16612 146.18583) (xy 159.16612 146.19402)
			(xy 159.16612 146.20222) (xy 159.15792 146.20222) (xy 159.15792 146.21041) (xy 159.15792 146.21861)
			(xy 159.14973 146.21861) (xy 159.14973 146.2268) (xy 159.14973 146.235) (xy 159.14153 146.235) (xy 159.14153 146.24319)
			(xy 159.12515 146.24319) (xy 159.12515 146.25139) (xy 159.10875 146.25139) (xy 159.10875 146.25958)
			(xy 157.54361 146.25958) (xy 157.54361 146.25139) (xy 157.51902 146.25139) (xy 157.51902 146.24319)
			(xy 157.51083 146.24319) (xy 157.51083 146.235) (xy 157.50263 146.235) (xy 157.50263 146.2268) (xy 157.49444 146.2268)
			(xy 157.49444 146.21861) (xy 157.49444 146.21041) (xy 157.48624 146.21041) (xy 157.48624 146.20222)
			(xy 157.48624 146.19402) (xy 157.48624 146.18583) (xy 157.48624 146.17764) (xy 157.48624 146.16944)
			(xy 157.48624 146.16125) (xy 157.48624 146.15305) (xy 157.48624 146.14486) (xy 157.48624 146.13666)
			(xy 157.48624 146.12847) (xy 157.48624 146.12027) (xy 157.48624 146.11208) (xy 157.48624 146.10388)
			(xy 157.48624 146.09569) (xy 157.48624 146.0875) (xy 157.48624 146.0793) (xy 157.48624 146.07111)
			(xy 157.48624 146.06291) (xy 157.48624 146.05472) (xy 157.48624 146.04652) (xy 157.48624 146.03833)
			(xy 157.48624 146.03014) (xy 157.48624 146.02194) (xy 157.48624 146.01375) (xy 157.48624 146.00555)
			(xy 157.48624 145.99736) (xy 157.48624 145.98916) (xy 157.48624 145.98097) (xy 157.48624 145.97277)
			(xy 157.48624 145.96458) (xy 157.48624 145.95638) (xy 157.48624 145.94819) (xy 157.48624 145.94)
			(xy 157.48624 145.9318) (xy 157.48624 145.9236) (xy 157.48624 145.91541) (xy 157.48624 145.90722)
			(xy 157.48624 145.89902) (xy 157.48624 145.89083) (xy 157.48624 145.88263) (xy 157.48624 145.87444)
			(xy 157.48624 145.86625) (xy 157.48624 145.85805) (xy 157.48624 145.84985) (xy 157.48624 145.84166)
			(xy 157.48624 145.83347) (xy 157.48624 145.82527) (xy 157.48624 145.81708) (xy 157.48624 145.80888)
			(xy 157.48624 145.80069) (xy 157.48624 145.7925) (xy 157.48624 145.7843) (xy 157.48624 145.7761)
			(xy 157.48624 145.76791) (xy 157.48624 145.75972) (xy 157.48624 145.75152) (xy 157.48624 145.74333)
			(xy 157.48624 145.73513) (xy 157.48624 145.72694) (xy 157.48624 145.71874) (xy 157.48624 145.71055)
			(xy 157.47805 145.71055) (xy 157.47805 145.70236) (xy 157.47805 145.69416) (xy 157.47805 145.68597)
			(xy 157.46986 145.68597) (xy 157.46986 145.67777) (xy 157.46986 145.66958) (xy 157.46166 145.66958)
			(xy 157.46166 145.66138) (xy 157.44527 145.66138) (xy 157.44527 145.65319) (xy 157.42069 145.65319)
			(xy 157.42069 145.64499) (xy 157.39611 145.64499) (xy 157.39611 145.65319) (xy 157.37152 145.65319)
			(xy 157.37152 145.66138) (xy 157.36333 145.66138) (xy 157.36333 145.66958) (xy 157.35513 145.66958)
			(xy 157.35513 145.67777) (xy 157.34694 145.67777) (xy 157.34694 145.68597) (xy 157.33875 145.68597)
			(xy 157.33875 145.69416) (xy 157.33875 145.70236) (xy 157.33875 145.71055) (xy 157.33875 145.71874)
			(xy 157.33055 145.71874) (xy 157.33055 145.72694) (xy 157.33055 145.73513) (xy 157.33055 145.74333)
			(xy 157.33055 145.75152) (xy 157.33055 145.75972) (xy 157.33055 145.76791) (xy 157.33055 145.7761)
			(xy 157.33055 145.7843) (xy 157.33055 145.7925) (xy 157.33055 145.80069) (xy 157.33055 145.80888)
			(xy 157.33055 145.81708) (xy 157.33055 145.82527) (xy 157.33055 145.83347) (xy 157.33055 145.84166)
			(xy 157.33055 145.84985) (xy 157.33055 145.85805) (xy 157.33055 145.86625) (xy 157.33055 145.87444)
			(xy 157.33055 145.88263) (xy 157.33055 145.89083) (xy 157.33055 145.89902) (xy 157.33055 145.90722)
			(xy 157.33055 145.91541) (xy 157.33055 145.9236) (xy 157.33055 145.9318) (xy 157.33055 145.94) (xy 157.33055 145.94819)
			(xy 157.33055 145.95638) (xy 157.33055 145.96458) (xy 157.33055 145.97277) (xy 157.33055 145.98097)
			(xy 157.33055 145.98916) (xy 157.33055 145.99736) (xy 157.33055 146.00555) (xy 157.33055 146.01375)
			(xy 157.33055 146.02194) (xy 157.33055 146.03014) (xy 157.33055 146.03833) (xy 157.33055 146.04652)
			(xy 157.33055 146.05472) (xy 157.33055 146.06291) (xy 157.33055 146.07111) (xy 157.33055 146.0793)
			(xy 157.33055 146.0875) (xy 157.33055 146.09569) (xy 157.33055 146.10388) (xy 157.33055 146.11208)
			(xy 157.33055 146.12027) (xy 157.33055 146.12847) (xy 157.33055 146.13666) (xy 157.33055 146.14486)
			(xy 157.33055 146.15305) (xy 157.33055 146.16125) (xy 157.33055 146.16944) (xy 157.33055 146.17764)
			(xy 157.33055 146.18583) (xy 157.33055 146.19402) (xy 157.33055 146.20222) (xy 157.33055 146.21041)
			(xy 157.33055 146.21861) (xy 157.32235 146.21861) (xy 157.32235 146.2268) (xy 157.31416 146.2268)
			(xy 157.31416 146.235) (xy 157.30597 146.235) (xy 157.30597 146.24319) (xy 157.29777 146.24319) (xy 157.29777 146.25139)
			(xy 157.27319 146.25139) (xy 157.27319 146.25958) (xy 156.47013 146.25958) (xy 156.47013 146.25139)
			(xy 156.45374 146.25139) (xy 156.45374 146.24319) (xy 156.43735 146.24319) (xy 156.43735 146.235)
			(xy 156.42916 146.235) (xy 156.42916 146.2268) (xy 156.42916 146.21861) (xy 156.42096 146.21861)
			(xy 156.42096 146.21041) (xy 156.42096 146.20222) (xy 156.42096 146.19402) (xy 156.41277 146.19402)
			(xy 156.41277 146.18583) (xy 156.41277 146.17764) (xy 156.41277 146.16944) (xy 156.41277 146.16125)
			(xy 156.41277 146.15305) (xy 156.41277 146.14486) (xy 156.41277 146.13666) (xy 156.41277 146.12847)
			(xy 156.41277 146.12027) (xy 156.41277 146.11208) (xy 156.41277 146.10388) (xy 156.41277 146.09569)
			(xy 156.41277 146.0875) (xy 156.41277 146.0793) (xy 156.41277 146.07111) (xy 156.41277 146.06291)
			(xy 156.41277 146.05472) (xy 156.41277 146.04652) (xy 156.41277 146.03833) (xy 156.41277 146.03014)
			(xy 156.41277 146.02194) (xy 156.41277 146.01375) (xy 156.41277 146.00555) (xy 156.41277 145.99736)
			(xy 156.41277 145.98916) (xy 156.41277 145.98097) (xy 156.41277 145.97277) (xy 156.41277 145.96458)
			(xy 156.41277 145.95638) (xy 156.41277 145.94819) (xy 156.41277 145.94) (xy 156.41277 145.9318) (xy 156.41277 145.9236)
			(xy 156.41277 145.91541) (xy 156.41277 145.90722) (xy 156.41277 145.89902) (xy 156.41277 145.89083)
			(xy 156.41277 145.88263) (xy 156.41277 145.87444) (xy 156.41277 145.86625) (xy 156.41277 145.85805)
			(xy 156.41277 145.84985) (xy 156.41277 145.84166) (xy 156.41277 145.83347) (xy 156.41277 145.82527)
			(xy 156.41277 145.81708) (xy 156.41277 145.80888) (xy 156.41277 145.80069) (xy 156.41277 145.7925)
			(xy 156.41277 145.7843) (xy 156.41277 145.7761) (xy 156.41277 145.76791) (xy 156.41277 145.75972)
			(xy 156.41277 145.75152) (xy 156.41277 145.74333) (xy 156.41277 145.73513) (xy 156.41277 145.72694)
			(xy 156.41277 145.71874) (xy 156.41277 145.71055) (xy 156.41277 145.70236) (xy 156.41277 145.69416)
			(xy 156.41277 145.68597) (xy 156.41277 145.67777) (xy 156.41277 145.66958) (xy 156.41277 145.66138)
			(xy 156.41277 145.65319) (xy 156.41277 145.64499) (xy 156.41277 145.6368) (xy 156.41277 145.6286)
			(xy 156.41277 145.62041) (xy 156.41277 145.61221) (xy 156.41277 145.60402) (xy 156.41277 145.59583)
			(xy 156.41277 145.58763) (xy 156.41277 145.57944) (xy 156.41277 145.57124) (xy 156.41277 145.56305)
			(xy 156.41277 145.55485) (xy 156.41277 145.54666) (xy 156.41277 145.53846) (xy 156.41277 145.53027)
			(xy 156.42096 145.53027) (xy 156.42096 145.52208) (xy 156.41277 145.52208) (xy 156.41277 145.51388)
			(xy 156.41277 145.50569) (xy 156.41277 145.49749) (xy 156.41277 145.4893) (xy 156.41277 145.4811)
			(xy 156.41277 145.47291) (xy 156.41277 145.46472) (xy 156.41277 145.45652) (xy 156.41277 145.44833)
			(xy 156.40457 145.44833) (xy 156.40457 145.44013) (xy 156.40457 145.43193) (xy 156.39638 145.43193)
			(xy 156.39638 145.42374) (xy 156.39638 145.41555) (xy 156.38818 145.41555) (xy 156.38818 145.40735)
			(xy 156.38818 145.39916) (xy 156.37999 145.39916) (xy 156.37999 145.39096) (xy 156.3718 145.39096)
			(xy 156.3718 145.38277) (xy 156.3636 145.38277) (xy 156.3636 145.37458) (xy 156.3554 145.37458) (xy 156.3554 145.36638)
			(xy 156.33901 145.36638) (xy 156.33901 145.35819) (xy 156.32263 145.35819) (xy 156.32263 145.34999)
			(xy 156.29804 145.34999) (xy 156.29804 145.3418) (xy 156.23249 145.3418) (xy 156.23249 145.34999)
			(xy 156.2079 145.34999) (xy 156.2079 145.35819) (xy 156.19152 145.35819) (xy 156.19152 145.36638)
			(xy 156.17513 145.36638) (xy 156.17513 145.37458) (xy 156.16693 145.37458) (xy 156.16693 145.38277)
			(xy 156.15874 145.38277) (xy 156.15874 145.39096) (xy 156.15054 145.39096) (xy 156.15054 145.39916)
			(xy 156.14235 145.39916) (xy 156.14235 145.40735) (xy 156.13415 145.40735) (xy 156.13415 145.41555)
			(xy 156.13415 145.42374) (xy 156.12596 145.42374) (xy 156.12596 145.43193) (xy 156.12596 145.44013)
			(xy 156.11776 145.44013) (xy 156.11776 145.44833) (xy 156.11776 145.45652) (xy 156.11776 145.46472)
			(xy 156.11776 145.47291) (xy 156.11776 145.4811) (xy 156.11776 145.4893) (xy 156.10957 145.4893)
			(xy 156.10957 145.49749) (xy 156.11776 145.49749) (xy 156.11776 145.50569) (xy 156.11776 145.51388)
			(xy 156.10957 145.51388) (xy 156.10957 145.52208) (xy 156.11776 145.52208) (xy 156.11776 145.53027)
			(xy 156.11776 145.53846) (xy 156.11776 145.54666) (xy 156.11776 145.55485) (xy 156.11776 145.56305)
			(xy 156.11776 145.57124) (xy 156.11776 145.57944) (xy 156.11776 145.58763) (xy 156.11776 145.59583)
			(xy 156.11776 145.60402) (xy 156.11776 145.61221) (xy 156.11776 145.62041) (xy 156.11776 145.6286)
			(xy 156.11776 145.6368) (xy 156.11776 145.64499) (xy 156.11776 145.65319) (xy 156.11776 145.66138)
			(xy 156.11776 145.66958) (xy 156.11776 145.67777) (xy 156.11776 145.68597) (xy 156.11776 145.69416)
			(xy 156.11776 145.70236) (xy 156.11776 145.71055) (xy 156.11776 145.71874) (xy 156.11776 145.72694)
			(xy 156.11776 145.73513) (xy 156.11776 145.74333) (xy 156.11776 145.75152) (xy 156.11776 145.75972)
			(xy 156.11776 145.76791) (xy 156.11776 145.7761) (xy 156.11776 145.7843) (xy 156.11776 145.7925)
			(xy 156.11776 145.80069) (xy 156.11776 145.80888) (xy 156.11776 145.81708) (xy 156.11776 145.82527)
			(xy 156.11776 145.83347) (xy 156.11776 145.84166) (xy 156.11776 145.84985) (xy 156.11776 145.85805)
			(xy 156.11776 145.86625) (xy 156.11776 145.87444) (xy 156.10957 145.87444) (xy 156.10957 145.88263)
			(xy 156.10957 145.89083) (xy 156.10957 145.89902) (xy 156.10957 145.90722) (xy 156.10137 145.90722)
			(xy 156.10137 145.91541) (xy 156.09318 145.91541) (xy 156.09318 145.9236) (xy 156.08499 145.9236)
			(xy 156.08499 145.9318) (xy 156.07679 145.9318) (xy 156.07679 145.94) (xy 156.05221 145.94) (xy 156.05221 145.94819)
			(xy 155.56054 145.94819) (xy 155.56054 145.94) (xy 155.53596 145.94) (xy 155.53596 145.9318) (xy 155.52776 145.9318)
			(xy 155.52776 145.9236) (xy 155.51957 145.9236) (xy 155.51957 145.91541) (xy 155.51137 145.91541)
			(xy 155.51137 145.90722) (xy 155.50318 145.90722) (xy 155.50318 145.89902) (xy 155.50318 145.89083)
			(xy 155.50318 145.88263) (xy 155.49498 145.88263) (xy 155.49498 145.87444) (xy 155.49498 145.86625)
			(xy 155.49498 145.85805) (xy 155.49498 145.84985) (xy 155.49498 145.84166) (xy 155.49498 145.83347)
			(xy 155.49498 145.82527) (xy 155.49498 145.81708) (xy 155.49498 145.80888) (xy 155.49498 145.80069)
			(xy 155.49498 145.7925) (xy 155.49498 145.7843) (xy 155.49498 145.7761) (xy 155.49498 145.76791)
			(xy 155.49498 145.75972) (xy 155.49498 145.75152) (xy 155.49498 145.74333) (xy 155.49498 145.73513)
			(xy 155.49498 145.72694) (xy 155.49498 145.71874) (xy 155.49498 145.71055) (xy 155.49498 145.70236)
			(xy 155.49498 145.69416) (xy 155.49498 145.68597) (xy 155.49498 145.67777) (xy 155.49498 145.66958)
			(xy 155.49498 145.66138) (xy 155.49498 145.65319) (xy 155.49498 145.64499) (xy 155.49498 145.6368)
			(xy 155.49498 145.6286) (xy 155.49498 145.62041) (xy 155.49498 145.61221) (xy 155.49498 145.60402)
			(xy 155.49498 145.59583) (xy 155.49498 145.58763) (xy 155.49498 145.57944) (xy 155.49498 145.57124)
			(xy 155.49498 145.56305) (xy 155.49498 145.55485) (xy 155.49498 145.54666) (xy 155.49498 145.53846)
			(xy 155.49498 145.53027) (xy 155.49498 145.52208) (xy 155.49498 145.51388) (xy 155.49498 145.50569)
			(xy 155.49498 145.49749) (xy 155.49498 145.4893) (xy 155.49498 145.4811) (xy 155.49498 145.47291)
			(xy 155.49498 145.46472) (xy 155.50318 145.46472) (xy 155.50318 145.45652) (xy 155.50318 145.44833)
			(xy 155.49498 145.44833) (xy 155.49498 145.44013) (xy 155.50318 145.44013) (xy 155.50318 145.43193)
			(xy 155.49498 145.43193) (xy 155.49498 145.42374) (xy 155.49498 145.41555) (xy 155.49498 145.40735)
			(xy 155.49498 145.39916) (xy 155.49498 145.39096) (xy 155.49498 145.38277) (xy 155.48679 145.38277)
			(xy 155.48679 145.37458) (xy 155.48679 145.36638) (xy 155.47859 145.36638) (xy 155.47859 145.35819)
			(xy 155.46221 145.35819) (xy 155.46221 145.34999) (xy 155.44582 145.34999) (xy 155.44582 145.3418)
			(xy 154.17567 145.3418) (xy 154.17567 145.34999) (xy 154.15928 145.34999) (xy 154.15928 145.35819)
			(xy 154.15109 145.35819) (xy 154.15109 145.36638) (xy 154.14289 145.36638) (xy 154.14289 145.37458)
			(xy 154.1347 145.37458) (xy 154.1347 145.38277) (xy 154.1347 145.39096) (xy 154.1265 145.39096) (xy 154.1265 145.39916)
			(xy 154.1265 145.40735) (xy 154.1265 145.41555) (xy 154.1265 145.42374) (xy 154.1265 145.43193) (xy 154.1265 145.44013)
			(xy 154.1265 145.44833) (xy 154.1265 145.45652) (xy 154.1265 145.46472) (xy 154.1265 145.47291) (xy 154.1265 145.4811)
			(xy 154.1265 145.4893) (xy 154.1265 145.49749) (xy 154.1265 145.50569) (xy 154.1265 145.51388) (xy 154.1265 145.52208)
			(xy 154.1265 145.53027) (xy 154.1265 145.53846) (xy 154.1265 145.54666) (xy 154.1265 145.55485) (xy 154.1265 145.56305)
			(xy 154.1265 145.57124) (xy 154.1265 145.57944) (xy 154.1265 145.58763) (xy 154.1265 145.59583) (xy 154.1265 145.60402)
			(xy 154.1265 145.61221) (xy 154.1265 145.62041) (xy 154.1265 145.6286) (xy 154.1265 145.6368) (xy 154.1265 145.64499)
			(xy 154.1265 145.65319) (xy 154.1265 145.66138) (xy 154.1265 145.66958) (xy 154.1265 145.67777) (xy 154.1265 145.68597)
			(xy 154.1265 145.69416) (xy 154.1265 145.70236) (xy 154.1265 145.71055) (xy 154.1265 145.71874) (xy 154.1265 145.72694)
			(xy 154.1265 145.73513) (xy 154.1265 145.74333) (xy 154.1265 145.75152) (xy 154.1265 145.75972) (xy 154.1265 145.76791)
			(xy 154.1265 145.7761) (xy 154.1265 145.7843) (xy 154.1265 145.7925) (xy 154.1265 145.80069) (xy 154.1265 145.80888)
			(xy 154.1265 145.81708) (xy 154.1265 145.82527) (xy 154.1265 145.83347) (xy 154.1265 145.84166) (xy 154.1265 145.84985)
			(xy 154.1265 145.85805) (xy 154.1265 145.86625) (xy 154.1265 145.87444) (xy 154.1265 145.88263) (xy 154.1265 145.89083)
			(xy 154.1265 145.89902) (xy 154.1265 145.90722) (xy 154.1265 145.91541) (xy 154.1265 145.9236) (xy 154.1265 145.9318)
			(xy 154.1265 145.94) (xy 154.1265 145.94819) (xy 154.1265 145.95638) (xy 154.1265 145.96458) (xy 154.1265 145.97277)
			(xy 154.1265 145.98097) (xy 154.1265 145.98916) (xy 154.1265 145.99736) (xy 154.1265 146.00555) (xy 154.1265 146.01375)
			(xy 154.1265 146.02194) (xy 154.1265 146.03014) (xy 154.1265 146.03833) (xy 154.1265 146.04652) (xy 154.1265 146.05472)
			(xy 154.1265 146.06291) (xy 154.1265 146.07111) (xy 154.1265 146.0793) (xy 154.1265 146.0875) (xy 154.1265 146.09569)
			(xy 154.1265 146.10388) (xy 152.90552 146.10388) (xy 152.90552 146.09569) (xy 152.90552 146.0875)
			(xy 152.90552 146.0793) (xy 152.90552 146.07111) (xy 152.90552 146.06291) (xy 152.90552 146.05472)
			(xy 152.90552 146.04652) (xy 152.90552 146.03833) (xy 152.90552 146.03014) (xy 152.90552 146.02194)
			(xy 152.90552 146.01375) (xy 152.90552 146.00555) (xy 152.90552 145.99736) (xy 152.90552 145.98916)
			(xy 152.90552 145.98097) (xy 152.90552 145.97277) (xy 152.90552 145.96458) (xy 152.90552 145.95638)
			(xy 152.90552 145.94819) (xy 152.90552 145.94) (xy 152.90552 145.9318) (xy 152.90552 145.9236) (xy 152.90552 145.91541)
			(xy 152.90552 145.90722) (xy 152.90552 145.89902) (xy 152.90552 145.89083) (xy 152.90552 145.88263)
			(xy 152.90552 145.87444) (xy 152.90552 145.86625) (xy 152.90552 145.85805) (xy 152.90552 145.84985)
			(xy 152.90552 145.84166) (xy 152.90552 145.83347) (xy 152.90552 145.82527) (xy 152.90552 145.81708)
			(xy 152.90552 145.80888) (xy 152.90552 145.80069) (xy 152.90552 145.7925) (xy 152.90552 145.7843)
			(xy 152.90552 145.7761) (xy 152.90552 145.76791) (xy 152.90552 145.75972) (xy 152.90552 145.75152)
			(xy 152.90552 145.74333) (xy 152.90552 145.73513) (xy 152.90552 145.72694) (xy 152.90552 145.71874)
			(xy 152.90552 145.71055) (xy 152.90552 145.70236) (xy 152.90552 145.69416) (xy 152.90552 145.68597)
			(xy 152.90552 145.67777) (xy 152.90552 145.66958) (xy 152.90552 145.66138) (xy 152.90552 145.65319)
			(xy 152.90552 145.64499) (xy 152.90552 145.6368) (xy 152.90552 145.6286) (xy 152.90552 145.62041)
			(xy 152.90552 145.61221) (xy 152.90552 145.60402) (xy 152.90552 145.59583) (xy 152.90552 145.58763)
			(xy 152.90552 145.57944) (xy 152.90552 145.57124) (xy 152.90552 145.56305) (xy 152.90552 145.55485)
			(xy 152.90552 145.54666) (xy 152.90552 145.53846) (xy 152.90552 145.53027) (xy 152.90552 145.52208)
			(xy 152.90552 145.51388) (xy 152.90552 145.50569) (xy 152.90552 145.49749) (xy 152.90552 145.4893)
			(xy 152.90552 145.4811) (xy 152.90552 145.47291) (xy 152.90552 145.46472) (xy 152.90552 145.45652)
			(xy 152.90552 145.44833) (xy 152.90552 145.44013) (xy 152.90552 145.43193) (xy 152.90552 145.42374)
			(xy 152.90552 145.41555) (xy 152.90552 145.40735) (xy 152.90552 145.39916) (xy 152.90552 145.39096)
			(xy 152.90552 145.38277) (xy 152.90552 145.37458) (xy 152.90552 145.36638) (xy 153.70039 145.36638)
			(xy 153.70039 145.35819) (xy 153.70039 145.34999) (xy 153.70039 145.3418) (xy 153.70039 145.3336)
			(xy 153.70039 145.32541) (xy 153.70039 145.31721) (xy 153.70039 145.30902) (xy 153.70039 145.30082)
			(xy 153.70039 145.29263) (xy 153.70039 145.28444) (xy 153.70039 145.27624) (xy 153.70039 145.26805)
			(xy 153.70039 145.25985) (xy 153.70039 145.25166) (xy 153.70039 145.24346) (xy 153.70039 145.23527)
			(xy 153.70039 145.22707) (xy 153.70039 145.21888) (xy 153.70039 145.21069) (xy 153.70039 145.20249)
			(xy 153.70039 145.19429) (xy 153.70039 145.1861) (xy 153.70039 145.17791) (xy 153.70039 145.16971)
			(xy 153.70039 145.16152) (xy 153.70039 145.15332) (xy 153.70039 145.14513) (xy 153.70039 145.13693)
			(xy 153.70039 145.12874) (xy 153.70039 145.12054) (xy 153.70039 145.11235) (xy 153.70039 145.10416)
			(xy 153.70039 145.09596) (xy 153.70039 145.08777) (xy 153.70039 145.07957) (xy 153.70039 145.07138)
			(xy 153.70039 145.06318) (xy 153.70039 145.05499) (xy 153.70039 145.04679) (xy 153.70039 145.0386)
			(xy 153.70039 145.03041) (xy 153.70039 145.02221) (xy 153.70039 145.01402) (xy 153.70039 145.00582)
			(xy 153.70039 144.99763) (xy 153.70039 144.98943) (xy 153.70039 144.98124) (xy 153.70039 144.97305)
			(xy 153.70039 144.96485) (xy 153.70039 144.95665) (xy 153.70039 144.94846) (xy 153.70039 144.94027)
			(xy 153.70039 144.93207) (xy 153.70039 144.92388) (xy 153.70039 144.91568) (xy 153.70039 144.90749)
			(xy 153.70039 144.89929) (xy 153.70039 144.8911) (xy 153.70039 144.8829) (xy 153.70039 144.87471)
			(xy 153.70039 144.86652) (xy 153.70039 144.85832) (xy 153.70039 144.85013) (xy 153.70039 144.84193)
			(xy 153.70039 144.83374) (xy 153.70039 144.82554) (xy 153.70039 144.81735) (xy 153.70039 144.80915)
			(xy 153.70039 144.80096) (xy 153.70039 144.79277) (xy 153.70039 144.78457) (xy 153.70039 144.77638)
			(xy 153.70039 144.76818) (xy 153.70039 144.75999) (xy 153.70039 144.75179) (xy 153.70039 144.7436)
			(xy 153.70039 144.73541) (xy 153.70039 144.72721) (xy 153.70039 144.71901) (xy 153.70039 144.71082)
			(xy 153.70039 144.70262) (xy 153.70039 144.69443) (xy 153.70039 144.68624) (xy 153.70039 144.67804)
			(xy 153.70039 144.66985) (xy 153.70039 144.66165) (xy 153.70039 144.65346) (xy 153.70039 144.64527)
			(xy 153.70039 144.63707) (xy 153.70039 144.62888) (xy 153.70039 144.62068) (xy 153.70039 144.61249)
			(xy 153.70039 144.60429) (xy 153.70039 144.5961) (xy 153.70039 144.5879) (xy 153.70039 144.57971)
			(xy 153.70039 144.57151) (xy 153.70039 144.56332) (xy 153.70039 144.55513) (xy 153.70039 144.54693)
			(xy 153.70039 144.53874) (xy 153.70039 144.53054) (xy 153.70039 144.52235) (xy 153.70039 144.51415)
			(xy 153.70039 144.50596) (xy 153.70039 144.49777) (xy 153.70039 144.48957) (xy 153.70039 144.48138)
			(xy 153.70039 144.47318) (xy 153.70039 144.46498) (xy 152.90552 144.46498) (xy 152.90552 144.45679)
			(xy 152.90552 144.4486) (xy 152.90552 144.4404) (xy 152.90552 144.43221) (xy 152.90552 144.42401)
			(xy 152.90552 144.41582) (xy 152.90552 144.40762) (xy 152.90552 144.39943) (xy 152.90552 144.39124)
			(xy 152.90552 144.38304) (xy 152.90552 144.37485) (xy 152.90552 144.36665) (xy 152.90552 144.35846)
			(xy 152.90552 144.35026) (xy 152.90552 144.34207) (xy 152.90552 144.33387) (xy 152.90552 144.32568)
			(xy 152.90552 144.31749) (xy 152.90552 144.30929) (xy 152.90552 144.3011) (xy 152.90552 144.2929)
			(xy 152.90552 144.28471) (xy 152.90552 144.27651) (xy 152.90552 144.26832) (xy 152.90552 144.26012)
			(xy 153.70039 144.26012) (xy 153.70039 144.25193) (xy 153.70039 144.24374) (xy 153.70039 144.23554)
			(xy 153.70039 144.22734) (xy 153.70039 144.21915) (xy 153.70039 144.21096) (xy 153.70039 144.20276)
			(xy 153.70039 144.19457) (xy 153.70039 144.18637) (xy 153.70039 144.17818) (xy 153.70039 144.16998)
			(xy 153.70039 144.16179) (xy 153.70039 144.1536) (xy 153.70039 144.1454) (xy 153.70039 144.13721)
			(xy 153.70039 144.12901) (xy 153.70039 144.12082) (xy 153.70039 144.11262) (xy 153.70039 144.10443)
			(xy 153.70039 144.09623) (xy 153.70039 144.08804) (xy 153.70039 144.07985) (xy 153.70039 144.07165)
			(xy 153.70039 144.06346) (xy 153.70039 144.05526) (xy 153.70039 144.04707) (xy 153.70039 144.03887)
			(xy 153.70039 144.03068) (xy 153.70039 144.02248) (xy 153.70039 144.01429) (xy 153.70039 144.0061)
			(xy 153.70039 143.9979) (xy 153.70039 143.9897) (xy 153.70039 143.98151) (xy 153.70039 143.97332)
			(xy 153.70039 143.96512) (xy 153.70039 143.95693) (xy 153.70039 143.94873) (xy 153.70039 143.94054)
			(xy 153.70039 143.93234) (xy 153.70039 143.92415) (xy 153.70039 143.91596) (xy 153.70039 143.90776)
			(xy 153.70039 143.89957) (xy 153.70039 143.89137) (xy 153.70039 143.88318) (xy 153.70039 143.87498)
			(xy 153.70039 143.86679) (xy 153.70039 143.85859) (xy 153.70039 143.8504) (xy 153.70039 143.8422)
			(xy 153.70039 143.83401) (xy 153.70039 143.82582) (xy 153.70039 143.81762) (xy 153.70039 143.80943)
			(xy 153.70039 143.80123) (xy 153.70039 143.79304) (xy 153.70039 143.78484) (xy 153.70039 143.77665)
			(xy 153.70039 143.76846) (xy 153.70039 143.76026) (xy 153.70039 143.75206) (xy 153.70039 143.74387)
			(xy 153.70039 143.73567) (xy 153.70039 143.72748) (xy 153.70039 143.71929) (xy 153.70039 143.71109)
			(xy 153.70039 143.7029) (xy 153.70039 143.6947) (xy 153.70039 143.68651) (xy 153.70039 143.67831)
			(xy 153.70039 143.67012) (xy 153.70039 143.66193) (xy 153.70039 143.65373) (xy 153.70039 143.64554)
			(xy 153.70039 143.63734) (xy 153.70039 143.62915) (xy 153.70039 143.62095) (xy 153.70039 143.61276)
			(xy 153.70039 143.60456) (xy 153.70039 143.59637) (xy 153.70039 143.58818) (xy 153.70039 143.57998)
			(xy 153.70039 143.57179) (xy 153.70039 143.56359) (xy 153.70039 143.5554) (xy 153.70039 143.5472)
			(xy 153.70039 143.53901) (xy 153.70039 143.53082) (xy 153.70039 143.52262) (xy 153.70039 143.51443)
			(xy 153.70039 143.50623) (xy 153.70039 143.49803) (xy 153.70039 143.48984) (xy 153.70039 143.48165)
			(xy 153.70039 143.47345) (xy 153.70039 143.46526) (xy 153.70039 143.45706) (xy 153.70039 143.44887)
			(xy 153.70039 143.44067) (xy 153.70039 143.43248) (xy 153.70039 143.42429) (xy 153.70039 143.41609)
			(xy 153.70039 143.4079) (xy 153.70039 143.3997) (xy 153.70039 143.39151) (xy 153.70039 143.38331)
			(xy 153.70039 143.37512) (xy 153.70039 143.36692) (xy 153.70039 143.35873) (xy 152.91372 143.35873)
			(xy 152.91372 143.35054) (xy 152.90552 143.35054) (xy 152.90552 143.34234) (xy 152.90552 143.33415)
			(xy 152.90552 143.32595) (xy 152.90552 143.31776) (xy 152.90552 143.30956) (xy 152.90552 143.30137)
			(xy 152.90552 143.29317) (xy 152.90552 143.28498) (xy 152.90552 143.27679) (xy 152.90552 143.26859)
			(xy 152.90552 143.26039) (xy 152.90552 143.2522) (xy 152.90552 143.24401) (xy 152.90552 143.23581)
			(xy 152.90552 143.22762) (xy 152.90552 143.21942) (xy 152.90552 143.21123) (xy 152.90552 143.20303)
			(xy 152.90552 143.19484) (xy 152.90552 143.18664) (xy 152.90552 143.17845) (xy 152.90552 143.17026)
			(xy 152.90552 143.16206) (xy 152.90552 143.15387) (xy 153.70039 143.15387) (xy 153.70039 143.14567)
			(xy 153.70039 143.13748) (xy 153.70039 143.12928) (xy 153.70039 143.12109) (xy 153.70039 143.1129)
			(xy 153.70039 143.1047) (xy 153.70039 143.09651) (xy 153.70039 143.08831) (xy 153.70039 143.08012)
			(xy 153.70039 143.07192) (xy 153.70039 143.06373) (xy 153.70039 143.05553) (xy 153.70039 143.04734)
			(xy 153.70039 143.03915) (xy 153.70039 143.03095) (xy 153.70039 143.02275) (xy 153.70039 143.01456)
			(xy 153.70039 143.00637) (xy 153.70039 142.99817) (xy 153.70039 142.98998) (xy 153.70039 142.98178)
			(xy 153.70039 142.97359) (xy 153.70039 142.96539) (xy 153.70039 142.9572) (xy 153.70039 142.949)
			(xy 153.70039 142.94081) (xy 153.70039 142.93262) (xy 153.70039 142.92442) (xy 153.70039 142.91623)
			(xy 153.70039 142.90803) (xy 153.70039 142.89984) (xy 153.70039 142.89164) (xy 153.70039 142.88345)
			(xy 153.70039 142.87525) (xy 153.70039 142.86706) (xy 153.70039 142.85887) (xy 153.70039 142.85067)
			(xy 153.70039 142.84248) (xy 153.70039 142.83428) (xy 153.70039 142.82609) (xy 153.70039 142.81789)
			(xy 153.70039 142.8097) (xy 153.70039 142.8015) (xy 153.70039 142.79331) (xy 153.70039 142.78511)
			(xy 153.70039 142.77692) (xy 153.70039 142.76873) (xy 153.70039 142.76053) (xy 153.70039 142.75234)
			(xy 153.70039 142.74414) (xy 153.70039 142.73595) (xy 153.70039 142.72775) (xy 153.70039 142.71956)
			(xy 153.70039 142.71136) (xy 153.70039 142.70317) (xy 153.70039 142.69498) (xy 153.70039 142.68678)
			(xy 153.70039 142.67859) (xy 153.70039 142.67039) (xy 153.70039 142.6622) (xy 153.70039 142.654)
			(xy 153.70039 142.64581) (xy 153.70039 142.63761) (xy 153.70039 142.62942) (xy 153.70039 142.62123)
			(xy 153.70039 142.61303) (xy 153.70039 142.60484) (xy 153.70039 142.59664) (xy 153.70039 142.58845)
			(xy 153.70039 142.58025) (xy 153.70039 142.57206) (xy 153.70039 142.56387) (xy 153.70039 142.55567)
			(xy 153.70039 142.54747) (xy 153.70039 142.53928) (xy 153.70039 142.53108) (xy 153.70039 142.52289)
			(xy 153.70039 142.5147) (xy 153.70039 142.5065) (xy 153.70039 142.49831) (xy 153.70039 142.49011)
			(xy 153.70039 142.48192) (xy 153.70039 142.47372) (xy 153.70039 142.46553) (xy 153.70039 142.45734)
			(xy 153.70039 142.44914) (xy 153.70039 142.44095) (xy 153.70039 142.43275) (xy 153.70039 142.42456)
			(xy 153.70039 142.41636) (xy 153.70039 142.40817) (xy 153.70039 142.39997) (xy 153.70039 142.39178)
			(xy 153.70039 142.38359) (xy 153.70039 142.37539) (xy 153.70039 142.3672) (xy 153.70039 142.359)
			(xy 153.70039 142.35081) (xy 153.70039 142.34261) (xy 153.70039 142.33442) (xy 153.70039 142.32622)
			(xy 153.70039 142.31803) (xy 153.70039 142.30984) (xy 153.70039 142.30164) (xy 153.70039 142.29344)
			(xy 153.70039 142.28525) (xy 153.70039 142.27706) (xy 153.70039 142.26886) (xy 153.70039 142.26067)
			(xy 153.70039 142.25247) (xy 153.70039 142.24428) (xy 152.90552 142.24428) (xy 152.90552 142.23608)
			(xy 152.90552 142.22789) (xy 152.90552 142.21969) (xy 152.90552 142.2115) (xy 152.90552 142.20331)
			(xy 152.90552 142.19511) (xy 152.90552 142.18692) (xy 152.90552 142.17872) (xy 152.90552 142.17053)
			(xy 152.90552 142.16233) (xy 152.90552 142.15414) (xy 152.90552 142.14594) (xy 152.90552 142.13775)
			(xy 152.90552 142.12956) (xy 152.90552 142.12136) (xy 152.90552 142.11317) (xy 152.90552 142.10497)
			(xy 152.90552 142.09678) (xy 152.90552 142.08858) (xy 152.90552 142.08039) (xy 152.90552 142.07219)
			(xy 152.90552 142.064) (xy 152.90552 142.0558) (xy 152.90552 142.04761) (xy 152.91372 142.04761)
			(xy 152.91372 142.03942) (xy 153.70039 142.03942) (xy 153.70039 142.03122) (xy 153.70039 142.02303)
			(xy 153.70039 142.01483) (xy 153.70039 142.00664) (xy 153.70039 141.99844) (xy 153.70039 141.99025)
			(xy 153.70039 141.98205) (xy 153.70039 141.97386) (xy 153.70039 141.96567) (xy 153.70039 141.95747)
			(xy 153.70039 141.94927) (xy 153.70039 141.94108) (xy 153.70039 141.93289) (xy 153.70039 141.92469)
			(xy 153.70039 141.9165) (xy 153.70039 141.9083) (xy 153.70039 141.90011) (xy 153.70039 141.89192)
			(xy 153.70039 141.88372) (xy 153.70039 141.87553) (xy 153.70039 141.86733) (xy 153.70039 141.85914)
			(xy 153.70039 141.85094) (xy 153.70039 141.84275) (xy 153.70039 141.83456) (xy 153.70039 141.82636)
			(xy 153.70039 141.81816) (xy 153.70039 141.80997) (xy 154.79845 141.80997) (xy 154.79845 141.81816)
			(xy 154.79845 141.82636) (xy 154.79845 141.83456) (xy 154.79845 141.84275) (xy 154.79845 141.85094)
			(xy 154.79845 141.85914) (xy 154.79845 141.86733) (xy 154.79845 141.87553) (xy 154.79845 141.88372)
			(xy 154.79845 141.89192) (xy 154.80665 141.89192) (xy 154.80665 141.90011) (xy 154.80665 141.9083)
			(xy 154.80665 141.9165) (xy 154.80665 141.92469) (xy 154.80665 141.93289) (xy 154.80665 141.94108)
			(xy 154.80665 141.94927) (xy 154.80665 141.95747) (xy 154.80665 141.96567) (xy 154.80665 141.97386)
			(xy 154.80665 141.98205) (xy 154.81484 141.98205) (xy 154.81484 141.99025) (xy 154.80665 141.99025)
			(xy 154.80665 141.99844) (xy 154.81484 141.99844) (xy 154.81484 142.00664) (xy 154.81484 142.01483)
			(xy 154.81484 142.02303) (xy 154.81484 142.03122) (xy 154.81484 142.03942) (xy 154.81484 142.04761)
			(xy 154.81484 142.0558) (xy 154.81484 142.064) (xy 154.81484 142.07219) (xy 154.81484 142.08039)
			(xy 154.82303 142.08039) (xy 154.82303 142.08858) (xy 154.82303 142.09678) (xy 154.82303 142.10497)
			(xy 154.82303 142.11317) (xy 154.82303 142.12136) (xy 154.82303 142.12956) (xy 154.82303 142.13775)
			(xy 154.82303 142.14594) (xy 154.83123 142.14594) (xy 154.83123 142.15414) (xy 154.83123 142.16233)
			(xy 154.83123 142.17053) (xy 154.83123 142.17872) (xy 154.83123 142.18692) (xy 154.83123 142.19511)
			(xy 154.83123 142.20331) (xy 154.83942 142.20331) (xy 154.83942 142.2115) (xy 154.83942 142.21969)
			(xy 154.83942 142.22789) (xy 154.83942 142.23608) (xy 154.83942 142.24428) (xy 154.83942 142.25247)
			(xy 154.84762 142.25247) (xy 154.84762 142.26067) (xy 154.84762 142.26886) (xy 154.84762 142.27706)
			(xy 154.84762 142.28525) (xy 154.84762 142.29344) (xy 154.85581 142.29344) (xy 154.85581 142.30164)
			(xy 154.85581 142.30984) (xy 154.85581 142.31803) (xy 154.85581 142.32622) (xy 154.85581 142.33442)
			(xy 154.86401 142.33442) (xy 154.86401 142.34261) (xy 154.86401 142.35081) (xy 154.86401 142.359)
			(xy 154.86401 142.3672) (xy 154.86401 142.37539) (xy 154.8722 142.37539) (xy 154.8722 142.38359)
			(xy 154.8722 142.39178) (xy 154.8722 142.39997) (xy 154.8722 142.40817) (xy 154.8722 142.41636) (xy 154.8804 142.41636)
			(xy 154.8804 142.42456) (xy 154.8804 142.43275) (xy 154.8804 142.44095) (xy 154.8804 142.44914) (xy 154.88859 142.44914)
			(xy 154.88859 142.45734) (xy 154.88859 142.46553) (xy 154.88859 142.47372) (xy 154.88859 142.48192)
			(xy 154.89678 142.48192) (xy 154.89678 142.49011) (xy 154.89678 142.49831) (xy 154.89678 142.5065)
			(xy 154.89678 142.5147) (xy 154.90498 142.5147) (xy 154.90498 142.52289) (xy 154.90498 142.53108)
			(xy 154.90498 142.53928) (xy 154.90498 142.54747) (xy 154.91317 142.54747) (xy 154.91317 142.55567)
			(xy 154.91317 142.56387) (xy 154.91317 142.57206) (xy 154.92137 142.57206) (xy 154.92137 142.58025)
			(xy 154.92137 142.58845) (xy 154.92137 142.59664) (xy 154.92137 142.60484) (xy 154.92956 142.60484)
			(xy 154.92956 142.61303) (xy 154.92956 142.62123) (xy 154.92956 142.62942) (xy 154.93776 142.62942)
			(xy 154.93776 142.63761) (xy 154.93776 142.64581) (xy 154.93776 142.654) (xy 154.94595 142.654) (xy 154.94595 142.6622)
			(xy 154.94595 142.67039) (xy 154.94595 142.67859) (xy 154.95415 142.67859) (xy 154.95415 142.68678)
			(xy 154.95415 142.69498) (xy 154.95415 142.70317) (xy 154.96234 142.70317) (xy 154.96234 142.71136)
			(xy 154.96234 142.71956) (xy 154.96234 142.72775) (xy 154.97054 142.72775) (xy 154.97054 142.73595)
			(xy 154.97054 142.74414) (xy 154.97054 142.75234) (xy 154.97873 142.75234) (xy 154.97873 142.76053)
			(xy 154.97873 142.76873) (xy 154.97873 142.77692) (xy 154.98693 142.77692) (xy 154.98693 142.78511)
			(xy 154.98693 142.79331) (xy 154.98693 142.8015) (xy 154.99512 142.8015) (xy 154.99512 142.8097)
			(xy 154.99512 142.81789) (xy 154.99512 142.82609) (xy 155.00331 142.82609) (xy 155.00331 142.83428)
			(xy 155.00331 142.84248) (xy 155.01151 142.84248) (xy 155.01151 142.85067) (xy 155.01151 142.85887)
			(xy 155.01151 142.86706) (xy 155.0197 142.86706) (xy 155.0197 142.87525) (xy 155.0197 142.88345)
			(xy 155.0279 142.88345) (xy 155.0279 142.89164) (xy 155.0279 142.89984) (xy 155.0279 142.90803) (xy 155.03609 142.90803)
			(xy 155.03609 142.91623) (xy 155.03609 142.92442) (xy 155.04428 142.92442) (xy 155.04428 142.93262)
			(xy 155.04428 142.94081) (xy 155.04428 142.949) (xy 155.05248 142.949) (xy 155.05248 142.9572) (xy 155.05248 142.96539)
			(xy 155.06068 142.96539) (xy 155.06068 142.97359) (xy 155.06068 142.98178) (xy 155.06887 142.98178)
			(xy 155.06887 142.98998) (xy 155.06887 142.99817) (xy 155.06887 143.00637) (xy 155.07706 143.00637)
			(xy 155.07706 143.01456) (xy 155.07706 143.02275) (xy 155.08526 143.02275) (xy 155.08526 143.03095)
			(xy 155.08526 143.03915) (xy 155.09345 143.03915) (xy 155.09345 143.04734) (xy 155.09345 143.05553)
			(xy 155.10165 143.05553) (xy 155.10165 143.06373) (xy 155.10165 143.07192) (xy 155.10984 143.07192)
			(xy 155.10984 143.08012) (xy 155.10984 143.08831) (xy 155.11804 143.08831) (xy 155.11804 143.09651)
			(xy 155.11804 143.1047) (xy 155.12623 143.1047) (xy 155.12623 143.1129) (xy 155.12623 143.12109)
			(xy 155.13443 143.12109) (xy 155.13443 143.12928) (xy 155.13443 143.13748) (xy 155.14262 143.13748)
			(xy 155.14262 143.14567) (xy 155.14262 143.15387) (xy 155.15081 143.15387) (xy 155.15081 143.16206)
			(xy 155.15081 143.17026) (xy 155.15901 143.17026) (xy 155.15901 143.17845) (xy 155.15901 143.18664)
			(xy 155.1672 143.18664) (xy 155.1672 143.19484) (xy 155.1672 143.20303) (xy 155.1754 143.20303) (xy 155.1754 143.21123)
			(xy 155.1754 143.21942) (xy 155.18359 143.21942) (xy 155.18359 143.22762) (xy 155.19179 143.22762)
			(xy 155.19179 143.23581) (xy 155.19179 143.24401) (xy 155.19998 143.24401) (xy 155.19998 143.2522)
			(xy 155.19998 143.26039) (xy 155.20818 143.26039) (xy 155.20818 143.26859) (xy 155.20818 143.27679)
			(xy 155.21637 143.27679) (xy 155.21637 143.28498) (xy 155.21637 143.29317) (xy 155.22457 143.29317)
			(xy 155.22457 143.30137) (xy 155.23276 143.30137) (xy 155.23276 143.30956) (xy 155.23276 143.31776)
			(xy 155.24095 143.31776) (xy 155.24095 143.32595) (xy 155.24095 143.33415) (xy 155.24915 143.33415)
			(xy 155.24915 143.34234) (xy 155.24915 143.35054) (xy 155.25734 143.35054) (xy 155.25734 143.35873)
			(xy 155.26554 143.35873) (xy 155.26554 143.36692) (xy 155.26554 143.37512) (xy 155.27373 143.37512)
			(xy 155.27373 143.38331) (xy 155.28193 143.38331) (xy 155.28193 143.39151) (xy 155.28193 143.3997)
			(xy 155.29012 143.3997) (xy 155.29012 143.4079) (xy 155.29012 143.41609) (xy 155.29832 143.41609)
			(xy 155.29832 143.42429) (xy 155.30651 143.42429) (xy 155.30651 143.43248) (xy 155.30651 143.44067)
			(xy 155.3147 143.44067) (xy 155.3147 143.44887) (xy 155.3229 143.44887) (xy 155.3229 143.45706) (xy 155.3229 143.46526)
			(xy 155.33109 143.46526) (xy 155.33109 143.47345) (xy 155.33929 143.47345) (xy 155.33929 143.48165)
			(xy 155.33929 143.48984) (xy 155.34748 143.48984) (xy 155.34748 143.49803) (xy 155.35568 143.49803)
			(xy 155.35568 143.50623) (xy 155.35568 143.51443) (xy 155.36387 143.51443) (xy 155.36387 143.52262)
			(xy 155.37206 143.52262) (xy 155.37206 143.53082) (xy 155.38026 143.53082) (xy 155.38026 143.53901)
			(xy 155.38026 143.5472) (xy 155.38845 143.5472) (xy 155.38845 143.5554) (xy 155.39665 143.5554) (xy 155.39665 143.56359)
			(xy 155.39665 143.57179) (xy 155.40485 143.57179) (xy 155.40485 143.57998) (xy 155.41304 143.57998)
			(xy 155.41304 143.58818) (xy 155.42123 143.58818) (xy 155.42123 143.59637) (xy 155.42123 143.60456)
			(xy 155.42943 143.60456) (xy 155.42943 143.61276) (xy 155.43762 143.61276) (xy 155.43762 143.62095)
			(xy 155.44582 143.62095) (xy 155.44582 143.62915) (xy 155.44582 143.63734) (xy 155.45401 143.63734)
			(xy 155.45401 143.64554) (xy 155.46221 143.64554) (xy 155.46221 143.65373) (xy 155.4704 143.65373)
			(xy 155.4704 143.66193) (xy 155.47859 143.66193) (xy 155.47859 143.67012) (xy 155.47859 143.67831)
			(xy 155.48679 143.67831) (xy 155.48679 143.68651) (xy 155.49498 143.68651) (xy 155.49498 143.6947)
			(xy 155.50318 143.6947) (xy 155.50318 143.7029) (xy 155.51137 143.7029) (xy 155.51137 143.71109)
			(xy 155.51137 143.71929) (xy 155.51957 143.71929) (xy 155.51957 143.72748) (xy 155.52776 143.72748)
			(xy 155.52776 143.73567) (xy 155.53596 143.73567) (xy 155.53596 143.74387) (xy 155.54415 143.74387)
			(xy 155.54415 143.75206) (xy 155.54415 143.76026) (xy 155.55234 143.76026) (xy 155.55234 143.76846)
			(xy 155.56054 143.76846) (xy 155.56054 143.77665) (xy 155.56873 143.77665) (xy 155.56873 143.78484)
			(xy 155.57693 143.78484) (xy 155.57693 143.79304) (xy 155.58512 143.79304) (xy 155.58512 143.80123)
			(xy 155.59332 143.80123) (xy 155.59332 143.80943) (xy 155.60151 143.80943) (xy 155.60151 143.81762)
			(xy 155.60151 143.82582) (xy 155.6097 143.82582) (xy 155.6097 143.83401) (xy 155.6179 143.83401)
			(xy 155.6179 143.8422) (xy 155.62609 143.8422) (xy 155.62609 143.8504) (xy 155.63429 143.8504) (xy 155.63429 143.85859)
			(xy 155.64249 143.85859) (xy 155.64249 143.86679) (xy 155.65068 143.86679) (xy 155.65068 143.87498)
			(xy 155.65887 143.87498) (xy 155.65887 143.88318) (xy 155.66707 143.88318) (xy 155.66707 143.89137)
			(xy 155.67526 143.89137) (xy 155.67526 143.89957) (xy 155.68346 143.89957) (xy 155.68346 143.90776)
			(xy 155.69165 143.90776) (xy 155.69165 143.91596) (xy 155.69985 143.91596) (xy 155.69985 143.92415)
			(xy 155.70804 143.92415) (xy 155.70804 143.93234) (xy 155.71623 143.93234) (xy 155.71623 143.94054)
			(xy 155.72443 143.94054) (xy 155.72443 143.94873) (xy 155.73262 143.94873) (xy 155.73262 143.95693)
			(xy 155.74082 143.95693) (xy 155.74082 143.96512) (xy 155.74901 143.96512) (xy 155.74901 143.97332)
			(xy 155.75721 143.97332) (xy 155.75721 143.98151) (xy 155.7654 143.98151) (xy 155.7654 143.9897)
			(xy 155.7736 143.9897) (xy 155.7736 143.9979) (xy 155.78179 143.9979) (xy 155.78179 144.0061) (xy 155.78999 144.0061)
			(xy 155.78999 144.01429) (xy 155.79818 144.01429) (xy 155.79818 144.02248) (xy 155.80637 144.02248)
			(xy 155.80637 144.03068) (xy 155.81457 144.03068) (xy 155.81457 144.03887) (xy 155.82276 144.03887)
			(xy 155.82276 144.04707) (xy 155.83096 144.04707) (xy 155.83096 144.05526) (xy 155.83915 144.05526)
			(xy 155.83915 144.06346) (xy 155.84735 144.06346) (xy 155.84735 144.07165) (xy 155.86373 144.07165)
			(xy 155.86373 144.07985) (xy 155.87193 144.07985) (xy 155.87193 144.08804) (xy 155.88013 144.08804)
			(xy 155.88013 144.09623) (xy 155.88832 144.09623) (xy 155.88832 144.10443) (xy 155.89651 144.10443)
			(xy 155.89651 144.11262) (xy 155.90471 144.11262) (xy 155.90471 144.12082) (xy 155.9129 144.12082)
			(xy 155.9129 144.12901) (xy 155.92929 144.12901) (xy 155.92929 144.13721) (xy 155.93749 144.13721)
			(xy 155.93749 144.1454) (xy 155.94568 144.1454) (xy 155.94568 144.1536) (xy 155.95388 144.1536) (xy 155.95388 144.16179)
			(xy 155.96207 144.16179) (xy 155.96207 144.16998) (xy 155.97846 144.16998) (xy 155.97846 144.17818)
			(xy 155.98666 144.17818) (xy 155.98666 144.18637) (xy 155.99485 144.18637) (xy 155.99485 144.19457)
			(xy 156.00304 144.19457) (xy 156.00304 144.20276) (xy 156.01943 144.20276) (xy 156.01943 144.21096)
			(xy 156.02763 144.21096) (xy 156.02763 144.21915) (xy 156.03582 144.21915) (xy 156.03582 144.22734)
			(xy 156.05221 144.22734) (xy 156.05221 144.23554) (xy 156.0604 144.23554) (xy 156.0604 144.24374)
			(xy 156.0686 144.24374) (xy 156.0686 144.25193) (xy 156.08499 144.25193) (xy 156.08499 144.26012)
			(xy 156.09318 144.26012) (xy 156.09318 144.26832) (xy 156.10137 144.26832) (xy 156.10137 144.27651)
			(xy 156.11776 144.27651) (xy 156.11776 144.28471) (xy 156.12596 144.28471) (xy 156.12596 144.2929)
			(xy 156.14235 144.2929) (xy 156.14235 144.3011) (xy 156.15054 144.3011) (xy 156.15054 144.30929)
			(xy 156.15874 144.30929) (xy 156.15874 144.31749) (xy 156.17513 144.31749) (xy 156.17513 144.32568)
			(xy 156.18332 144.32568) (xy 156.18332 144.33387) (xy 156.19971 144.33387) (xy 156.19971 144.34207)
			(xy 156.2079 144.34207) (xy 156.2079 144.35026) (xy 156.22429 144.35026) (xy 156.22429 144.35846)
			(xy 156.23249 144.35846) (xy 156.23249 144.36665) (xy 156.24888 144.36665) (xy 156.24888 144.37485)
			(xy 156.25707 144.37485) (xy 156.25707 144.38304) (xy 156.27346 144.38304) (xy 156.27346 144.39124)
			(xy 156.28985 144.39124) (xy 156.28985 144.39943) (xy 156.29804 144.39943) (xy 156.29804 144.40762)
			(xy 156.31443 144.40762) (xy 156.31443 144.41582) (xy 156.32263 144.41582) (xy 156.32263 144.42401)
			(xy 156.33901 144.42401) (xy 156.33901 144.43221) (xy 156.3554 144.43221) (xy 156.3554 144.4404)
			(xy 156.3636 144.4404) (xy 156.3636 144.4486) (xy 156.37999 144.4486) (xy 156.37999 144.45679) (xy 156.39638 144.45679)
			(xy 156.39638 144.46498) (xy 156.41277 144.46498) (xy 156.41277 144.47318) (xy 156.42096 144.47318)
			(xy 156.42096 144.48138) (xy 156.43735 144.48138) (xy 156.43735 144.48957) (xy 156.45374 144.48957)
			(xy 156.45374 144.49777) (xy 156.47013 144.49777) (xy 156.47013 144.50596) (xy 156.48652 144.50596)
			(xy 156.48652 144.51415) (xy 156.50291 144.51415) (xy 156.50291 144.52235) (xy 156.5193 144.52235)
			(xy 156.5193 144.53054) (xy 156.53568 144.53054) (xy 156.53568 144.53874) (xy 156.55207 144.53874)
			(xy 156.55207 144.54693) (xy 156.56846 144.54693) (xy 156.56846 144.55513) (xy 156.58485 144.55513)
			(xy 156.58485 144.56332) (xy 156.60124 144.56332) (xy 156.60124 144.57151) (xy 156.61763 144.57151)
			(xy 156.61763 144.57971) (xy 156.63402 144.57971) (xy 156.63402 144.5879) (xy 156.65041 144.5879)
			(xy 156.65041 144.5961) (xy 156.6668 144.5961) (xy 156.6668 144.60429) (xy 156.69138 144.60429) (xy 156.69138 144.61249)
			(xy 156.70777 144.61249) (xy 156.70777 144.62068) (xy 156.72416 144.62068) (xy 156.72416 144.62888)
			(xy 156.74874 144.62888) (xy 156.74874 144.63707) (xy 156.76513 144.63707) (xy 156.76513 144.64527)
			(xy 156.78971 144.64527) (xy 156.78971 144.65346) (xy 156.8061 144.65346) (xy 156.8061 144.66165)
			(xy 156.83068 144.66165) (xy 156.83068 144.66985) (xy 156.84708 144.66985) (xy 156.84708 144.67804)
			(xy 156.87166 144.67804) (xy 156.87166 144.68624) (xy 156.89624 144.68624) (xy 156.89624 144.69443)
			(xy 156.92083 144.69443) (xy 156.92083 144.70262) (xy 156.93721 144.70262) (xy 156.93721 144.71082)
			(xy 156.9618 144.71082) (xy 156.9618 144.71901) (xy 156.98638 144.71901) (xy 156.98638 144.72721)
			(xy 157.01916 144.72721) (xy 157.01916 144.73541) (xy 157.04374 144.73541) (xy 157.04374 144.7436)
			(xy 157.06832 144.7436) (xy 157.06832 144.75179) (xy 157.1011 144.75179) (xy 157.1011 144.75999)
			(xy 157.12569 144.75999) (xy 157.12569 144.76818) (xy 157.15847 144.76818) (xy 157.15847 144.77638)
			(xy 157.19124 144.77638) (xy 157.19124 144.78457) (xy 157.22402 144.78457) (xy 157.22402 144.79277)
			(xy 157.2568 144.79277) (xy 157.2568 144.80096) (xy 157.29777 144.80096) (xy 157.29777 144.80915)
			(xy 157.33055 144.80915) (xy 157.33055 144.81735) (xy 157.37152 144.81735) (xy 157.37152 144.82554)
			(xy 157.42069 144.82554) (xy 157.42069 144.83374) (xy 157.46986 144.83374) (xy 157.46986 144.84193)
			(xy 157.52722 144.84193) (xy 157.52722 144.85013) (xy 157.58458 144.85013) (xy 157.58458 144.85832)
			(xy 157.66652 144.85832) (xy 157.66652 144.86652) (xy 157.76486 144.86652) (xy 157.76486 144.87471)
			(xy 158.1582 144.87471) (xy 158.1582 144.86652) (xy 158.26472 144.86652) (xy 158.26472 144.85832)
			(xy 158.33847 144.85832) (xy 158.33847 144.85013) (xy 158.40403 144.85013) (xy 158.40403 144.84193)
			(xy 158.46139 144.84193) (xy 158.46139 144.83374) (xy 158.51055 144.83374) (xy 158.51055 144.82554)
			(xy 158.55153 144.82554) (xy 158.55153 144.81735) (xy 158.6007 144.81735) (xy 158.6007 144.80915)
			(xy 158.63347 144.80915) (xy 158.63347 144.80096) (xy 158.66625 144.80096) (xy 158.66625 144.79277)
			(xy 158.70722 144.79277) (xy 158.70722 144.78457) (xy 158.74 144.78457) (xy 158.74 144.77638) (xy 158.77278 144.77638)
			(xy 158.77278 144.76818) (xy 158.80556 144.76818) (xy 158.80556 144.75999) (xy 158.83014 144.75999)
			(xy 158.83014 144.75179) (xy 158.86292 144.75179) (xy 158.86292 144.7436) (xy 158.88751 144.7436)
			(xy 158.88751 144.73541) (xy 158.91209 144.73541) (xy 158.91209 144.72721) (xy 158.93667 144.72721)
			(xy 158.93667 144.71901) (xy 158.96126 144.71901) (xy 158.96126 144.71082) (xy 158.98584 144.71082)
			(xy 158.98584 144.70262) (xy 159.01042 144.70262) (xy 159.01042 144.69443) (xy 159.035 144.69443)
			(xy 159.035 144.68624) (xy 159.05959 144.68624) (xy 159.05959 144.67804) (xy 159.08417 144.67804)
			(xy 159.08417 144.66985) (xy 159.10056 144.66985) (xy 159.10056 144.66165) (xy 159.12515 144.66165)
			(xy 159.12515 144.65346) (xy 159.14153 144.65346) (xy 159.14153 144.64527) (xy 159.16612 144.64527)
			(xy 159.16612 144.63707) (xy 159.18251 144.63707) (xy 159.18251 144.62888) (xy 159.20709 144.62888)
			(xy 159.20709 144.62068) (xy 159.22348 144.62068) (xy 159.22348 144.61249) (xy 159.23986 144.61249)
			(xy 159.23986 144.60429) (xy 159.26445 144.60429) (xy 159.26445 144.5961) (xy 159.28084 144.5961)
			(xy 159.28084 144.5879) (xy 159.29723 144.5879) (xy 159.29723 144.57971) (xy 159.31362 144.57971)
			(xy 159.31362 144.57151) (xy 159.33001 144.57151) (xy 159.33001 144.56332) (xy 159.34639 144.56332)
			(xy 159.34639 144.55513) (xy 159.36278 144.55513) (xy 159.36278 144.54693) (xy 159.37918 144.54693)
			(xy 159.37918 144.53874) (xy 159.39556 144.53874) (xy 159.39556 144.53054) (xy 159.41195 144.53054)
			(xy 159.41195 144.52235) (xy 159.42834 144.52235) (xy 159.42834 144.51415) (xy 159.44473 144.51415)
			(xy 159.44473 144.50596) (xy 159.46112 144.50596) (xy 159.46112 144.49777) (xy 159.47751 144.49777)
			(xy 159.47751 144.48957) (xy 159.4939 144.48957) (xy 159.4939 144.48138) (xy 159.50209 144.48138)
			(xy 159.50209 144.47318) (xy 159.51848 144.47318) (xy 159.51848 144.46498) (xy 159.53487 144.46498)
			(xy 159.53487 144.45679) (xy 159.55126 144.45679) (xy 159.55126 144.4486) (xy 159.55945 144.4486)
			(xy 159.55945 144.4404) (xy 159.57584 144.4404) (xy 159.57584 144.43221) (xy 159.59223 144.43221)
			(xy 159.59223 144.42401) (xy 159.60042 144.42401) (xy 159.60042 144.41582) (xy 159.61682 144.41582)
			(xy 159.61682 144.40762) (xy 159.6332 144.40762) (xy 159.6332 144.39943) (xy 159.6414 144.39943)
			(xy 159.6414 144.39124) (xy 159.65779 144.39124) (xy 159.65779 144.38304) (xy 159.66598 144.38304)
			(xy 159.66598 144.37485) (xy 159.68237 144.37485) (xy 159.68237 144.36665) (xy 159.69876 144.36665)
			(xy 159.69876 144.35846) (xy 159.70695 144.35846) (xy 159.70695 144.35026) (xy 159.72334 144.35026)
			(xy 159.72334 144.34207) (xy 159.73153 144.34207) (xy 159.73153 144.33387) (xy 159.74793 144.33387)
			(xy 159.74793 144.32568) (xy 159.75612 144.32568) (xy 159.75612 144.31749) (xy 159.76431 144.31749)
			(xy 159.76431 144.30929) (xy 159.7807 144.30929) (xy 159.7807 144.3011) (xy 159.7889 144.3011) (xy 159.7889 144.2929)
			(xy 159.80529 144.2929) (xy 159.80529 144.28471) (xy 159.81348 144.28471) (xy 159.81348 144.27651)
			(xy 159.82987 144.27651) (xy 159.82987 144.26832) (xy 159.83806 144.26832) (xy 159.83806 144.26012)
			(xy 159.84626 144.26012) (xy 159.84626 144.25193) (xy 159.86265 144.25193) (xy 159.86265 144.24374)
			(xy 159.87084 144.24374) (xy 159.87084 144.23554) (xy 159.87904 144.23554) (xy 159.87904 144.22734)
			(xy 159.89543 144.22734) (xy 159.89543 144.21915) (xy 159.90362 144.21915) (xy 159.90362 144.21096)
			(xy 159.91182 144.21096) (xy 159.91182 144.20276) (xy 159.92001 144.20276) (xy 159.92001 144.19457)
			(xy 159.9364 144.19457) (xy 159.9364 144.18637) (xy 159.94459 144.18637) (xy 159.94459 144.17818)
			(xy 159.95279 144.17818) (xy 159.95279 144.16998) (xy 159.96098 144.16998) (xy 159.96098 144.16179)
			(xy 159.97737 144.16179) (xy 159.97737 144.1536) (xy 159.98557 144.1536) (xy 159.98557 144.1454)
			(xy 159.99376 144.1454) (xy 159.99376 144.13721) (xy 160.00195 144.13721) (xy 160.00195 144.12901)
			(xy 160.01015 144.12901) (xy 160.01015 144.12082) (xy 160.02654 144.12082) (xy 160.02654 144.11262)
			(xy 160.03473 144.11262) (xy 160.03473 144.10443) (xy 160.04293 144.10443) (xy 160.04293 144.09623)
			(xy 160.05112 144.09623) (xy 160.05112 144.08804) (xy 160.05932 144.08804) (xy 160.05932 144.07985)
			(xy 160.06751 144.07985) (xy 160.06751 144.07165) (xy 160.0757 144.07165) (xy 160.0757 144.06346)
			(xy 160.09209 144.06346) (xy 160.09209 144.05526) (xy 160.10029 144.05526) (xy 160.10029 144.04707)
			(xy 160.10848 144.04707) (xy 160.10848 144.03887) (xy 160.11668 144.03887) (xy 160.11668 144.03068)
			(xy 160.12487 144.03068) (xy 160.12487 144.02248) (xy 160.13307 144.02248) (xy 160.13307 144.01429)
			(xy 160.14126 144.01429) (xy 160.14126 144.0061) (xy 160.14946 144.0061) (xy 160.14946 143.9979)
			(xy 160.15765 143.9979) (xy 160.15765 143.9897) (xy 160.16584 143.9897) (xy 160.16584 143.98151)
			(xy 160.17404 143.98151) (xy 160.17404 143.97332) (xy 160.18223 143.97332) (xy 160.18223 143.96512)
			(xy 160.19043 143.96512) (xy 160.19043 143.95693) (xy 160.19862 143.95693) (xy 160.19862 143.94873)
			(xy 160.20682 143.94873) (xy 160.20682 143.94054) (xy 160.21501 143.94054) (xy 160.21501 143.93234)
			(xy 160.22321 143.93234) (xy 160.22321 143.92415) (xy 160.2314 143.92415) (xy 160.2314 143.91596)
			(xy 160.2396 143.91596) (xy 160.2396 143.90776) (xy 160.24779 143.90776) (xy 160.24779 143.89957)
			(xy 160.25598 143.89957) (xy 160.25598 143.89137) (xy 160.26418 143.89137) (xy 160.26418 143.88318)
			(xy 160.27237 143.88318) (xy 160.27237 143.87498) (xy 160.28057 143.87498) (xy 160.28057 143.86679)
			(xy 160.28876 143.86679) (xy 160.28876 143.85859) (xy 160.29696 143.85859) (xy 160.29696 143.8504)
			(xy 160.30515 143.8504) (xy 160.30515 143.8422) (xy 160.31334 143.8422) (xy 160.31334 143.83401)
			(xy 160.32154 143.83401) (xy 160.32154 143.82582) (xy 160.32154 143.81762) (xy 160.32974 143.81762)
			(xy 160.32974 143.80943) (xy 160.33793 143.80943) (xy 160.33793 143.80123) (xy 160.34613 143.80123)
			(xy 160.34613 143.79304) (xy 160.35432 143.79304) (xy 160.35432 143.78484) (xy 160.36251 143.78484)
			(xy 160.36251 143.77665) (xy 160.37071 143.77665) (xy 160.37071 143.76846) (xy 160.3789 143.76846)
			(xy 160.3789 143.76026) (xy 160.3789 143.75206) (xy 160.3871 143.75206) (xy 160.3871 143.74387) (xy 160.25598 143.74387)
			(xy 160.25598 143.75206) (xy 160.24779 143.75206) (xy 160.24779 143.76026) (xy 160.2396 143.76026)
			(xy 160.2396 143.76846) (xy 160.2396 143.77665) (xy 160.2314 143.77665) (xy 160.2314 143.78484) (xy 160.22321 143.78484)
			(xy 160.22321 143.79304) (xy 160.21501 143.79304) (xy 160.21501 143.80123) (xy 160.20682 143.80123)
			(xy 160.20682 143.80943) (xy 160.19862 143.80943) (xy 160.19862 143.81762) (xy 160.19043 143.81762)
			(xy 160.19043 143.82582) (xy 160.18223 143.82582) (xy 160.18223 143.83401) (xy 160.17404 143.83401)
			(xy 160.17404 143.8422) (xy 160.16584 143.8422) (xy 160.16584 143.8504) (xy 160.15765 143.8504) (xy 160.15765 143.85859)
			(xy 160.14946 143.85859) (xy 160.14946 143.86679) (xy 160.14126 143.86679) (xy 160.14126 143.87498)
			(xy 160.13307 143.87498) (xy 160.13307 143.88318) (xy 160.12487 143.88318) (xy 160.12487 143.89137)
			(xy 160.11668 143.89137) (xy 160.11668 143.89957) (xy 160.10848 143.89957) (xy 160.10848 143.90776)
			(xy 160.10029 143.90776) (xy 160.10029 143.91596) (xy 160.09209 143.91596) (xy 160.09209 143.92415)
			(xy 160.0839 143.92415) (xy 160.0839 143.93234) (xy 160.0757 143.93234) (xy 160.0757 143.94054) (xy 160.06751 143.94054)
			(xy 160.06751 143.94873) (xy 160.05932 143.94873) (xy 160.05932 143.95693) (xy 160.05112 143.95693)
			(xy 160.05112 143.96512) (xy 160.04293 143.96512) (xy 160.04293 143.97332) (xy 160.03473 143.97332)
			(xy 160.03473 143.98151) (xy 160.01834 143.98151) (xy 160.01834 143.9897) (xy 160.01015 143.9897)
			(xy 160.01015 143.9979) (xy 160.00195 143.9979) (xy 160.00195 144.0061) (xy 159.99376 144.0061) (xy 159.99376 144.01429)
			(xy 159.98557 144.01429) (xy 159.98557 144.02248) (xy 159.97737 144.02248) (xy 159.97737 144.03068)
			(xy 159.96917 144.03068) (xy 159.96917 144.03887) (xy 159.95279 144.03887) (xy 159.95279 144.04707)
			(xy 159.94459 144.04707) (xy 159.94459 144.05526) (xy 159.9364 144.05526) (xy 159.9364 144.06346)
			(xy 159.9282 144.06346) (xy 159.9282 144.07165) (xy 159.92001 144.07165) (xy 159.92001 144.07985)
			(xy 159.90362 144.07985) (xy 159.90362 144.08804) (xy 159.89543 144.08804) (xy 159.89543 144.09623)
			(xy 159.88723 144.09623) (xy 159.88723 144.10443) (xy 159.87904 144.10443) (xy 159.87904 144.11262)
			(xy 159.86265 144.11262) (xy 159.86265 144.12082) (xy 159.85445 144.12082) (xy 159.85445 144.12901)
			(xy 159.84626 144.12901) (xy 159.84626 144.13721) (xy 159.83806 144.13721) (xy 159.83806 144.1454)
			(xy 159.82168 144.1454) (xy 159.82168 144.1536) (xy 159.81348 144.1536) (xy 159.81348 144.16179)
			(xy 159.80529 144.16179) (xy 159.80529 144.16998) (xy 159.7889 144.16998) (xy 159.7889 144.17818)
			(xy 159.7807 144.17818) (xy 159.7807 144.18637) (xy 159.77251 144.18637) (xy 159.77251 144.19457)
			(xy 159.75612 144.19457) (xy 159.75612 144.20276) (xy 159.74793 144.20276) (xy 159.74793 144.21096)
			(xy 159.73153 144.21096) (xy 159.73153 144.21915) (xy 159.72334 144.21915) (xy 159.72334 144.22734)
			(xy 159.71515 144.22734) (xy 159.71515 144.23554) (xy 159.69876 144.23554) (xy 159.69876 144.24374)
			(xy 159.69056 144.24374) (xy 159.69056 144.25193) (xy 159.67417 144.25193) (xy 159.67417 144.26012)
			(xy 159.66598 144.26012) (xy 159.66598 144.26832) (xy 159.64959 144.26832) (xy 159.64959 144.27651)
			(xy 159.6414 144.27651) (xy 159.6414 144.28471) (xy 159.62501 144.28471) (xy 159.62501 144.2929)
			(xy 159.61682 144.2929) (xy 159.61682 144.3011) (xy 159.60042 144.3011) (xy 159.60042 144.30929)
			(xy 159.58403 144.30929) (xy 159.58403 144.31749) (xy 159.57584 144.31749) (xy 159.57584 144.32568)
			(xy 159.55945 144.32568) (xy 159.55945 144.33387) (xy 159.54306 144.33387) (xy 159.54306 144.34207)
			(xy 159.53487 144.34207) (xy 159.53487 144.35026) (xy 159.51848 144.35026) (xy 159.51848 144.35846)
			(xy 159.50209 144.35846) (xy 159.50209 144.36665) (xy 159.4939 144.36665) (xy 159.4939 144.37485)
			(xy 159.47751 144.37485) (xy 159.47751 144.38304) (xy 159.46112 144.38304) (xy 159.46112 144.39124)
			(xy 159.44473 144.39124) (xy 159.44473 144.39943) (xy 159.43653 144.39943) (xy 159.43653 144.40762)
			(xy 159.42015 144.40762) (xy 159.42015 144.41582) (xy 159.40376 144.41582) (xy 159.40376 144.42401)
			(xy 159.38737 144.42401) (xy 159.38737 144.43221) (xy 159.37098 144.43221) (xy 159.37098 144.4404)
			(xy 159.35459 144.4404) (xy 159.35459 144.4486) (xy 159.3382 144.4486) (xy 159.3382 144.45679) (xy 159.32181 144.45679)
			(xy 159.32181 144.46498) (xy 159.30542 144.46498) (xy 159.30542 144.47318) (xy 159.28903 144.47318)
			(xy 159.28903 144.48138) (xy 159.27265 144.48138) (xy 159.27265 144.48957) (xy 159.25626 144.48957)
			(xy 159.25626 144.49777) (xy 159.23986 144.49777) (xy 159.23986 144.50596) (xy 159.22348 144.50596)
			(xy 159.22348 144.51415) (xy 159.19889 144.51415) (xy 159.19889 144.52235) (xy 159.18251 144.52235)
			(xy 159.18251 144.53054) (xy 159.15792 144.53054) (xy 159.15792 144.53874) (xy 159.14153 144.53874)
			(xy 159.14153 144.54693) (xy 159.12515 144.54693) (xy 159.12515 144.55513) (xy 159.10056 144.55513)
			(xy 159.10056 144.56332) (xy 159.08417 144.56332) (xy 159.08417 144.57151) (xy 159.05959 144.57151)
			(xy 159.05959 144.57971) (xy 159.035 144.57971) (xy 159.035 144.5879) (xy 159.01862 144.5879) (xy 159.01862 144.5961)
			(xy 158.99403 144.5961) (xy 158.99403 144.60429) (xy 158.96945 144.60429) (xy 158.96945 144.61249)
			(xy 158.94486 144.61249) (xy 158.94486 144.62068) (xy 158.92028 144.62068) (xy 158.92028 144.62888)
			(xy 158.8957 144.62888) (xy 158.8957 144.63707) (xy 158.87111 144.63707) (xy 158.87111 144.64527)
			(xy 158.84653 144.64527) (xy 158.84653 144.65346) (xy 158.81375 144.65346) (xy 158.81375 144.66165)
			(xy 158.78917 144.66165) (xy 158.78917 144.66985) (xy 158.75639 144.66985) (xy 158.75639 144.67804)
			(xy 158.72361 144.67804) (xy 158.72361 144.68624) (xy 158.69084 144.68624) (xy 158.69084 144.69443)
			(xy 158.65806 144.69443) (xy 158.65806 144.70262) (xy 158.61708 144.70262) (xy 158.61708 144.71082)
			(xy 158.58431 144.71082) (xy 158.58431 144.71901) (xy 158.54334 144.71901) (xy 158.54334 144.72721)
			(xy 158.49417 144.72721) (xy 158.49417 144.73541) (xy 158.445 144.73541) (xy 158.445 144.7436) (xy 158.38764 144.7436)
			(xy 158.38764 144.75179) (xy 158.33847 144.75179) (xy 158.33847 144.75999) (xy 158.24014 144.75999)
			(xy 158.24014 144.76818) (xy 158.15 144.76818) (xy 158.15 144.77638) (xy 158.1418 144.77638) (xy 158.1418 144.76818)
			(xy 158.12542 144.76818) (xy 158.12542 144.77638) (xy 157.80583 144.77638) (xy 157.80583 144.76818)
			(xy 157.68291 144.76818) (xy 157.68291 144.75999) (xy 157.60916 144.75999) (xy 157.60916 144.75179)
			(xy 157.54361 144.75179) (xy 157.54361 144.7436) (xy 157.48624 144.7436) (xy 157.48624 144.73541)
			(xy 157.43708 144.73541) (xy 157.43708 144.72721) (xy 157.38791 144.72721) (xy 157.38791 144.71901)
			(xy 157.34694 144.71901) (xy 157.34694 144.71082) (xy 157.30597 144.71082) (xy 157.30597 144.70262)
			(xy 157.27319 144.70262) (xy 157.27319 144.69443) (xy 157.24041 144.69443) (xy 157.24041 144.68624)
			(xy 157.20763 144.68624) (xy 157.20763 144.67804) (xy 157.17485 144.67804) (xy 157.17485 144.66985)
			(xy 157.14208 144.66985) (xy 157.14208 144.66165) (xy 157.11749 144.66165) (xy 157.11749 144.65346)
			(xy 157.08471 144.65346) (xy 157.08471 144.64527) (xy 157.06013 144.64527) (xy 157.06013 144.63707)
			(xy 157.03555 144.63707) (xy 157.03555 144.62888) (xy 157.01097 144.62888) (xy 157.01097 144.62068)
			(xy 156.98638 144.62068) (xy 156.98638 144.61249) (xy 156.9618 144.61249) (xy 156.9618 144.60429)
			(xy 156.93721 144.60429) (xy 156.93721 144.5961) (xy 156.91263 144.5961) (xy 156.91263 144.5879)
			(xy 156.88805 144.5879) (xy 156.88805 144.57971) (xy 156.87166 144.57971) (xy 156.87166 144.57151)
			(xy 156.84708 144.57151) (xy 156.84708 144.56332) (xy 156.83068 144.56332) (xy 156.83068 144.55513)
			(xy 156.8061 144.55513) (xy 156.8061 144.54693) (xy 156.78971 144.54693) (xy 156.78971 144.53874)
			(xy 156.76513 144.53874) (xy 156.76513 144.53054) (xy 156.74874 144.53054) (xy 156.74874 144.52235)
			(xy 156.73235 144.52235) (xy 156.73235 144.51415) (xy 156.71596 144.51415) (xy 156.71596 144.50596)
			(xy 156.69138 144.50596) (xy 156.69138 144.49777) (xy 156.67499 144.49777) (xy 156.67499 144.48957)
			(xy 156.6586 144.48957) (xy 156.6586 144.48138) (xy 156.64221 144.48138) (xy 156.64221 144.47318)
			(xy 156.62582 144.47318) (xy 156.62582 144.46498) (xy 156.60944 144.46498) (xy 156.60944 144.45679)
			(xy 156.59304 144.45679) (xy 156.59304 144.4486) (xy 156.57666 144.4486) (xy 156.57666 144.4404)
			(xy 156.56027 144.4404) (xy 156.56027 144.43221) (xy 156.54388 144.43221) (xy 156.54388 144.42401)
			(xy 156.52749 144.42401) (xy 156.52749 144.41582) (xy 156.5111 144.41582) (xy 156.5111 144.40762)
			(xy 156.49471 144.40762) (xy 156.49471 144.39943) (xy 156.48652 144.39943) (xy 156.48652 144.39124)
			(xy 156.47013 144.39124) (xy 156.47013 144.38304) (xy 156.45374 144.38304) (xy 156.45374 144.37485)
			(xy 156.43735 144.37485) (xy 156.43735 144.36665) (xy 156.42096 144.36665) (xy 156.42096 144.35846)
			(xy 156.41277 144.35846) (xy 156.41277 144.35026) (xy 156.39638 144.35026) (xy 156.39638 144.34207)
			(xy 156.37999 144.34207) (xy 156.37999 144.33387) (xy 156.3718 144.33387) (xy 156.3718 144.32568)
			(xy 156.3554 144.32568) (xy 156.3554 144.31749) (xy 156.34721 144.31749) (xy 156.34721 144.30929)
			(xy 156.33082 144.30929) (xy 156.33082 144.3011) (xy 156.31443 144.3011) (xy 156.31443 144.2929)
			(xy 156.30624 144.2929) (xy 156.30624 144.28471) (xy 156.28985 144.28471) (xy 156.28985 144.27651)
			(xy 156.28166 144.27651) (xy 156.28166 144.26832) (xy 156.26527 144.26832) (xy 156.26527 144.26012)
			(xy 156.25707 144.26012) (xy 156.25707 144.25193) (xy 156.24068 144.25193) (xy 156.24068 144.24374)
			(xy 156.23249 144.24374) (xy 156.23249 144.23554) (xy 156.2161 144.23554) (xy 156.2161 144.22734)
			(xy 156.2079 144.22734) (xy 156.2079 144.21915) (xy 156.19152 144.21915) (xy 156.19152 144.21096)
			(xy 156.18332 144.21096) (xy 156.18332 144.20276) (xy 156.17513 144.20276) (xy 156.17513 144.19457)
			(xy 156.15874 144.19457) (xy 156.15874 144.18637) (xy 156.15054 144.18637) (xy 156.15054 144.17818)
			(xy 156.14235 144.17818) (xy 156.14235 144.16998) (xy 156.12596 144.16998) (xy 156.12596 144.16179)
			(xy 156.11776 144.16179) (xy 156.11776 144.1536) (xy 156.10957 144.1536) (xy 156.10957 144.1454)
			(xy 156.09318 144.1454) (xy 156.09318 144.13721) (xy 156.08499 144.13721) (xy 156.08499 144.12901)
			(xy 156.07679 144.12901) (xy 156.07679 144.12082) (xy 156.0604 144.12082) (xy 156.0604 144.11262)
			(xy 156.05221 144.11262) (xy 156.05221 144.10443) (xy 156.04401 144.10443) (xy 156.04401 144.09623)
			(xy 156.03582 144.09623) (xy 156.03582 144.08804) (xy 156.01943 144.08804) (xy 156.01943 144.07985)
			(xy 156.01124 144.07985) (xy 156.01124 144.07165) (xy 156.00304 144.07165) (xy 156.00304 144.06346)
			(xy 155.99485 144.06346) (xy 155.99485 144.05526) (xy 155.98666 144.05526) (xy 155.98666 144.04707)
			(xy 155.97026 144.04707) (xy 155.97026 144.03887) (xy 155.96207 144.03887) (xy 155.96207 144.03068)
			(xy 155.95388 144.03068) (xy 155.95388 144.02248) (xy 155.94568 144.02248) (xy 155.94568 144.01429)
			(xy 155.93749 144.01429) (xy 155.93749 144.0061) (xy 155.92929 144.0061) (xy 155.92929 143.9979)
			(xy 155.9211 143.9979) (xy 155.9211 143.9897) (xy 155.90471 143.9897) (xy 155.90471 143.98151) (xy 155.89651 143.98151)
			(xy 155.89651 143.97332) (xy 155.88832 143.97332) (xy 155.88832 143.96512) (xy 155.88013 143.96512)
			(xy 155.88013 143.95693) (xy 155.87193 143.95693) (xy 155.87193 143.94873) (xy 155.86373 143.94873)
			(xy 155.86373 143.94054) (xy 155.85554 143.94054) (xy 155.85554 143.93234) (xy 155.84735 143.93234)
			(xy 155.84735 143.92415) (xy 155.83915 143.92415) (xy 155.83915 143.91596) (xy 155.83096 143.91596)
			(xy 155.83096 143.90776) (xy 155.82276 143.90776) (xy 155.82276 143.89957) (xy 155.81457 143.89957)
			(xy 155.81457 143.89137) (xy 155.80637 143.89137) (xy 155.80637 143.88318) (xy 155.79818 143.88318)
			(xy 155.79818 143.87498) (xy 155.78999 143.87498) (xy 155.78999 143.86679) (xy 155.78179 143.86679)
			(xy 155.78179 143.85859) (xy 155.7736 143.85859) (xy 155.7736 143.8504) (xy 155.7654 143.8504) (xy 155.7654 143.8422)
			(xy 155.75721 143.8422) (xy 155.75721 143.83401) (xy 155.74901 143.83401) (xy 155.74901 143.82582)
			(xy 155.74082 143.82582) (xy 155.74082 143.81762) (xy 155.73262 143.81762) (xy 155.73262 143.80943)
			(xy 155.72443 143.80943) (xy 155.72443 143.80123) (xy 155.71623 143.80123) (xy 155.71623 143.79304)
			(xy 155.70804 143.79304) (xy 155.70804 143.78484) (xy 155.69985 143.78484) (xy 155.69985 143.77665)
			(xy 155.69165 143.77665) (xy 155.69165 143.76846) (xy 155.68346 143.76846) (xy 155.68346 143.76026)
			(xy 155.68346 143.75206) (xy 155.67526 143.75206) (xy 155.67526 143.74387) (xy 155.66707 143.74387)
			(xy 155.66707 143.73567) (xy 155.65887 143.73567) (xy 155.65887 143.72748) (xy 155.65068 143.72748)
			(xy 155.65068 143.71929) (xy 155.64249 143.71929) (xy 155.64249 143.71109) (xy 155.63429 143.71109)
			(xy 155.63429 143.7029) (xy 155.62609 143.7029) (xy 155.62609 143.6947) (xy 155.62609 143.68651)
			(xy 155.6179 143.68651) (xy 155.6179 143.67831) (xy 155.6097 143.67831) (xy 155.6097 143.67012) (xy 155.60151 143.67012)
			(xy 155.60151 143.66193) (xy 155.59332 143.66193) (xy 155.59332 143.65373) (xy 155.58512 143.65373)
			(xy 155.58512 143.64554) (xy 155.58512 143.63734) (xy 155.57693 143.63734) (xy 155.57693 143.62915)
			(xy 155.56873 143.62915) (xy 155.56873 143.62095) (xy 155.56054 143.62095) (xy 155.56054 143.61276)
			(xy 155.55234 143.61276) (xy 155.55234 143.60456) (xy 155.55234 143.59637) (xy 155.54415 143.59637)
			(xy 155.54415 143.58818) (xy 155.53596 143.58818) (xy 155.53596 143.57998) (xy 155.52776 143.57998)
			(xy 155.52776 143.57179) (xy 155.52776 143.56359) (xy 155.51957 143.56359) (xy 155.51957 143.5554)
			(xy 155.51137 143.5554) (xy 155.51137 143.5472) (xy 155.50318 143.5472) (xy 155.50318 143.53901)
			(xy 155.50318 143.53082) (xy 155.49498 143.53082) (xy 155.49498 143.52262) (xy 155.48679 143.52262)
			(xy 155.48679 143.51443) (xy 155.47859 143.51443) (xy 155.47859 143.50623) (xy 155.47859 143.49803)
			(xy 155.4704 143.49803) (xy 155.4704 143.48984) (xy 155.46221 143.48984) (xy 155.46221 143.48165)
			(xy 155.45401 143.48165) (xy 155.45401 143.47345) (xy 155.45401 143.46526) (xy 155.44582 143.46526)
			(xy 155.44582 143.45706) (xy 155.43762 143.45706) (xy 155.43762 143.44887) (xy 155.43762 143.44067)
			(xy 155.42943 143.44067) (xy 155.42943 143.43248) (xy 155.42123 143.43248) (xy 155.42123 143.42429)
			(xy 155.42123 143.41609) (xy 155.41304 143.41609) (xy 155.41304 143.4079) (xy 155.40485 143.4079)
			(xy 155.40485 143.3997) (xy 155.40485 143.39151) (xy 155.39665 143.39151) (xy 155.39665 143.38331)
			(xy 155.38845 143.38331) (xy 155.38845 143.37512) (xy 155.38845 143.36692) (xy 155.38026 143.36692)
			(xy 155.38026 143.35873) (xy 155.37206 143.35873) (xy 155.37206 143.35054) (xy 155.37206 143.34234)
			(xy 155.36387 143.34234) (xy 155.36387 143.33415) (xy 155.36387 143.32595) (xy 155.35568 143.32595)
			(xy 155.35568 143.31776) (xy 155.34748 143.31776) (xy 155.34748 143.30956) (xy 155.34748 143.30137)
			(xy 155.33929 143.30137) (xy 155.33929 143.29317) (xy 155.33109 143.29317) (xy 155.33109 143.28498)
			(xy 155.33109 143.27679) (xy 155.3229 143.27679) (xy 155.3229 143.26859) (xy 155.3229 143.26039)
			(xy 155.3147 143.26039) (xy 155.3147 143.2522) (xy 155.3147 143.24401) (xy 155.30651 143.24401) (xy 155.30651 143.23581)
			(xy 155.29832 143.23581) (xy 155.29832 143.22762) (xy 155.29832 143.21942) (xy 155.29012 143.21942)
			(xy 155.29012 143.21123) (xy 155.29012 143.20303) (xy 155.28193 143.20303) (xy 155.28193 143.19484)
			(xy 155.28193 143.18664) (xy 155.27373 143.18664) (xy 155.27373 143.17845) (xy 155.26554 143.17845)
			(xy 155.26554 143.17026) (xy 155.26554 143.16206) (xy 155.25734 143.16206) (xy 155.25734 143.15387)
			(xy 155.25734 143.14567) (xy 155.24915 143.14567) (xy 155.24915 143.13748) (xy 155.24915 143.12928)
			(xy 155.24095 143.12928) (xy 155.24095 143.12109) (xy 155.24095 143.1129) (xy 155.23276 143.1129)
			(xy 155.23276 143.1047) (xy 155.23276 143.09651) (xy 155.22457 143.09651) (xy 155.22457 143.08831)
			(xy 155.22457 143.08012) (xy 155.21637 143.08012) (xy 155.21637 143.07192) (xy 155.21637 143.06373)
			(xy 155.20818 143.06373) (xy 155.20818 143.05553) (xy 155.20818 143.04734) (xy 155.19998 143.04734)
			(xy 155.19998 143.03915) (xy 155.19998 143.03095) (xy 155.19179 143.03095) (xy 155.19179 143.02275)
			(xy 155.19179 143.01456) (xy 155.18359 143.01456) (xy 155.18359 143.00637) (xy 155.18359 142.99817)
			(xy 155.1754 142.99817) (xy 155.1754 142.98998) (xy 155.1754 142.98178) (xy 155.1672 142.98178) (xy 155.1672 142.97359)
			(xy 155.1672 142.96539) (xy 155.1672 142.9572) (xy 155.15901 142.9572) (xy 155.15901 142.949) (xy 155.15901 142.94081)
			(xy 155.15081 142.94081) (xy 155.15081 142.93262) (xy 155.15081 142.92442) (xy 155.14262 142.92442)
			(xy 155.14262 142.91623) (xy 155.14262 142.90803) (xy 155.14262 142.89984) (xy 155.13443 142.89984)
			(xy 155.13443 142.89164) (xy 155.13443 142.88345) (xy 155.12623 142.88345) (xy 155.12623 142.87525)
			(xy 155.12623 142.86706) (xy 155.11804 142.86706) (xy 155.11804 142.85887) (xy 155.11804 142.85067)
			(xy 155.11804 142.84248) (xy 155.10984 142.84248) (xy 155.10984 142.83428) (xy 155.10984 142.82609)
			(xy 155.10165 142.82609) (xy 155.10165 142.81789) (xy 155.10165 142.8097) (xy 155.10165 142.8015)
			(xy 155.09345 142.8015) (xy 155.09345 142.79331) (xy 155.09345 142.78511) (xy 155.09345 142.77692)
			(xy 155.08526 142.77692) (xy 155.08526 142.76873) (xy 155.08526 142.76053) (xy 155.07706 142.76053)
			(xy 155.07706 142.75234) (xy 155.07706 142.74414) (xy 155.07706 142.73595) (xy 155.06887 142.73595)
			(xy 155.06887 142.72775) (xy 155.06887 142.71956) (xy 155.06887 142.71136) (xy 155.06068 142.71136)
			(xy 155.06068 142.70317) (xy 155.06068 142.69498) (xy 155.06068 142.68678) (xy 155.05248 142.68678)
			(xy 155.05248 142.67859) (xy 155.05248 142.67039) (xy 155.05248 142.6622) (xy 155.04428 142.6622)
			(xy 155.04428 142.654) (xy 155.04428 142.64581) (xy 155.04428 142.63761) (xy 155.03609 142.63761)
			(xy 155.03609 142.62942) (xy 155.03609 142.62123) (xy 155.03609 142.61303) (xy 155.0279 142.61303)
			(xy 155.0279 142.60484) (xy 155.0279 142.59664) (xy 155.0279 142.58845) (xy 155.0197 142.58845) (xy 155.0197 142.58025)
			(xy 155.0197 142.57206) (xy 155.0197 142.56387) (xy 155.0197 142.55567) (xy 155.01151 142.55567)
			(xy 155.01151 142.54747) (xy 155.01151 142.53928) (xy 155.01151 142.53108) (xy 155.00331 142.53108)
			(xy 155.00331 142.52289) (xy 155.00331 142.5147) (xy 155.00331 142.5065) (xy 155.00331 142.49831)
			(xy 154.99512 142.49831) (xy 154.99512 142.49011) (xy 154.99512 142.48192) (xy 154.99512 142.47372)
			(xy 154.99512 142.46553) (xy 154.98693 142.46553) (xy 154.98693 142.45734) (xy 154.98693 142.44914)
			(xy 154.98693 142.44095) (xy 154.98693 142.43275) (xy 154.97873 142.43275) (xy 154.97873 142.42456)
			(xy 154.97873 142.41636) (xy 154.97873 142.40817) (xy 154.97873 142.39997) (xy 154.97054 142.39997)
			(xy 154.97054 142.39178) (xy 154.97054 142.38359) (xy 154.97054 142.37539) (xy 154.97054 142.3672)
			(xy 154.97054 142.359) (xy 154.96234 142.359) (xy 154.96234 142.35081) (xy 154.96234 142.34261) (xy 154.96234 142.33442)
			(xy 154.96234 142.32622) (xy 154.96234 142.31803) (xy 154.95415 142.31803) (xy 154.95415 142.30984)
			(xy 154.95415 142.30164) (xy 154.95415 142.29344) (xy 154.95415 142.28525) (xy 154.95415 142.27706)
			(xy 154.94595 142.27706) (xy 154.94595 142.26886) (xy 154.94595 142.26067) (xy 154.94595 142.25247)
			(xy 154.94595 142.24428) (xy 154.94595 142.23608) (xy 154.93776 142.23608) (xy 154.93776 142.22789)
			(xy 154.93776 142.21969) (xy 154.93776 142.2115) (xy 154.93776 142.20331) (xy 154.93776 142.19511)
			(xy 154.93776 142.18692) (xy 154.92956 142.18692) (xy 154.92956 142.17872) (xy 154.92956 142.17053)
			(xy 154.92956 142.16233) (xy 154.92956 142.15414) (xy 154.92956 142.14594) (xy 154.92956 142.13775)
			(xy 154.92956 142.12956) (xy 154.92137 142.12956) (xy 154.92137 142.12136) (xy 154.92137 142.11317)
			(xy 154.92137 142.10497) (xy 154.92137 142.09678) (xy 155.65068 142.09678) (xy 155.65068 142.10497)
			(xy 155.65068 142.11317) (xy 155.65068 142.12136) (xy 155.65068 142.12956) (xy 155.65068 142.13775)
			(xy 155.65068 142.14594) (xy 155.65068 142.15414) (xy 155.65068 142.16233) (xy 155.65068 142.17053)
			(xy 155.65068 142.17872) (xy 155.65068 142.18692) (xy 155.65068 142.19511) (xy 155.65068 142.20331)
			(xy 155.65068 142.2115) (xy 155.65068 142.21969) (xy 155.65068 142.22789) (xy 155.65068 142.23608)
			(xy 155.65068 142.24428) (xy 155.65068 142.25247) (xy 155.65068 142.26067) (xy 155.65068 142.26886)
			(xy 155.65068 142.27706) (xy 155.65068 142.28525) (xy 155.65068 142.29344) (xy 155.65068 142.30164)
			(xy 155.65068 142.30984) (xy 155.65068 142.31803) (xy 155.65068 142.32622) (xy 155.65068 142.33442)
			(xy 155.65068 142.34261) (xy 155.65068 142.35081) (xy 155.65068 142.359) (xy 155.65068 142.3672)
			(xy 155.65068 142.37539) (xy 155.65068 142.38359) (xy 155.65068 142.39178) (xy 155.65068 142.39997)
			(xy 155.65068 142.40817) (xy 155.65068 142.41636) (xy 155.65068 142.42456) (xy 155.65068 142.43275)
			(xy 155.65068 142.44095) (xy 155.65068 142.44914) (xy 155.65068 142.45734) (xy 155.65068 142.46553)
			(xy 155.65068 142.47372) (xy 155.65068 142.48192) (xy 155.65068 142.49011) (xy 155.65068 142.49831)
			(xy 155.65068 142.5065) (xy 155.65068 142.5147) (xy 155.65068 142.52289) (xy 155.65068 142.53108)
			(xy 155.65068 142.53928) (xy 155.65068 142.54747) (xy 155.65068 142.55567) (xy 155.65068 142.56387)
			(xy 155.65068 142.57206) (xy 155.65068 142.58025) (xy 155.65068 142.58845) (xy 155.65068 142.59664)
			(xy 155.65068 142.60484) (xy 155.65068 142.61303) (xy 155.65068 142.62123) (xy 155.65068 142.62942)
			(xy 155.65068 142.63761) (xy 155.65068 142.64581) (xy 155.65068 142.654) (xy 155.65068 142.6622)
			(xy 155.65068 142.67039) (xy 155.65068 142.67859) (xy 155.65068 142.68678) (xy 155.65068 142.69498)
			(xy 155.65068 142.70317) (xy 155.65068 142.71136) (xy 155.65068 142.71956) (xy 155.65068 142.72775)
			(xy 155.65068 142.73595) (xy 155.65068 142.74414) (xy 155.65068 142.75234) (xy 155.65068 142.76053)
			(xy 155.65068 142.76873) (xy 155.65068 142.77692) (xy 155.65068 142.78511) (xy 155.65068 142.79331)
			(xy 155.65068 142.8015) (xy 155.65068 142.8097) (xy 155.65068 142.81789) (xy 155.65068 142.82609)
			(xy 155.65068 142.83428) (xy 155.65068 142.84248) (xy 155.65068 142.85067) (xy 155.65068 142.85887)
			(xy 155.65068 142.86706) (xy 155.65068 142.87525) (xy 155.65068 142.88345) (xy 155.65068 142.89164)
			(xy 155.65068 142.89984) (xy 155.65068 142.90803) (xy 155.65068 142.91623) (xy 155.65068 142.92442)
			(xy 155.65068 142.93262) (xy 155.65068 142.94081) (xy 155.65068 142.949) (xy 155.65068 142.9572)
			(xy 155.65068 142.96539) (xy 155.65068 142.97359) (xy 155.65068 142.98178) (xy 155.65068 142.98998)
			(xy 155.65068 142.99817) (xy 155.65068 143.00637) (xy 155.65068 143.01456) (xy 155.65068 143.02275)
			(xy 155.65068 143.03095) (xy 155.65068 143.03915) (xy 155.65068 143.04734) (xy 155.65068 143.05553)
			(xy 155.65068 143.06373) (xy 155.65068 143.07192) (xy 155.65068 143.08012) (xy 155.65068 143.08831)
			(xy 155.65068 143.09651) (xy 155.65068 143.1047) (xy 155.65068 143.1129) (xy 155.65068 143.12109)
			(xy 155.65068 143.12928) (xy 155.65068 143.13748) (xy 155.65068 143.14567) (xy 155.65068 143.15387)
			(xy 155.65068 143.16206) (xy 155.65068 143.17026) (xy 155.65068 143.17845) (xy 155.65068 143.18664)
			(xy 155.65068 143.19484) (xy 155.65068 143.20303) (xy 155.65068 143.21123) (xy 155.65068 143.21942)
			(xy 155.65068 143.22762) (xy 155.65068 143.23581) (xy 155.65068 143.24401) (xy 155.65068 143.2522)
			(xy 155.65068 143.26039) (xy 155.65068 143.26859) (xy 155.65068 143.27679) (xy 155.65068 143.28498)
			(xy 155.65887 143.28498) (xy 155.65887 143.29317) (xy 155.65887 143.30137) (xy 155.65887 143.30956)
			(xy 155.66707 143.30956) (xy 155.66707 143.31776) (xy 155.66707 143.32595) (xy 155.67526 143.32595)
			(xy 155.67526 143.33415) (xy 155.68346 143.33415) (xy 155.68346 143.34234) (xy 155.69165 143.34234)
			(xy 155.69165 143.35054) (xy 155.69985 143.35054) (xy 155.69985 143.35873) (xy 155.70804 143.35873)
			(xy 155.70804 143.36692) (xy 155.71623 143.36692) (xy 155.71623 143.37512) (xy 155.72443 143.37512)
			(xy 155.72443 143.38331) (xy 155.73262 143.38331) (xy 155.73262 143.39151) (xy 155.74082 143.39151)
			(xy 155.74082 143.3997) (xy 155.74901 143.3997) (xy 155.74901 143.4079) (xy 155.75721 143.4079) (xy 155.75721 143.41609)
			(xy 155.7654 143.41609) (xy 155.7654 143.42429) (xy 155.7736 143.42429) (xy 155.7736 143.43248) (xy 155.78179 143.43248)
			(xy 155.78179 143.44067) (xy 155.78999 143.44067) (xy 155.78999 143.44887) (xy 155.79818 143.44887)
			(xy 155.79818 143.45706) (xy 155.80637 143.45706) (xy 155.80637 143.46526) (xy 155.81457 143.46526)
			(xy 155.81457 143.47345) (xy 155.82276 143.47345) (xy 155.82276 143.48165) (xy 155.83096 143.48165)
			(xy 155.83096 143.48984) (xy 155.83915 143.48984) (xy 155.83915 143.49803) (xy 155.84735 143.49803)
			(xy 155.84735 143.50623) (xy 155.85554 143.50623) (xy 155.85554 143.51443) (xy 155.86373 143.51443)
			(xy 155.86373 143.52262) (xy 155.87193 143.52262) (xy 155.87193 143.53082) (xy 155.88013 143.53082)
			(xy 155.88013 143.53901) (xy 155.88832 143.53901) (xy 155.88832 143.5472) (xy 155.89651 143.5472)
			(xy 155.89651 143.5554) (xy 155.90471 143.5554) (xy 155.90471 143.56359) (xy 155.9211 143.56359)
			(xy 155.9211 143.57179) (xy 155.94568 143.57179) (xy 155.94568 143.57998) (xy 156.98638 143.57998)
			(xy 156.98638 143.57179) (xy 156.99457 143.57179) (xy 156.99457 143.56359) (xy 157.00277 143.56359)
			(xy 157.00277 143.5554) (xy 157.01097 143.5554) (xy 157.01097 143.5472) (xy 157.01097 143.53901)
			(xy 157.01097 143.53082) (xy 157.01097 143.52262) (xy 157.01097 143.51443) (xy 157.01097 143.50623)
			(xy 157.01097 143.49803) (xy 157.01097 143.48984) (xy 157.01097 143.48165) (xy 157.01097 143.47345)
			(xy 157.01097 143.46526) (xy 157.01097 143.45706) (xy 157.01097 143.44887) (xy 157.01097 143.44067)
			(xy 157.01097 143.43248) (xy 157.01097 143.42429) (xy 157.01097 143.41609) (xy 157.01097 143.4079)
			(xy 157.01097 143.3997) (xy 157.01097 143.39151) (xy 157.01097 143.38331) (xy 157.01097 143.37512)
			(xy 157.01097 143.36692) (xy 157.01097 143.35873) (xy 157.01097 143.35054) (xy 157.01097 143.34234)
			(xy 157.01097 143.33415) (xy 157.01097 143.32595) (xy 157.01097 143.31776) (xy 157.01097 143.30956)
			(xy 157.01097 143.30137) (xy 157.01097 143.29317) (xy 157.01097 143.28498) (xy 157.01097 143.27679)
			(xy 157.01097 143.26859) (xy 157.01097 143.26039) (xy 157.01097 143.2522) (xy 157.01097 143.24401)
			(xy 157.01097 143.23581) (xy 157.01097 143.22762) (xy 157.01097 143.21942) (xy 157.01097 143.21123)
			(xy 157.01097 143.20303) (xy 157.01097 143.19484) (xy 157.01097 143.18664) (xy 157.01097 143.17845)
			(xy 157.01097 143.17026) (xy 157.00277 143.17026) (xy 157.00277 143.16206) (xy 156.99457 143.16206)
			(xy 156.99457 143.15387) (xy 156.97819 143.15387) (xy 156.97819 143.14567) (xy 156.12596 143.14567)
			(xy 156.12596 143.13748) (xy 156.10957 143.13748) (xy 156.10957 143.12928) (xy 156.10957 143.12109)
			(xy 156.10137 143.12109) (xy 156.10137 143.1129) (xy 156.10137 143.1047) (xy 156.10137 143.09651)
			(xy 156.10137 143.08831) (xy 156.10137 143.08012) (xy 156.10137 143.07192) (xy 156.10137 143.06373)
			(xy 156.10137 143.05553) (xy 156.10137 143.04734) (xy 156.10137 143.03915) (xy 156.10137 143.03095)
			(xy 156.10137 143.02275) (xy 156.10137 143.01456) (xy 156.10137 143.00637) (xy 156.10137 142.99817)
			(xy 156.10137 142.98998) (xy 156.10137 142.98178) (xy 156.10137 142.97359) (xy 156.10137 142.96539)
			(xy 156.10137 142.9572) (xy 156.10137 142.949) (xy 156.10137 142.94081) (xy 156.10137 142.93262)
			(xy 156.10137 142.92442) (xy 156.10137 142.91623) (xy 156.10137 142.90803) (xy 156.10137 142.89984)
			(xy 156.10137 142.89164) (xy 156.10137 142.88345) (xy 156.10137 142.87525) (xy 156.10137 142.86706)
			(xy 156.10137 142.85887) (xy 156.10137 142.85067) (xy 156.10137 142.84248) (xy 156.10137 142.83428)
			(xy 156.10137 142.82609) (xy 156.10137 142.81789) (xy 156.10137 142.8097) (xy 156.10137 142.8015)
			(xy 156.10137 142.79331) (xy 156.10137 142.78511) (xy 156.10137 142.77692) (xy 156.10137 142.76873)
			(xy 156.10137 142.76053) (xy 156.10137 142.75234) (xy 156.10137 142.74414) (xy 156.10137 142.73595)
			(xy 156.10137 142.72775) (xy 156.10137 142.71956) (xy 156.10137 142.71136) (xy 156.10137 142.70317)
			(xy 156.10137 142.69498) (xy 156.10137 142.68678) (xy 156.10137 142.67859) (xy 156.10137 142.67039)
			(xy 156.10137 142.6622) (xy 156.10137 142.654) (xy 156.10137 142.64581) (xy 156.10137 142.63761)
			(xy 156.10137 142.62942) (xy 156.10137 142.62123) (xy 156.10137 142.61303) (xy 156.10137 142.60484)
			(xy 156.10137 142.59664) (xy 156.10137 142.58845) (xy 156.10137 142.58025) (xy 156.10137 142.57206)
			(xy 156.10137 142.56387) (xy 156.10137 142.55567) (xy 156.10137 142.54747) (xy 156.10137 142.53928)
			(xy 156.10137 142.53108) (xy 156.10137 142.52289) (xy 156.10137 142.5147) (xy 156.10137 142.5065)
			(xy 156.10137 142.49831) (xy 156.10137 142.49011) (xy 156.10137 142.48192) (xy 156.10137 142.47372)
			(xy 156.8143 142.47372) (xy 156.8143 142.48192) (xy 156.8143 142.49011) (xy 156.8143 142.49831) (xy 156.8143 142.5065)
			(xy 156.8143 142.5147) (xy 156.8143 142.52289) (xy 156.8143 142.53108) (xy 156.8143 142.53928) (xy 156.8143 142.54747)
			(xy 156.8143 142.55567) (xy 156.8143 142.56387) (xy 156.8143 142.57206) (xy 156.8143 142.58025) (xy 156.8143 142.58845)
			(xy 156.8143 142.59664) (xy 156.8143 142.60484) (xy 156.8143 142.61303) (xy 156.8143 142.62123) (xy 156.8143 142.62942)
			(xy 156.8143 142.63761) (xy 156.8143 142.64581) (xy 156.8143 142.654) (xy 156.8143 142.6622) (xy 156.8143 142.67039)
			(xy 156.8143 142.67859) (xy 156.8143 142.68678) (xy 156.8143 142.69498) (xy 156.8143 142.70317) (xy 156.8143 142.71136)
			(xy 156.8143 142.71956) (xy 156.8143 142.72775) (xy 156.8143 142.73595) (xy 156.8143 142.74414) (xy 156.8143 142.75234)
			(xy 156.8143 142.76053) (xy 156.8143 142.76873) (xy 156.8143 142.77692) (xy 156.8143 142.78511) (xy 156.8143 142.79331)
			(xy 156.8143 142.8015) (xy 156.8143 142.8097) (xy 156.8143 142.81789) (xy 156.8143 142.82609) (xy 156.8143 142.83428)
			(xy 156.8143 142.84248) (xy 156.82249 142.84248) (xy 156.82249 142.85067) (xy 156.83068 142.85067)
			(xy 156.83068 142.85887) (xy 156.83068 142.86706) (xy 156.83888 142.86706) (xy 156.83888 142.87525)
			(xy 156.84708 142.87525) (xy 156.84708 142.88345) (xy 156.84708 142.89164) (xy 156.85527 142.89164)
			(xy 156.85527 142.89984) (xy 156.86346 142.89984) (xy 156.86346 142.90803) (xy 156.87166 142.90803)
			(xy 156.87166 142.91623) (xy 156.87985 142.91623) (xy 156.87985 142.92442) (xy 156.88805 142.92442)
			(xy 156.88805 142.93262) (xy 156.89624 142.93262) (xy 156.89624 142.94081) (xy 156.90444 142.94081)
			(xy 156.90444 142.949) (xy 156.91263 142.949) (xy 156.91263 142.9572) (xy 156.92083 142.9572) (xy 156.92083 142.96539)
			(xy 156.93721 142.96539) (xy 156.93721 142.9572) (xy 156.94541 142.9572) (xy 156.94541 142.949) (xy 156.9536 142.949)
			(xy 156.9536 142.94081) (xy 156.9618 142.94081) (xy 156.9618 142.93262) (xy 156.96999 142.93262)
			(xy 156.96999 142.92442) (xy 156.97819 142.92442) (xy 156.97819 142.91623) (xy 156.98638 142.91623)
			(xy 156.98638 142.90803) (xy 156.99457 142.90803) (xy 156.99457 142.89984) (xy 157.00277 142.89984)
			(xy 157.21583 142.89984) (xy 157.21583 142.90803) (xy 157.21583 142.91623) (xy 157.21583 142.92442)
			(xy 157.21583 142.93262) (xy 157.21583 142.94081) (xy 157.21583 142.949) (xy 157.21583 142.9572)
			(xy 157.21583 142.96539) (xy 157.21583 142.97359) (xy 157.21583 142.98178) (xy 157.21583 142.98998)
			(xy 157.21583 142.99817) (xy 157.21583 143.00637) (xy 157.21583 143.01456) (xy 157.21583 143.02275)
			(xy 157.21583 143.03095) (xy 157.21583 143.03915) (xy 157.21583 143.04734) (xy 157.21583 143.05553)
			(xy 157.21583 143.06373) (xy 157.21583 143.07192) (xy 157.21583 143.08012) (xy 157.21583 143.08831)
			(xy 157.21583 143.09651) (xy 157.21583 143.1047) (xy 157.21583 143.1129) (xy 157.21583 143.12109)
			(xy 157.21583 143.12928) (xy 157.21583 143.13748) (xy 157.21583 143.14567) (xy 157.21583 143.15387)
			(xy 157.21583 143.16206) (xy 157.21583 143.17026) (xy 157.21583 143.17845) (xy 157.21583 143.18664)
			(xy 157.21583 143.19484) (xy 157.21583 143.20303) (xy 157.21583 143.21123) (xy 157.21583 143.21942)
			(xy 157.21583 143.22762) (xy 157.21583 143.23581) (xy 157.21583 143.24401) (xy 157.21583 143.2522)
			(xy 157.21583 143.26039) (xy 157.21583 143.26859) (xy 157.21583 143.27679) (xy 157.21583 143.28498)
			(xy 157.21583 143.29317) (xy 157.21583 143.30137) (xy 157.21583 143.30956) (xy 157.21583 143.31776)
			(xy 157.21583 143.32595) (xy 157.21583 143.33415) (xy 157.21583 143.34234) (xy 157.21583 143.35054)
			(xy 157.21583 143.35873) (xy 157.21583 143.36692) (xy 157.21583 143.37512) (xy 157.21583 143.38331)
			(xy 157.21583 143.39151) (xy 157.21583 143.3997) (xy 157.21583 143.4079) (xy 157.21583 143.41609)
			(xy 157.21583 143.42429) (xy 157.21583 143.43248) (xy 157.21583 143.44067) (xy 157.21583 143.44887)
			(xy 157.21583 143.45706) (xy 157.21583 143.46526) (xy 157.21583 143.47345) (xy 157.21583 143.48165)
			(xy 157.21583 143.48984) (xy 157.21583 143.49803) (xy 157.21583 143.50623) (xy 157.21583 143.51443)
			(xy 157.21583 143.52262) (xy 157.21583 143.53082) (xy 157.21583 143.53901) (xy 157.21583 143.5472)
			(xy 157.21583 143.5554) (xy 157.22402 143.5554) (xy 157.22402 143.56359) (xy 157.23222 143.56359)
			(xy 157.23222 143.57179) (xy 157.2486 143.57179) (xy 157.2486 143.57998) (xy 157.63375 143.57998)
			(xy 157.63375 143.57179) (xy 157.65013 143.57179) (xy 157.65013 143.56359) (xy 157.65833 143.56359)
			(xy 157.65833 143.5554) (xy 157.65833 143.5472) (xy 157.66652 143.5472) (xy 157.66652 143.53901)
			(xy 157.66652 143.53082) (xy 157.66652 143.52262) (xy 157.66652 143.51443) (xy 157.66652 143.50623)
			(xy 157.66652 143.49803) (xy 157.66652 143.48984) (xy 157.66652 143.48165) (xy 157.66652 143.47345)
			(xy 157.66652 143.46526) (xy 157.66652 143.45706) (xy 157.66652 143.44887) (xy 157.66652 143.44067)
			(xy 157.66652 143.43248) (xy 157.66652 143.42429) (xy 157.66652 143.41609) (xy 157.66652 143.4079)
			(xy 157.66652 143.3997) (xy 157.66652 143.39151) (xy 157.66652 143.38331) (xy 157.66652 143.37512)
			(xy 157.66652 143.36692) (xy 157.66652 143.35873) (xy 157.66652 143.35054) (xy 157.66652 143.34234)
			(xy 157.66652 143.33415) (xy 157.66652 143.32595) (xy 157.66652 143.31776) (xy 157.66652 143.30956)
			(xy 157.66652 143.30137) (xy 157.66652 143.29317) (xy 157.66652 143.28498) (xy 157.66652 143.27679)
			(xy 157.66652 143.26859) (xy 157.66652 143.26039) (xy 157.66652 143.2522) (xy 157.66652 143.24401)
			(xy 157.66652 143.23581) (xy 157.66652 143.22762) (xy 157.66652 143.21942) (xy 157.66652 143.21123)
			(xy 157.66652 143.20303) (xy 157.66652 143.19484) (xy 157.66652 143.18664) (xy 157.66652 143.17845)
			(xy 157.66652 143.17026) (xy 157.66652 143.16206) (xy 157.66652 143.15387) (xy 157.66652 143.14567)
			(xy 157.66652 143.13748) (xy 157.66652 143.12928) (xy 157.66652 143.12109) (xy 157.66652 143.1129)
			(xy 157.66652 143.1047) (xy 157.66652 143.09651) (xy 157.66652 143.08831) (xy 157.66652 143.08012)
			(xy 157.66652 143.07192) (xy 157.66652 143.06373) (xy 157.66652 143.05553) (xy 157.67472 143.05553)
			(xy 157.67472 143.04734) (xy 157.67472 143.03915) (xy 157.69111 143.03915) (xy 157.69111 143.03095)
			(xy 158.24014 143.03095) (xy 158.24014 143.03915) (xy 158.25653 143.03915) (xy 158.25653 143.04734)
			(xy 158.25653 143.05553) (xy 158.26472 143.05553) (xy 158.26472 143.06373) (xy 158.26472 143.07192)
			(xy 158.26472 143.08012) (xy 158.26472 143.08831) (xy 158.26472 143.09651) (xy 158.26472 143.1047)
			(xy 158.26472 143.1129) (xy 158.26472 143.12109) (xy 158.26472 143.12928) (xy 158.26472 143.13748)
			(xy 158.26472 143.14567) (xy 158.26472 143.15387) (xy 158.26472 143.16206) (xy 158.26472 143.17026)
			(xy 158.26472 143.17845) (xy 158.26472 143.18664) (xy 158.26472 143.19484) (xy 158.26472 143.20303)
			(xy 158.26472 143.21123) (xy 158.26472 143.21942) (xy 158.26472 143.22762) (xy 158.26472 143.23581)
			(xy 158.26472 143.24401) (xy 158.26472 143.2522) (xy 158.26472 143.26039) (xy 158.26472 143.26859)
			(xy 158.26472 143.27679) (xy 158.26472 143.28498) (xy 158.26472 143.29317) (xy 158.26472 143.30137)
			(xy 158.26472 143.30956) (xy 158.26472 143.31776) (xy 158.26472 143.32595) (xy 158.26472 143.33415)
			(xy 158.26472 143.34234) (xy 158.26472 143.35054) (xy 158.26472 143.35873) (xy 158.26472 143.36692)
			(xy 158.26472 143.37512) (xy 158.26472 143.38331) (xy 158.26472 143.39151) (xy 158.26472 143.3997)
			(xy 158.26472 143.4079) (xy 158.26472 143.41609) (xy 158.26472 143.42429) (xy 158.26472 143.43248)
			(xy 158.26472 143.44067) (xy 158.26472 143.44887) (xy 158.26472 143.45706) (xy 158.26472 143.46526)
			(xy 158.26472 143.47345) (xy 158.26472 143.48165) (xy 158.26472 143.48984) (xy 158.26472 143.49803)
			(xy 158.26472 143.50623) (xy 158.26472 143.51443) (xy 158.26472 143.52262) (xy 158.26472 143.53082)
			(xy 158.26472 143.53901) (xy 158.26472 143.5472) (xy 158.26472 143.5554) (xy 158.27292 143.5554)
			(xy 158.27292 143.56359) (xy 158.28111 143.56359) (xy 158.28111 143.57179) (xy 158.2975 143.57179)
			(xy 158.2975 143.57998) (xy 158.68264 143.57998) (xy 158.68264 143.57179) (xy 158.69903 143.57179)
			(xy 158.69903 143.56359) (xy 158.70722 143.56359) (xy 158.70722 143.5554) (xy 158.70722 143.5472)
			(xy 158.71542 143.5472) (xy 158.71542 143.53901) (xy 158.71542 143.53082) (xy 158.71542 143.52262)
			(xy 158.71542 143.51443) (xy 158.71542 143.50623) (xy 158.71542 143.49803) (xy 158.71542 143.48984)
			(xy 158.71542 143.48165) (xy 158.71542 143.47345) (xy 158.71542 143.46526) (xy 158.71542 143.45706)
			(xy 158.71542 143.44887) (xy 158.71542 143.44067) (xy 158.71542 143.43248) (xy 158.71542 143.42429)
			(xy 158.71542 143.41609) (xy 158.71542 143.4079) (xy 158.71542 143.3997) (xy 158.71542 143.39151)
			(xy 158.71542 143.38331) (xy 158.71542 143.37512) (xy 158.71542 143.36692) (xy 158.71542 143.35873)
			(xy 158.71542 143.35054) (xy 158.71542 143.34234) (xy 158.71542 143.33415) (xy 158.71542 143.32595)
			(xy 158.71542 143.31776) (xy 158.71542 143.30956) (xy 158.71542 143.30137) (xy 158.71542 143.29317)
			(xy 158.71542 143.28498) (xy 158.71542 143.27679) (xy 158.71542 143.26859) (xy 158.71542 143.26039)
			(xy 158.71542 143.2522) (xy 158.71542 143.24401) (xy 158.71542 143.23581) (xy 158.71542 143.22762)
			(xy 158.71542 143.21942) (xy 158.71542 143.21123) (xy 158.71542 143.20303) (xy 158.71542 143.19484)
			(xy 158.71542 143.18664) (xy 158.71542 143.17845) (xy 158.71542 143.17026) (xy 158.71542 143.16206)
			(xy 158.71542 143.15387) (xy 158.71542 143.14567) (xy 158.71542 143.13748) (xy 158.71542 143.12928)
			(xy 158.71542 143.12109) (xy 158.71542 143.1129) (xy 158.71542 143.1047) (xy 158.71542 143.09651)
			(xy 158.71542 143.08831) (xy 158.71542 143.08012) (xy 158.71542 143.07192) (xy 158.71542 143.06373)
			(xy 158.71542 143.05553) (xy 158.71542 143.04734) (xy 158.71542 143.03915) (xy 158.71542 143.03095)
			(xy 158.71542 143.02275) (xy 158.71542 143.01456) (xy 158.71542 143.00637) (xy 158.71542 142.99817)
			(xy 158.71542 142.98998) (xy 158.71542 142.98178) (xy 158.71542 142.97359) (xy 158.71542 142.96539)
			(xy 158.71542 142.9572) (xy 158.71542 142.949) (xy 158.71542 142.94081) (xy 158.71542 142.93262)
			(xy 158.71542 142.92442) (xy 158.71542 142.91623) (xy 158.71542 142.90803) (xy 158.71542 142.89984)
			(xy 158.71542 142.89164) (xy 158.71542 142.88345) (xy 158.71542 142.87525) (xy 158.71542 142.86706)
			(xy 158.71542 142.85887) (xy 158.71542 142.85067) (xy 158.71542 142.84248) (xy 158.71542 142.83428)
			(xy 158.71542 142.82609) (xy 158.71542 142.81789) (xy 158.71542 142.8097) (xy 158.71542 142.8015)
			(xy 158.71542 142.79331) (xy 158.71542 142.78511) (xy 158.71542 142.77692) (xy 158.71542 142.76873)
			(xy 158.71542 142.76053) (xy 158.71542 142.75234) (xy 158.71542 142.74414) (xy 158.71542 142.73595)
			(xy 158.71542 142.72775) (xy 158.71542 142.71956) (xy 158.71542 142.71136) (xy 158.71542 142.70317)
			(xy 158.71542 142.69498) (xy 158.71542 142.68678) (xy 158.71542 142.67859) (xy 158.71542 142.67039)
			(xy 158.71542 142.6622) (xy 158.71542 142.654) (xy 158.71542 142.64581) (xy 158.71542 142.63761)
			(xy 158.71542 142.62942) (xy 158.71542 142.62123) (xy 158.71542 142.61303) (xy 158.71542 142.60484)
			(xy 158.71542 142.59664) (xy 158.71542 142.58845) (xy 158.71542 142.58025) (xy 158.71542 142.57206)
			(xy 158.71542 142.56387) (xy 158.71542 142.55567) (xy 158.71542 142.54747) (xy 158.71542 142.53928)
			(xy 158.71542 142.53108) (xy 158.71542 142.52289) (xy 158.71542 142.5147) (xy 158.71542 142.5065)
			(xy 158.71542 142.49831) (xy 158.71542 142.49011) (xy 158.71542 142.48192) (xy 158.71542 142.47372)
			(xy 158.71542 142.46553) (xy 158.71542 142.45734) (xy 158.71542 142.44914) (xy 158.71542 142.44095)
			(xy 158.71542 142.43275) (xy 158.71542 142.42456) (xy 158.71542 142.41636) (xy 158.71542 142.40817)
			(xy 158.71542 142.39997) (xy 158.71542 142.39178) (xy 158.71542 142.38359) (xy 158.71542 142.37539)
			(xy 158.71542 142.3672) (xy 158.71542 142.359) (xy 158.71542 142.35081) (xy 158.71542 142.34261)
			(xy 158.71542 142.33442) (xy 158.71542 142.32622) (xy 158.71542 142.31803) (xy 158.71542 142.30984)
			(xy 158.71542 142.30164) (xy 158.71542 142.29344) (xy 158.71542 142.28525) (xy 158.71542 142.27706)
			(xy 158.71542 142.26886) (xy 158.71542 142.26067) (xy 158.71542 142.25247) (xy 158.71542 142.24428)
			(xy 158.71542 142.23608) (xy 158.71542 142.22789) (xy 158.71542 142.21969) (xy 158.71542 142.2115)
			(xy 158.71542 142.20331) (xy 158.71542 142.19511) (xy 158.71542 142.18692) (xy 158.71542 142.17872)
			(xy 158.71542 142.17053) (xy 158.71542 142.16233) (xy 158.71542 142.15414) (xy 158.71542 142.14594)
			(xy 158.71542 142.13775) (xy 158.71542 142.12956) (xy 158.71542 142.12136) (xy 158.71542 142.11317)
			(xy 158.71542 142.10497) (xy 158.70722 142.10497) (xy 158.70722 142.09678) (xy 158.70722 142.08858)
			(xy 158.70722 142.08039) (xy 158.70722 142.07219) (xy 158.69903 142.07219) (xy 158.69903 142.064)
			(xy 158.69903 142.0558) (xy 158.69903 142.04761) (xy 158.69084 142.04761) (xy 158.69084 142.03942)
			(xy 158.68264 142.03942) (xy 158.68264 142.03122) (xy 158.67445 142.03122) (xy 158.67445 142.02303)
			(xy 158.66625 142.02303) (xy 158.66625 142.01483) (xy 158.65806 142.01483) (xy 158.65806 142.00664)
			(xy 158.64986 142.00664) (xy 158.64986 141.99844) (xy 158.64167 141.99844) (xy 158.64167 141.99025)
			(xy 158.63347 141.99025) (xy 158.63347 141.98205) (xy 158.62528 141.98205) (xy 158.62528 141.97386)
			(xy 158.61708 141.97386) (xy 158.61708 141.96567) (xy 158.60889 141.96567) (xy 158.60889 141.95747)
			(xy 158.6007 141.95747) (xy 158.6007 141.94927) (xy 158.5925 141.94927) (xy 158.5925 141.94108) (xy 158.58431 141.94108)
			(xy 158.58431 141.93289) (xy 158.57611 141.93289) (xy 158.57611 141.92469) (xy 158.56792 141.92469)
			(xy 158.56792 141.9165) (xy 158.55972 141.9165) (xy 158.55972 141.9083) (xy 158.55153 141.9083) (xy 158.55153 141.90011)
			(xy 158.54334 141.90011) (xy 158.54334 141.89192) (xy 158.53514 141.89192) (xy 158.53514 141.88372)
			(xy 158.52694 141.88372) (xy 158.52694 141.87553) (xy 158.51875 141.87553) (xy 158.51875 141.86733)
			(xy 158.51055 141.86733) (xy 158.51055 141.85914) (xy 158.50236 141.85914) (xy 158.50236 141.85094)
			(xy 158.49417 141.85094) (xy 158.49417 141.84275) (xy 158.88751 141.84275) (xy 158.88751 141.85094)
			(xy 158.88751 141.85914) (xy 158.88751 141.86733) (xy 158.88751 141.87553) (xy 158.88751 141.88372)
			(xy 158.88751 141.89192) (xy 158.88751 141.90011) (xy 158.88751 141.9083) (xy 158.88751 141.9165)
			(xy 158.88751 141.92469) (xy 158.88751 141.93289) (xy 158.88751 141.94108) (xy 158.88751 141.94927)
			(xy 158.88751 141.95747) (xy 158.88751 141.96567) (xy 158.88751 141.97386) (xy 158.88751 141.98205)
			(xy 158.88751 141.99025) (xy 158.88751 141.99844) (xy 158.88751 142.00664) (xy 158.88751 142.01483)
			(xy 158.88751 142.02303) (xy 158.88751 142.03122) (xy 158.88751 142.03942) (xy 158.88751 142.04761)
			(xy 158.88751 142.0558) (xy 158.88751 142.064) (xy 158.88751 142.07219) (xy 158.88751 142.08039)
			(xy 158.88751 142.08858) (xy 158.88751 142.09678) (xy 158.88751 142.10497) (xy 158.88751 142.11317)
			(xy 158.88751 142.12136) (xy 158.88751 142.12956) (xy 158.88751 142.13775) (xy 158.88751 142.14594)
			(xy 158.88751 142.15414) (xy 158.88751 142.16233) (xy 158.88751 142.17053) (xy 158.88751 142.17872)
			(xy 158.88751 142.18692) (xy 158.88751 142.19511) (xy 158.88751 142.20331) (xy 158.88751 142.2115)
			(xy 158.88751 142.21969) (xy 158.88751 142.22789) (xy 158.88751 142.23608) (xy 158.88751 142.24428)
			(xy 158.88751 142.25247) (xy 158.88751 142.26067) (xy 158.88751 142.26886) (xy 158.88751 142.27706)
			(xy 158.88751 142.28525) (xy 158.88751 142.29344) (xy 158.88751 142.30164) (xy 158.88751 142.30984)
			(xy 158.88751 142.31803) (xy 158.88751 142.32622) (xy 158.88751 142.33442) (xy 158.88751 142.34261)
			(xy 158.88751 142.35081) (xy 158.88751 142.359) (xy 158.88751 142.3672) (xy 158.88751 142.37539)
			(xy 158.88751 142.38359) (xy 158.88751 142.39178) (xy 158.88751 142.39997) (xy 158.88751 142.40817)
			(xy 158.88751 142.41636) (xy 158.88751 142.42456) (xy 158.88751 142.43275) (xy 158.88751 142.44095)
			(xy 158.88751 142.44914) (xy 158.88751 142.45734) (xy 158.88751 142.46553) (xy 158.88751 142.47372)
			(xy 158.88751 142.48192) (xy 158.88751 142.49011) (xy 158.88751 142.49831) (xy 158.88751 142.5065)
			(xy 158.88751 142.5147) (xy 158.88751 142.52289) (xy 158.88751 142.53108) (xy 158.88751 142.53928)
			(xy 158.88751 142.54747) (xy 158.88751 142.55567) (xy 158.88751 142.56387) (xy 158.88751 142.57206)
			(xy 158.88751 142.58025) (xy 158.88751 142.58845) (xy 158.88751 142.59664) (xy 158.88751 142.60484)
			(xy 158.88751 142.61303) (xy 158.88751 142.62123) (xy 158.88751 142.62942) (xy 158.88751 142.63761)
			(xy 158.88751 142.64581) (xy 158.88751 142.654) (xy 158.88751 142.6622) (xy 158.88751 142.67039)
			(xy 158.88751 142.67859) (xy 158.88751 142.68678) (xy 158.88751 142.69498) (xy 158.88751 142.70317)
			(xy 158.88751 142.71136) (xy 158.88751 142.71956) (xy 158.88751 142.72775) (xy 158.88751 142.73595)
			(xy 158.88751 142.74414) (xy 158.88751 142.75234) (xy 158.88751 142.76053) (xy 158.88751 142.76873)
			(xy 158.88751 142.77692) (xy 158.88751 142.78511) (xy 158.88751 142.79331) (xy 158.88751 142.8015)
			(xy 158.88751 142.8097) (xy 158.88751 142.81789) (xy 158.88751 142.82609) (xy 158.88751 142.83428)
			(xy 158.88751 142.84248) (xy 158.88751 142.85067) (xy 158.88751 142.85887) (xy 158.88751 142.86706)
			(xy 158.88751 142.87525) (xy 158.88751 142.88345) (xy 158.88751 142.89164) (xy 158.88751 142.89984)
			(xy 158.88751 142.90803) (xy 158.88751 142.91623) (xy 158.88751 142.92442) (xy 158.88751 142.93262)
			(xy 158.88751 142.94081) (xy 158.88751 142.949) (xy 158.88751 142.9572) (xy 158.88751 142.96539)
			(xy 158.88751 142.97359) (xy 158.88751 142.98178) (xy 158.88751 142.98998) (xy 158.88751 142.99817)
			(xy 158.88751 143.00637) (xy 158.88751 143.01456) (xy 158.88751 143.02275) (xy 158.88751 143.03095)
			(xy 158.88751 143.03915) (xy 158.88751 143.04734) (xy 158.88751 143.05553) (xy 158.88751 143.06373)
			(xy 158.88751 143.07192) (xy 158.88751 143.08012) (xy 158.88751 143.08831) (xy 158.88751 143.09651)
			(xy 158.88751 143.1047) (xy 158.88751 143.1129) (xy 158.88751 143.12109) (xy 158.88751 143.12928)
			(xy 158.88751 143.13748) (xy 158.88751 143.14567) (xy 158.88751 143.15387) (xy 158.88751 143.16206)
			(xy 158.88751 143.17026) (xy 158.88751 143.17845) (xy 158.88751 143.18664) (xy 158.88751 143.19484)
			(xy 158.88751 143.20303) (xy 158.88751 143.21123) (xy 158.88751 143.21942) (xy 158.88751 143.22762)
			(xy 158.88751 143.23581) (xy 158.88751 143.24401) (xy 158.88751 143.2522) (xy 158.88751 143.26039)
			(xy 158.88751 143.26859) (xy 158.88751 143.27679) (xy 158.88751 143.28498) (xy 158.88751 143.29317)
			(xy 158.88751 143.30137) (xy 158.88751 143.30956) (xy 158.88751 143.31776) (xy 158.88751 143.32595)
			(xy 158.88751 143.33415) (xy 158.88751 143.34234) (xy 158.88751 143.35054) (xy 158.88751 143.35873)
			(xy 158.88751 143.36692) (xy 158.88751 143.37512) (xy 158.88751 143.38331) (xy 158.88751 143.39151)
			(xy 158.88751 143.3997) (xy 158.88751 143.4079) (xy 158.88751 143.41609) (xy 158.88751 143.42429)
			(xy 158.88751 143.43248) (xy 158.88751 143.44067) (xy 158.88751 143.44887) (xy 158.88751 143.45706)
			(xy 158.88751 143.46526) (xy 158.88751 143.47345) (xy 158.88751 143.48165) (xy 158.88751 143.48984)
			(xy 158.88751 143.49803) (xy 158.88751 143.50623) (xy 158.88751 143.51443) (xy 158.88751 143.52262)
			(xy 158.8957 143.52262) (xy 158.8957 143.53082) (xy 158.88751 143.53082) (xy 158.88751 143.53901)
			(xy 158.8957 143.53901) (xy 158.8957 143.5472) (xy 158.8957 143.5554) (xy 158.8957 143.56359) (xy 158.90389 143.56359)
			(xy 158.90389 143.57179) (xy 158.92028 143.57179) (xy 158.92028 143.57998) (xy 159.32181 143.57998)
			(xy 159.32181 143.57179) (xy 159.33001 143.57179) (xy 159.33001 143.56359) (xy 159.3382 143.56359)
			(xy 159.3382 143.5554) (xy 159.3382 143.5472) (xy 159.3382 143.53901) (xy 159.34639 143.53901) (xy 159.34639 143.53082)
			(xy 159.34639 143.52262) (xy 159.34639 143.51443) (xy 159.34639 143.50623) (xy 159.34639 143.49803)
			(xy 159.34639 143.48984) (xy 159.34639 143.48165) (xy 159.34639 143.47345) (xy 159.34639 143.46526)
			(xy 159.34639 143.45706) (xy 159.34639 143.44887) (xy 159.34639 143.44067) (xy 159.34639 143.43248)
			(xy 159.34639 143.42429) (xy 159.34639 143.41609) (xy 159.34639 143.4079) (xy 159.34639 143.3997)
			(xy 159.34639 143.39151) (xy 159.34639 143.38331) (xy 159.34639 143.37512) (xy 159.34639 143.36692)
			(xy 159.34639 143.35873) (xy 159.34639 143.35054) (xy 159.34639 143.34234) (xy 159.34639 143.33415)
			(xy 159.34639 143.32595) (xy 159.34639 143.31776) (xy 159.34639 143.30956) (xy 159.34639 143.30137)
			(xy 159.34639 143.29317) (xy 159.34639 143.28498) (xy 159.34639 143.27679) (xy 159.34639 143.26859)
			(xy 159.34639 143.26039) (xy 159.34639 143.2522) (xy 159.34639 143.24401) (xy 159.34639 143.23581)
			(xy 159.34639 143.22762) (xy 159.34639 143.21942) (xy 159.34639 143.21123) (xy 159.34639 143.20303)
			(xy 159.34639 143.19484) (xy 159.34639 143.18664) (xy 159.34639 143.17845) (xy 159.34639 143.17026)
			(xy 159.34639 143.16206) (xy 159.34639 143.15387) (xy 159.34639 143.14567) (xy 159.34639 143.13748)
			(xy 159.34639 143.12928) (xy 159.34639 143.12109) (xy 159.34639 143.1129) (xy 159.34639 143.1047)
			(xy 159.34639 143.09651) (xy 159.3382 143.09651) (xy 159.3382 143.08831) (xy 159.34639 143.08831)
			(xy 159.34639 143.08012) (xy 159.34639 143.07192) (xy 159.34639 143.06373) (xy 159.34639 143.05553)
			(xy 159.34639 143.04734) (xy 159.65779 143.04734) (xy 159.65779 143.05553) (xy 159.65779 143.06373)
			(xy 159.66598 143.06373) (xy 159.66598 143.07192) (xy 159.66598 143.08012) (xy 159.67417 143.08012)
			(xy 159.67417 143.08831) (xy 159.68237 143.08831) (xy 159.68237 143.09651) (xy 159.68237 143.1047)
			(xy 159.69056 143.1047) (xy 159.69056 143.1129) (xy 159.69056 143.12109) (xy 159.69876 143.12109)
			(xy 159.69876 143.12928) (xy 159.70695 143.12928) (xy 159.70695 143.13748) (xy 159.70695 143.14567)
			(xy 159.71515 143.14567) (xy 159.71515 143.15387) (xy 159.71515 143.16206) (xy 159.72334 143.16206)
			(xy 159.72334 143.17026) (xy 159.72334 143.17845) (xy 159.73153 143.17845) (xy 159.73153 143.18664)
			(xy 159.73973 143.18664) (xy 159.73973 143.19484) (xy 159.73973 143.20303) (xy 159.74793 143.20303)
			(xy 159.74793 143.21123) (xy 159.74793 143.21942) (xy 159.75612 143.21942) (xy 159.75612 143.22762)
			(xy 159.76431 143.22762) (xy 159.76431 143.23581) (xy 159.76431 143.24401) (xy 159.77251 143.24401)
			(xy 159.77251 143.2522) (xy 159.77251 143.26039) (xy 159.7807 143.26039) (xy 159.7807 143.26859)
			(xy 159.7889 143.26859) (xy 159.7889 143.27679) (xy 159.7889 143.28498) (xy 159.79709 143.28498)
			(xy 159.79709 143.29317) (xy 159.79709 143.30137) (xy 159.80529 143.30137) (xy 159.80529 143.30956)
			(xy 159.80529 143.31776) (xy 159.81348 143.31776) (xy 159.81348 143.32595) (xy 159.82168 143.32595)
			(xy 159.82168 143.33415) (xy 159.82168 143.34234) (xy 159.82987 143.34234) (xy 159.82987 143.35054)
			(xy 159.82987 143.35873) (xy 159.83806 143.35873) (xy 159.83806 143.36692) (xy 159.84626 143.36692)
			(xy 159.84626 143.37512) (xy 159.84626 143.38331) (xy 159.85445 143.38331) (xy 159.85445 143.39151)
			(xy 159.85445 143.3997) (xy 159.86265 143.3997) (xy 159.86265 143.4079) (xy 159.87084 143.4079) (xy 159.87084 143.41609)
			(xy 159.87084 143.42429) (xy 159.87904 143.42429) (xy 159.87904 143.43248) (xy 159.87904 143.44067)
			(xy 159.88723 143.44067) (xy 159.88723 143.44887) (xy 159.89543 143.44887) (xy 159.89543 143.45706)
			(xy 159.89543 143.46526) (xy 159.90362 143.46526) (xy 159.90362 143.47345) (xy 159.90362 143.48165)
			(xy 159.91182 143.48165) (xy 159.91182 143.48984) (xy 159.91182 143.49803) (xy 159.92001 143.49803)
			(xy 159.92001 143.50623) (xy 159.9282 143.50623) (xy 159.9282 143.51443) (xy 159.9282 143.52262)
			(xy 159.9364 143.52262) (xy 159.9364 143.53082) (xy 159.9364 143.53901) (xy 159.94459 143.53901)
			(xy 159.94459 143.5472) (xy 159.95279 143.5472) (xy 159.95279 143.5554) (xy 159.96098 143.5554) (xy 159.96098 143.56359)
			(xy 159.96917 143.56359) (xy 159.96917 143.57179) (xy 159.98557 143.57179) (xy 159.98557 143.57998)
			(xy 160.44446 143.57998) (xy 160.44446 143.57179) (xy 160.45265 143.57179) (xy 160.45265 143.56359)
			(xy 160.45265 143.5554) (xy 160.45265 143.5472) (xy 160.45265 143.53901) (xy 160.44446 143.53901)
			(xy 160.44446 143.53082) (xy 160.43626 143.53082) (xy 160.43626 143.52262) (xy 160.43626 143.51443)
			(xy 160.42807 143.51443) (xy 160.42807 143.50623) (xy 160.42807 143.49803) (xy 160.41987 143.49803)
			(xy 160.41987 143.48984) (xy 160.41168 143.48984) (xy 160.41168 143.48165) (xy 160.41168 143.47345)
			(xy 160.40349 143.47345) (xy 160.40349 143.46526) (xy 160.40349 143.45706) (xy 160.39529 143.45706)
			(xy 160.39529 143.44887) (xy 160.3871 143.44887) (xy 160.3871 143.44067) (xy 160.3871 143.43248)
			(xy 160.3789 143.43248) (xy 160.3789 143.42429) (xy 160.3789 143.41609) (xy 160.37071 143.41609)
			(xy 160.37071 143.4079) (xy 160.36251 143.4079) (xy 160.36251 143.3997) (xy 160.36251 143.39151)
			(xy 160.35432 143.39151) (xy 160.35432 143.38331) (xy 160.35432 143.37512) (xy 160.34613 143.37512)
			(xy 160.34613 143.36692) (xy 160.33793 143.36692) (xy 160.33793 143.35873) (xy 160.33793 143.35054)
			(xy 160.32974 143.35054) (xy 160.32974 143.34234) (xy 160.32974 143.33415) (xy 160.32154 143.33415)
			(xy 160.32154 143.32595) (xy 160.31334 143.32595) (xy 160.31334 143.31776) (xy 160.31334 143.30956)
			(xy 160.30515 143.30956) (xy 160.30515 143.30137) (xy 160.30515 143.29317) (xy 160.29696 143.29317)
			(xy 160.29696 143.28498) (xy 160.28876 143.28498) (xy 160.28876 143.27679) (xy 160.28876 143.26859)
			(xy 160.28057 143.26859) (xy 160.28057 143.26039) (xy 160.28057 143.2522) (xy 160.27237 143.2522)
			(xy 160.27237 143.24401) (xy 160.26418 143.24401) (xy 160.26418 143.23581) (xy 160.26418 143.22762)
			(xy 160.25598 143.22762) (xy 160.25598 143.21942) (xy 160.25598 143.21123) (xy 160.24779 143.21123)
			(xy 160.24779 143.20303) (xy 160.2396 143.20303) (xy 160.2396 143.19484) (xy 160.2396 143.18664)
			(xy 160.2314 143.18664) (xy 160.2314 143.17845) (xy 160.2314 143.17026) (xy 160.22321 143.17026)
			(xy 160.22321 143.16206) (xy 160.21501 143.16206) (xy 160.21501 143.15387) (xy 160.21501 143.14567)
			(xy 160.20682 143.14567) (xy 160.20682 143.13748) (xy 160.20682 143.12928) (xy 160.19862 143.12928)
			(xy 160.19862 143.12109) (xy 160.19043 143.12109) (xy 160.19043 143.1129) (xy 160.19043 143.1047)
			(xy 160.18223 143.1047) (xy 160.18223 143.09651) (xy 160.18223 143.08831) (xy 160.17404 143.08831)
			(xy 160.17404 143.08012) (xy 160.17404 143.07192) (xy 160.16584 143.07192) (xy 160.16584 143.06373)
			(xy 160.15765 143.06373) (xy 160.15765 143.05553) (xy 160.15765 143.04734) (xy 160.14946 143.04734)
			(xy 160.14946 143.03915) (xy 160.14946 143.03095) (xy 160.14126 143.03095) (xy 160.14126 143.02275)
			(xy 160.13307 143.02275) (xy 160.13307 143.01456) (xy 160.13307 143.00637) (xy 160.14126 143.00637)
			(xy 160.14126 142.99817) (xy 160.14946 142.99817) (xy 160.14946 142.98998) (xy 160.15765 142.98998)
			(xy 160.15765 142.98178) (xy 160.16584 142.98178) (xy 160.16584 142.97359) (xy 160.17404 142.97359)
			(xy 160.17404 142.96539) (xy 160.18223 142.96539) (xy 160.18223 142.9572) (xy 160.19043 142.9572)
			(xy 160.19043 142.949) (xy 160.19862 142.949) (xy 160.19862 142.94081) (xy 160.20682 142.94081) (xy 160.20682 142.93262)
			(xy 160.21501 142.93262) (xy 160.21501 142.92442) (xy 160.22321 142.92442) (xy 160.22321 142.91623)
			(xy 160.2314 142.91623) (xy 160.2314 142.90803) (xy 160.2396 142.90803) (xy 160.2396 142.89984) (xy 160.24779 142.89984)
			(xy 160.24779 142.89164) (xy 160.25598 142.89164) (xy 160.25598 142.88345) (xy 160.26418 142.88345)
			(xy 160.26418 142.87525) (xy 160.27237 142.87525) (xy 160.27237 142.86706) (xy 160.28057 142.86706)
			(xy 160.28057 142.85887) (xy 160.28876 142.85887) (xy 160.28876 142.85067) (xy 160.29696 142.85067)
			(xy 160.29696 142.84248) (xy 160.30515 142.84248) (xy 160.30515 142.83428) (xy 160.31334 142.83428)
			(xy 160.31334 142.82609) (xy 160.32154 142.82609) (xy 160.32154 142.81789) (xy 160.32154 142.8097)
			(xy 160.32974 142.8097) (xy 160.32974 142.8015) (xy 160.33793 142.8015) (xy 160.33793 142.79331)
			(xy 160.34613 142.79331) (xy 160.34613 142.78511) (xy 160.35432 142.78511) (xy 160.35432 142.77692)
			(xy 160.36251 142.77692) (xy 160.36251 142.76873) (xy 160.37071 142.76873) (xy 160.37071 142.76053)
			(xy 160.37071 142.75234) (xy 160.3789 142.75234) (xy 160.3789 142.74414) (xy 160.3789 142.73595)
			(xy 160.3871 142.73595) (xy 160.3871 142.72775) (xy 160.3871 142.71956) (xy 160.3871 142.71136) (xy 160.3871 142.70317)
			(xy 160.3871 142.69498) (xy 160.3871 142.68678) (xy 160.3871 142.67859) (xy 160.3871 142.67039) (xy 160.3871 142.6622)
			(xy 160.3871 142.654) (xy 160.3871 142.64581) (xy 160.3871 142.63761) (xy 160.3871 142.62942) (xy 160.3871 142.62123)
			(xy 160.3871 142.61303) (xy 160.3871 142.60484) (xy 160.3871 142.59664) (xy 160.3871 142.58845) (xy 160.3871 142.58025)
			(xy 160.3871 142.57206) (xy 160.3871 142.56387) (xy 160.3871 142.55567) (xy 160.3871 142.54747) (xy 160.3871 142.53928)
			(xy 160.3871 142.53108) (xy 160.3871 142.52289) (xy 160.3871 142.5147) (xy 160.3871 142.5065) (xy 160.3871 142.49831)
			(xy 160.3871 142.49011) (xy 160.3871 142.48192) (xy 160.3871 142.47372) (xy 160.3871 142.46553) (xy 160.3871 142.45734)
			(xy 160.3871 142.44914) (xy 160.3871 142.44095) (xy 160.3871 142.43275) (xy 160.3871 142.42456) (xy 160.3871 142.41636)
			(xy 160.3871 142.40817) (xy 160.3871 142.39997) (xy 160.3871 142.39178) (xy 160.3871 142.38359) (xy 160.3871 142.37539)
			(xy 160.3871 142.3672) (xy 160.3871 142.359) (xy 160.3871 142.35081) (xy 160.3871 142.34261) (xy 160.3871 142.33442)
			(xy 160.3871 142.32622) (xy 160.3871 142.31803) (xy 160.3871 142.30984) (xy 160.3871 142.30164) (xy 160.3871 142.29344)
			(xy 160.3871 142.28525) (xy 160.3871 142.27706) (xy 160.3871 142.26886) (xy 160.3871 142.26067) (xy 160.3871 142.25247)
			(xy 160.3871 142.24428) (xy 160.3871 142.23608) (xy 160.3871 142.22789) (xy 160.3871 142.21969) (xy 160.3871 142.2115)
			(xy 160.3871 142.20331) (xy 160.3871 142.19511) (xy 160.3871 142.18692) (xy 160.3871 142.17872) (xy 160.3871 142.17053)
			(xy 160.3871 142.16233) (xy 160.3871 142.15414) (xy 160.3871 142.14594) (xy 160.3871 142.13775) (xy 160.3871 142.12956)
			(xy 160.3871 142.12136) (xy 160.3871 142.11317) (xy 160.3871 142.10497) (xy 160.3871 142.09678) (xy 160.3871 142.08858)
			(xy 160.3789 142.08858) (xy 160.3789 142.08039) (xy 160.3789 142.07219) (xy 160.3789 142.064) (xy 160.37071 142.064)
			(xy 160.37071 142.0558) (xy 160.37071 142.04761) (xy 160.36251 142.04761) (xy 160.36251 142.03942)
			(xy 160.35432 142.03942) (xy 160.35432 142.03122) (xy 160.34613 142.03122) (xy 160.34613 142.02303)
			(xy 160.33793 142.02303) (xy 160.33793 142.01483) (xy 160.32974 142.01483) (xy 160.32974 142.00664)
			(xy 160.32154 142.00664) (xy 160.32154 141.99844) (xy 160.31334 141.99844) (xy 160.31334 141.99025)
			(xy 160.30515 141.99025) (xy 160.30515 141.98205) (xy 160.29696 141.98205) (xy 160.29696 141.97386)
			(xy 160.28876 141.97386) (xy 160.28876 141.96567) (xy 160.28057 141.96567) (xy 160.28057 141.95747)
			(xy 160.27237 141.95747) (xy 160.27237 141.94927) (xy 160.26418 141.94927) (xy 160.26418 141.94108)
			(xy 160.25598 141.94108) (xy 160.25598 141.93289) (xy 160.24779 141.93289) (xy 160.24779 141.92469)
			(xy 160.2396 141.92469) (xy 160.2396 141.9165) (xy 160.2314 141.9165) (xy 160.2314 141.9083) (xy 160.22321 141.9083)
			(xy 160.22321 141.90011) (xy 160.21501 141.90011) (xy 160.21501 141.89192) (xy 160.20682 141.89192)
			(xy 160.20682 141.88372) (xy 160.19862 141.88372) (xy 160.19862 141.87553) (xy 160.19043 141.87553)
			(xy 160.19043 141.86733) (xy 160.18223 141.86733) (xy 160.18223 141.85914) (xy 160.17404 141.85914)
			(xy 160.17404 141.85094) (xy 160.16584 141.85094) (xy 160.16584 141.84275) (xy 160.15765 141.84275)
			(xy 160.15765 141.83456) (xy 160.14946 141.83456) (xy 160.14946 141.82636) (xy 160.63293 141.82636)
			(xy 160.63293 141.83456) (xy 160.63293 141.84275) (xy 160.63293 141.85094) (xy 160.63293 141.85914)
			(xy 160.63293 141.86733) (xy 160.63293 141.87553) (xy 160.63293 141.88372) (xy 160.63293 141.89192)
			(xy 160.63293 141.90011) (xy 160.63293 141.9083) (xy 160.63293 141.9165) (xy 160.63293 141.92469)
			(xy 160.63293 141.93289) (xy 160.63293 141.94108) (xy 160.63293 141.94927) (xy 160.63293 141.95747)
			(xy 160.63293 141.96567) (xy 160.63293 141.97386) (xy 160.63293 141.98205) (xy 160.63293 141.99025)
			(xy 160.63293 141.99844) (xy 160.63293 142.00664) (xy 160.63293 142.01483) (xy 160.63293 142.02303)
			(xy 160.63293 142.03122) (xy 160.63293 142.03942) (xy 160.63293 142.04761) (xy 160.63293 142.0558)
			(xy 160.63293 142.064) (xy 160.63293 142.07219) (xy 160.63293 142.08039) (xy 160.63293 142.08858)
			(xy 160.63293 142.09678) (xy 160.63293 142.10497) (xy 160.63293 142.11317) (xy 160.63293 142.12136)
			(xy 160.63293 142.12956) (xy 160.63293 142.13775) (xy 160.63293 142.14594) (xy 160.63293 142.15414)
			(xy 160.63293 142.16233) (xy 160.63293 142.17053) (xy 160.63293 142.17872) (xy 160.63293 142.18692)
			(xy 160.63293 142.19511) (xy 160.63293 142.20331) (xy 160.63293 142.2115) (xy 160.63293 142.21969)
			(xy 160.63293 142.22789) (xy 160.63293 142.23608) (xy 160.63293 142.24428) (xy 160.63293 142.25247)
			(xy 160.63293 142.26067) (xy 160.63293 142.26886) (xy 160.63293 142.27706) (xy 160.63293 142.28525)
			(xy 160.63293 142.29344) (xy 160.63293 142.30164) (xy 160.63293 142.30984) (xy 160.63293 142.31803)
			(xy 160.63293 142.32622) (xy 160.63293 142.33442) (xy 160.63293 142.34261) (xy 160.63293 142.35081)
			(xy 160.63293 142.359) (xy 160.63293 142.3672) (xy 160.63293 142.37539) (xy 160.63293 142.38359)
			(xy 160.63293 142.39178) (xy 160.63293 142.39997) (xy 160.63293 142.40817) (xy 160.63293 142.41636)
			(xy 160.63293 142.42456) (xy 160.63293 142.43275) (xy 160.63293 142.44095) (xy 160.63293 142.44914)
			(xy 160.63293 142.45734) (xy 160.63293 142.46553) (xy 160.63293 142.47372) (xy 160.63293 142.48192)
			(xy 160.63293 142.49011) (xy 160.63293 142.49831) (xy 160.63293 142.5065) (xy 160.63293 142.5147)
			(xy 160.63293 142.52289) (xy 160.63293 142.53108) (xy 160.63293 142.53928) (xy 160.63293 142.54747)
			(xy 160.63293 142.55567) (xy 160.63293 142.56387) (xy 160.63293 142.57206) (xy 160.63293 142.58025)
			(xy 160.63293 142.58845) (xy 160.63293 142.59664) (xy 160.63293 142.60484) (xy 160.63293 142.61303)
			(xy 160.63293 142.62123) (xy 160.63293 142.62942) (xy 160.63293 142.63761) (xy 160.63293 142.64581)
			(xy 160.63293 142.654) (xy 160.63293 142.6622) (xy 160.63293 142.67039) (xy 160.63293 142.67859)
			(xy 160.63293 142.68678) (xy 160.63293 142.69498) (xy 160.63293 142.70317) (xy 160.63293 142.71136)
			(xy 160.63293 142.71956) (xy 160.63293 142.72775) (xy 160.63293 142.73595) (xy 160.63293 142.74414)
			(xy 160.63293 142.75234) (xy 160.63293 142.76053) (xy 160.63293 142.76873) (xy 160.63293 142.77692)
			(xy 160.63293 142.78511) (xy 160.63293 142.79331) (xy 160.63293 142.8015) (xy 160.63293 142.8097)
			(xy 160.63293 142.81789) (xy 160.63293 142.82609) (xy 160.63293 142.83428) (xy 160.63293 142.84248)
			(xy 160.63293 142.85067) (xy 160.63293 142.85887) (xy 160.63293 142.86706) (xy 160.63293 142.87525)
			(xy 160.63293 142.88345) (xy 160.63293 142.89164) (xy 160.63293 142.89984) (xy 160.63293 142.90803)
			(xy 160.63293 142.91623) (xy 160.63293 142.92442) (xy 160.63293 142.93262) (xy 160.63293 142.94081)
			(xy 160.63293 142.949) (xy 160.63293 142.9572) (xy 160.63293 142.96539) (xy 160.63293 142.97359)
			(xy 160.63293 142.98178) (xy 160.63293 142.98998) (xy 160.63293 142.99817) (xy 160.63293 143.00637)
			(xy 160.63293 143.01456) (xy 160.63293 143.02275) (xy 160.63293 143.03095) (xy 160.63293 143.03915)
			(xy 160.63293 143.04734) (xy 160.63293 143.05553) (xy 160.63293 143.06373) (xy 160.63293 143.07192)
			(xy 160.63293 143.08012) (xy 160.63293 143.08831) (xy 160.63293 143.09651) (xy 160.63293 143.1047)
			(xy 160.63293 143.1129) (xy 160.63293 143.12109) (xy 160.63293 143.12928) (xy 160.63293 143.13748)
			(xy 160.63293 143.14567) (xy 160.63293 143.15387) (xy 160.63293 143.16206) (xy 160.63293 143.17026)
			(xy 160.63293 143.17845) (xy 160.63293 143.18664) (xy 160.63293 143.19484) (xy 160.63293 143.20303)
			(xy 160.63293 143.21123) (xy 160.63293 143.21942) (xy 160.63293 143.22762) (xy 160.63293 143.23581)
			(xy 160.63293 143.24401) (xy 160.63293 143.2522) (xy 160.63293 143.26039) (xy 160.63293 143.26859)
			(xy 160.63293 143.27679) (xy 160.63293 143.28498) (xy 160.63293 143.29317) (xy 160.63293 143.30137)
			(xy 160.63293 143.30956) (xy 160.63293 143.31776) (xy 160.63293 143.32595) (xy 160.63293 143.33415)
			(xy 160.63293 143.34234) (xy 160.63293 143.35054) (xy 160.63293 143.35873) (xy 160.63293 143.36692)
			(xy 160.63293 143.37512) (xy 160.63293 143.38331) (xy 160.63293 143.39151) (xy 160.63293 143.3997)
			(xy 160.63293 143.4079) (xy 160.63293 143.41609) (xy 160.63293 143.42429) (xy 160.63293 143.43248)
			(xy 160.63293 143.44067) (xy 160.63293 143.44887) (xy 160.63293 143.45706) (xy 160.63293 143.46526)
			(xy 160.63293 143.47345) (xy 160.63293 143.48165) (xy 160.63293 143.48984) (xy 160.63293 143.49803)
			(xy 160.63293 143.50623) (xy 160.63293 143.51443) (xy 160.63293 143.52262) (xy 160.63293 143.53082)
			(xy 160.63293 143.53901) (xy 160.63293 143.5472) (xy 160.63293 143.5554) (xy 160.64113 143.5554)
			(xy 160.64113 143.56359) (xy 160.64932 143.56359) (xy 160.64932 143.57179) (xy 160.65751 143.57179)
			(xy 160.65751 143.57998) (xy 161.82933 143.57998) (xy 161.82933 143.57179) (xy 161.86211 143.57179)
			(xy 161.86211 143.56359) (xy 161.87849 143.56359) (xy 161.87849 143.5554) (xy 161.88669 143.5554)
			(xy 161.88669 143.5472) (xy 161.89488 143.5472) (xy 161.89488 143.53901) (xy 161.90308 143.53901)
			(xy 161.90308 143.53082) (xy 161.91127 143.53082) (xy 161.91127 143.52262) (xy 161.91947 143.52262)
			(xy 161.91947 143.51443) (xy 161.92766 143.51443) (xy 161.92766 143.50623) (xy 161.93586 143.50623)
			(xy 161.93586 143.49803) (xy 161.94405 143.49803) (xy 161.94405 143.48984) (xy 161.95224 143.48984)
			(xy 161.95224 143.48165) (xy 161.96044 143.48165) (xy 161.96044 143.47345) (xy 161.96863 143.47345)
			(xy 161.96863 143.46526) (xy 161.97683 143.46526) (xy 161.97683 143.45706) (xy 161.98502 143.45706)
			(xy 161.98502 143.44887) (xy 161.99322 143.44887) (xy 161.99322 143.44067) (xy 162.00141 143.44067)
			(xy 162.00141 143.43248) (xy 162.0096 143.43248) (xy 162.0096 143.42429) (xy 162.0178 143.42429)
			(xy 162.0178 143.41609) (xy 162.026 143.41609) (xy 162.026 143.4079) (xy 162.03419 143.4079) (xy 162.03419 143.3997)
			(xy 162.04238 143.3997) (xy 162.04238 143.39151) (xy 162.05058 143.39151) (xy 162.05058 143.38331)
			(xy 162.05877 143.38331) (xy 162.05877 143.37512) (xy 162.06697 143.37512) (xy 162.06697 143.36692)
			(xy 162.07516 143.36692) (xy 162.07516 143.35873) (xy 162.08336 143.35873) (xy 162.08336 143.35054)
			(xy 162.09155 143.35054) (xy 162.09155 143.34234) (xy 162.09975 143.34234) (xy 162.09975 143.33415)
			(xy 162.10794 143.33415) (xy 162.10794 143.32595) (xy 162.11613 143.32595) (xy 162.11613 143.31776)
			(xy 162.11613 143.30956) (xy 162.11613 143.30137) (xy 162.12433 143.30137) (xy 162.12433 143.29317)
			(xy 162.12433 143.28498) (xy 162.12433 143.27679) (xy 162.12433 143.26859) (xy 162.13252 143.26859)
			(xy 162.13252 143.26039) (xy 162.13252 143.2522) (xy 162.13252 143.24401) (xy 162.13252 143.23581)
			(xy 162.13252 143.22762) (xy 162.13252 143.21942) (xy 162.13252 143.21123) (xy 162.13252 143.20303)
			(xy 162.13252 143.19484) (xy 162.13252 143.18664) (xy 162.13252 143.17845) (xy 162.13252 143.17026)
			(xy 162.13252 143.16206) (xy 162.13252 143.15387) (xy 162.13252 143.14567) (xy 162.13252 143.13748)
			(xy 162.13252 143.12928) (xy 162.13252 143.12109) (xy 162.13252 143.1129) (xy 162.13252 143.1047)
			(xy 162.13252 143.09651) (xy 162.13252 143.08831) (xy 162.13252 143.08012) (xy 162.13252 143.07192)
			(xy 162.13252 143.06373) (xy 162.13252 143.05553) (xy 162.13252 143.04734) (xy 162.13252 143.03915)
			(xy 162.13252 143.03095) (xy 162.13252 143.02275) (xy 162.13252 143.01456) (xy 162.13252 143.00637)
			(xy 162.13252 142.99817) (xy 162.13252 142.98998) (xy 162.13252 142.98178) (xy 162.13252 142.97359)
			(xy 162.13252 142.96539) (xy 162.13252 142.9572) (xy 162.13252 142.949) (xy 162.13252 142.94081)
			(xy 162.13252 142.93262) (xy 162.13252 142.92442) (xy 162.13252 142.91623) (xy 162.13252 142.90803)
			(xy 162.13252 142.89984) (xy 162.13252 142.89164) (xy 162.13252 142.88345) (xy 162.13252 142.87525)
			(xy 162.13252 142.86706) (xy 162.13252 142.85887) (xy 162.13252 142.85067) (xy 162.13252 142.84248)
			(xy 162.13252 142.83428) (xy 162.13252 142.82609) (xy 162.13252 142.81789) (xy 162.13252 142.8097)
			(xy 162.13252 142.8015) (xy 162.13252 142.79331) (xy 162.13252 142.78511) (xy 162.13252 142.77692)
			(xy 162.13252 142.76873) (xy 162.13252 142.76053) (xy 162.13252 142.75234) (xy 162.13252 142.74414)
			(xy 162.13252 142.73595) (xy 162.13252 142.72775) (xy 162.13252 142.71956) (xy 162.13252 142.71136)
			(xy 162.13252 142.70317) (xy 162.13252 142.69498) (xy 162.13252 142.68678) (xy 162.13252 142.67859)
			(xy 162.13252 142.67039) (xy 162.13252 142.6622) (xy 162.13252 142.654) (xy 162.13252 142.64581)
			(xy 162.13252 142.63761) (xy 162.13252 142.62942) (xy 162.13252 142.62123) (xy 162.13252 142.61303)
			(xy 162.13252 142.60484) (xy 162.13252 142.59664) (xy 162.13252 142.58845) (xy 162.13252 142.58025)
			(xy 162.13252 142.57206) (xy 162.13252 142.56387) (xy 162.13252 142.55567) (xy 162.13252 142.54747)
			(xy 162.13252 142.53928) (xy 162.13252 142.53108) (xy 162.13252 142.52289) (xy 162.13252 142.5147)
			(xy 162.13252 142.5065) (xy 162.13252 142.49831) (xy 162.13252 142.49011) (xy 162.13252 142.48192)
			(xy 162.13252 142.47372) (xy 162.13252 142.46553) (xy 162.13252 142.45734) (xy 162.13252 142.44914)
			(xy 162.13252 142.44095) (xy 162.13252 142.43275) (xy 162.13252 142.42456) (xy 162.13252 142.41636)
			(xy 162.13252 142.40817) (xy 162.13252 142.39997) (xy 162.13252 142.39178) (xy 162.13252 142.38359)
			(xy 162.13252 142.37539) (xy 162.13252 142.3672) (xy 162.13252 142.359) (xy 162.13252 142.35081)
			(xy 162.13252 142.34261) (xy 162.13252 142.33442) (xy 162.13252 142.32622) (xy 162.13252 142.31803)
			(xy 162.13252 142.30984) (xy 162.13252 142.30164) (xy 162.13252 142.29344) (xy 162.13252 142.28525)
			(xy 162.13252 142.27706) (xy 162.13252 142.26886) (xy 162.13252 142.26067) (xy 162.13252 142.25247)
			(xy 162.13252 142.24428) (xy 162.13252 142.23608) (xy 162.13252 142.22789) (xy 162.13252 142.21969)
			(xy 162.13252 142.2115) (xy 162.13252 142.20331) (xy 162.13252 142.19511) (xy 162.13252 142.18692)
			(xy 162.13252 142.17872) (xy 162.13252 142.17053) (xy 162.13252 142.16233) (xy 162.13252 142.15414)
			(xy 162.13252 142.14594) (xy 162.13252 142.13775) (xy 162.13252 142.12956) (xy 162.13252 142.12136)
			(xy 162.13252 142.11317) (xy 162.13252 142.10497) (xy 162.12433 142.10497) (xy 162.12433 142.09678)
			(xy 162.12433 142.08858) (xy 162.12433 142.08039) (xy 162.12433 142.07219) (xy 162.11613 142.07219)
			(xy 162.11613 142.064) (xy 162.11613 142.0558) (xy 162.10794 142.0558) (xy 162.10794 142.04761) (xy 162.09975 142.04761)
			(xy 162.09975 142.03942) (xy 162.09155 142.03942) (xy 162.09155 142.03122) (xy 162.08336 142.03122)
			(xy 162.08336 142.02303) (xy 162.07516 142.02303) (xy 162.07516 142.01483) (xy 162.06697 142.01483)
			(xy 162.06697 142.00664) (xy 162.05877 142.00664) (xy 162.05877 141.99844) (xy 162.05058 141.99844)
			(xy 162.05058 141.99025) (xy 162.04238 141.99025) (xy 162.04238 141.98205) (xy 162.03419 141.98205)
			(xy 162.03419 141.97386) (xy 162.026 141.97386) (xy 162.026 141.96567) (xy 162.0178 141.96567) (xy 162.0178 141.95747)
			(xy 162.0096 141.95747) (xy 162.0096 141.94927) (xy 162.00141 141.94927) (xy 162.00141 141.94108)
			(xy 161.99322 141.94108) (xy 161.99322 141.93289) (xy 161.98502 141.93289) (xy 161.98502 141.92469)
			(xy 161.97683 141.92469) (xy 161.97683 141.9165) (xy 161.96863 141.9165) (xy 161.96863 141.9083)
			(xy 161.96044 141.9083) (xy 161.96044 141.90011) (xy 161.95224 141.90011) (xy 161.95224 141.89192)
			(xy 161.94405 141.89192) (xy 161.94405 141.88372) (xy 161.93586 141.88372) (xy 161.93586 141.87553)
			(xy 161.92766 141.87553) (xy 161.92766 141.86733) (xy 161.91947 141.86733) (xy 161.91947 141.85914)
			(xy 161.91127 141.85914) (xy 161.91127 141.85094) (xy 161.90308 141.85094) (xy 161.90308 141.84275)
			(xy 161.89488 141.84275) (xy 161.89488 141.83456) (xy 161.88669 141.83456) (xy 161.88669 141.82636)
			(xy 161.87849 141.82636) (xy 161.87849 141.81816) (xy 161.8703 141.81816) (xy 161.8703 141.80997)
			(xy 161.84572 141.80997) (xy 161.84572 141.80177) (xy 161.80474 141.80177) (xy 161.80474 141.79358)
			(xy 160.6739 141.79358) (xy 160.6739 141.80177) (xy 160.65751 141.80177) (xy 160.65751 141.80997)
			(xy 160.64932 141.80997) (xy 160.64932 141.81816) (xy 160.64113 141.81816) (xy 160.64113 141.82636)
			(xy 160.63293 141.82636) (xy 160.14946 141.82636) (xy 160.14126 141.82636) (xy 160.14126 141.81816)
			(xy 160.12487 141.81816) (xy 160.12487 141.80997) (xy 160.10029 141.80997) (xy 160.10029 141.80177)
			(xy 160.05932 141.80177) (xy 160.05932 141.79358) (xy 158.92848 141.79358) (xy 158.92848 141.80177)
			(xy 158.91209 141.80177) (xy 158.91209 141.80997) (xy 158.90389 141.80997) (xy 158.90389 141.81816)
			(xy 158.8957 141.81816) (xy 158.8957 141.82636) (xy 158.8957 141.83456) (xy 158.8957 141.84275) (xy 158.88751 141.84275)
			(xy 158.49417 141.84275) (xy 158.48597 141.84275) (xy 158.48597 141.83456) (xy 158.47778 141.83456)
			(xy 158.47778 141.82636) (xy 158.46958 141.82636) (xy 158.46958 141.81816) (xy 158.4532 141.81816)
			(xy 158.4532 141.80997) (xy 158.43681 141.80997) (xy 158.43681 141.80177) (xy 158.40403 141.80177)
			(xy 158.40403 141.79358) (xy 158.2893 141.79358) (xy 158.2893 141.80177) (xy 158.28111 141.80177)
			(xy 158.28111 141.80997) (xy 158.27292 141.80997) (xy 158.27292 141.81816) (xy 158.26472 141.81816)
			(xy 158.26472 141.82636) (xy 158.25653 141.82636) (xy 158.25653 141.83456) (xy 158.24833 141.83456)
			(xy 158.24833 141.84275) (xy 158.24014 141.84275) (xy 158.24014 141.85094) (xy 158.23194 141.85094)
			(xy 158.23194 141.85914) (xy 158.22375 141.85914) (xy 158.22375 141.86733) (xy 158.21555 141.86733)
			(xy 158.21555 141.87553) (xy 158.20736 141.87553) (xy 158.20736 141.88372) (xy 158.19917 141.88372)
			(xy 158.19917 141.89192) (xy 158.19097 141.89192) (xy 158.19097 141.90011) (xy 158.18278 141.90011)
			(xy 158.18278 141.9083) (xy 158.17458 141.9083) (xy 158.17458 141.9165) (xy 158.16639 141.9165) (xy 158.16639 141.92469)
			(xy 158.1582 141.92469) (xy 158.1582 141.93289) (xy 158.15 141.93289) (xy 158.15 141.94108) (xy 158.1418 141.94108)
			(xy 158.1418 141.94927) (xy 158.13361 141.94927) (xy 158.13361 141.95747) (xy 158.12542 141.95747)
			(xy 158.12542 141.96567) (xy 158.11722 141.96567) (xy 158.11722 141.97386) (xy 158.10903 141.97386)
			(xy 158.10903 141.98205) (xy 158.10083 141.98205) (xy 158.10083 141.99025) (xy 158.09264 141.99025)
			(xy 158.09264 141.99844) (xy 158.08444 141.99844) (xy 158.08444 142.00664) (xy 158.07625 142.00664)
			(xy 158.07625 142.01483) (xy 158.06805 142.01483) (xy 158.06805 142.02303) (xy 158.05986 142.02303)
			(xy 158.05986 142.03122) (xy 158.05167 142.03122) (xy 158.05167 142.03942) (xy 158.04347 142.03942)
			(xy 158.04347 142.04761) (xy 158.03528 142.04761) (xy 158.03528 142.0558) (xy 158.02708 142.0558)
			(xy 158.02708 142.064) (xy 158.01889 142.064) (xy 158.01889 142.07219) (xy 158.01069 142.07219) (xy 158.01069 142.08039)
			(xy 158.0025 142.08039) (xy 158.0025 142.08858) (xy 157.9943 142.08858) (xy 157.9943 142.09678) (xy 157.98611 142.09678)
			(xy 157.98611 142.10497) (xy 157.97791 142.10497) (xy 157.97791 142.11317) (xy 157.96972 142.11317)
			(xy 157.96972 142.12136) (xy 157.96153 142.12136) (xy 157.96153 142.12956) (xy 157.95333 142.12956)
			(xy 157.95333 142.13775) (xy 157.94514 142.13775) (xy 157.94514 142.14594) (xy 157.93694 142.14594)
			(xy 157.93694 142.15414) (xy 157.92875 142.15414) (xy 157.92875 142.16233) (xy 157.92055 142.16233)
			(xy 157.92055 142.17053) (xy 157.91236 142.17053) (xy 157.91236 142.17872) (xy 157.90416 142.17872)
			(xy 157.90416 142.18692) (xy 157.89597 142.18692) (xy 157.89597 142.19511) (xy 158.26472 142.19511)
			(xy 158.26472 142.20331) (xy 158.26472 142.2115) (xy 158.26472 142.21969) (xy 158.26472 142.22789)
			(xy 158.26472 142.23608) (xy 158.26472 142.24428) (xy 158.26472 142.25247) (xy 158.26472 142.26067)
			(xy 158.26472 142.26886) (xy 158.26472 142.27706) (xy 158.26472 142.28525) (xy 158.26472 142.29344)
			(xy 158.26472 142.30164) (xy 158.26472 142.30984) (xy 158.26472 142.31803) (xy 158.26472 142.32622)
			(xy 158.26472 142.33442) (xy 158.26472 142.34261) (xy 158.26472 142.35081) (xy 158.26472 142.359)
			(xy 158.26472 142.3672) (xy 158.26472 142.37539) (xy 158.26472 142.38359) (xy 158.26472 142.39178)
			(xy 158.26472 142.39997) (xy 158.26472 142.40817) (xy 158.26472 142.41636) (xy 158.26472 142.42456)
			(xy 158.26472 142.43275) (xy 158.26472 142.44095) (xy 158.26472 142.44914) (xy 158.26472 142.45734)
			(xy 158.26472 142.46553) (xy 158.26472 142.47372) (xy 158.26472 142.48192) (xy 158.26472 142.49011)
			(xy 158.26472 142.49831) (xy 158.26472 142.5065) (xy 158.26472 142.5147) (xy 158.26472 142.52289)
			(xy 158.26472 142.53108) (xy 158.26472 142.53928) (xy 158.26472 142.54747) (xy 158.26472 142.55567)
			(xy 158.26472 142.56387) (xy 158.26472 142.57206) (xy 158.26472 142.58025) (xy 158.26472 142.58845)
			(xy 158.26472 142.59664) (xy 158.26472 142.60484) (xy 158.26472 142.61303) (xy 158.26472 142.62123)
			(xy 158.26472 142.62942) (xy 158.26472 142.63761) (xy 158.26472 142.64581) (xy 157.66652 142.64581)
			(xy 157.66652 142.63761) (xy 157.66652 142.62942) (xy 157.66652 142.62123) (xy 157.66652 142.61303)
			(xy 157.66652 142.60484) (xy 157.66652 142.59664) (xy 157.66652 142.58845) (xy 157.66652 142.58025)
			(xy 157.66652 142.57206) (xy 157.66652 142.56387) (xy 157.66652 142.55567) (xy 157.66652 142.54747)
			(xy 157.66652 142.53928) (xy 157.66652 142.53108) (xy 157.66652 142.52289) (xy 157.66652 142.5147)
			(xy 157.66652 142.5065) (xy 157.66652 142.49831) (xy 157.66652 142.49011) (xy 157.66652 142.48192)
			(xy 157.66652 142.47372) (xy 157.66652 142.46553) (xy 157.65833 142.46553) (xy 157.65833 142.47372)
			(xy 157.65013 142.47372) (xy 157.65013 142.48192) (xy 157.64194 142.48192) (xy 157.64194 142.49011)
			(xy 157.63375 142.49011) (xy 157.63375 142.49831) (xy 157.62555 142.49831) (xy 157.62555 142.5065)
			(xy 157.61736 142.5065) (xy 157.61736 142.5147) (xy 157.60916 142.5147) (xy 157.60916 142.52289)
			(xy 157.60097 142.52289) (xy 157.60097 142.53108) (xy 157.59277 142.53108) (xy 157.59277 142.53928)
			(xy 157.58458 142.53928) (xy 157.58458 142.54747) (xy 157.57639 142.54747) (xy 157.57639 142.55567)
			(xy 157.56819 142.55567) (xy 157.56819 142.56387) (xy 157.55999 142.56387) (xy 157.55999 142.57206)
			(xy 157.5518 142.57206) (xy 157.5518 142.58025) (xy 157.54361 142.58025) (xy 157.54361 142.58845)
			(xy 157.53541 142.58845) (xy 157.53541 142.59664) (xy 157.52722 142.59664) (xy 157.52722 142.60484)
			(xy 157.51902 142.60484) (xy 157.51902 142.61303) (xy 157.51083 142.61303) (xy 157.51083 142.62123)
			(xy 157.50263 142.62123) (xy 157.50263 142.62942) (xy 157.49444 142.62942) (xy 157.49444 142.63761)
			(xy 157.48624 142.63761) (xy 157.48624 142.64581) (xy 157.47805 142.64581) (xy 157.47805 142.654)
			(xy 157.46986 142.654) (xy 157.46986 142.6622) (xy 157.46166 142.6622) (xy 157.46166 142.67039) (xy 157.45347 142.67039)
			(xy 157.45347 142.67859) (xy 157.44527 142.67859) (xy 157.44527 142.68678) (xy 157.43708 142.68678)
			(xy 157.43708 142.69498) (xy 157.42888 142.69498) (xy 157.42888 142.70317) (xy 157.42069 142.70317)
			(xy 157.42069 142.71136) (xy 157.41249 142.71136) (xy 157.41249 142.71956) (xy 157.4043 142.71956)
			(xy 157.4043 142.72775) (xy 157.39611 142.72775) (xy 157.39611 142.73595) (xy 157.38791 142.73595)
			(xy 157.38791 142.74414) (xy 157.37972 142.74414) (xy 157.37972 142.75234) (xy 157.37152 142.75234)
			(xy 157.37152 142.76053) (xy 157.36333 142.76053) (xy 157.36333 142.76873) (xy 157.35513 142.76873)
			(xy 157.35513 142.77692) (xy 157.34694 142.77692) (xy 157.34694 142.78511) (xy 157.33875 142.78511)
			(xy 157.33875 142.79331) (xy 157.33055 142.79331) (xy 157.33055 142.8015) (xy 157.32235 142.8015)
			(xy 157.32235 142.8097) (xy 157.31416 142.8097) (xy 157.31416 142.81789) (xy 157.30597 142.81789)
			(xy 157.30597 142.82609) (xy 157.29777 142.82609) (xy 157.29777 142.83428) (xy 157.28958 142.83428)
			(xy 157.28958 142.84248) (xy 157.28138 142.84248) (xy 157.28138 142.85067) (xy 157.26499 142.85067)
			(xy 157.26499 142.85887) (xy 157.2568 142.85887) (xy 157.2568 142.86706) (xy 157.2486 142.86706)
			(xy 157.2486 142.87525) (xy 157.24041 142.87525) (xy 157.24041 142.88345) (xy 157.23222 142.88345)
			(xy 157.23222 142.89164) (xy 157.22402 142.89164) (xy 157.22402 142.89984) (xy 157.21583 142.89984)
			(xy 157.00277 142.89984) (xy 157.00277 142.89164) (xy 157.01097 142.89164) (xy 157.01097 142.88345)
			(xy 157.01916 142.88345) (xy 157.01916 142.87525) (xy 157.02735 142.87525) (xy 157.02735 142.86706)
			(xy 157.03555 142.86706) (xy 157.03555 142.85887) (xy 157.04374 142.85887) (xy 157.04374 142.85067)
			(xy 157.05194 142.85067) (xy 157.05194 142.84248) (xy 157.06013 142.84248) (xy 157.06013 142.83428)
			(xy 157.06832 142.83428) (xy 157.06832 142.82609) (xy 157.07652 142.82609) (xy 157.07652 142.81789)
			(xy 157.08471 142.81789) (xy 157.08471 142.8097) (xy 157.09291 142.8097) (xy 157.09291 142.8015)
			(xy 157.1011 142.8015) (xy 157.1011 142.79331) (xy 157.1093 142.79331) (xy 157.1093 142.78511) (xy 157.11749 142.78511)
			(xy 157.11749 142.77692) (xy 157.12569 142.77692) (xy 157.12569 142.76873) (xy 157.14208 142.76873)
			(xy 157.14208 142.76053) (xy 157.15027 142.76053) (xy 157.15027 142.75234) (xy 157.15847 142.75234)
			(xy 157.15847 142.74414) (xy 157.16666 142.74414) (xy 157.16666 142.73595) (xy 157.17485 142.73595)
			(xy 157.17485 142.72775) (xy 157.18305 142.72775) (xy 157.18305 142.71956) (xy 157.19124 142.71956)
			(xy 157.19124 142.71136) (xy 157.19944 142.71136) (xy 157.19944 142.70317) (xy 157.20763 142.70317)
			(xy 157.20763 142.69498) (xy 157.21583 142.69498) (xy 157.21583 142.68678) (xy 157.22402 142.68678)
			(xy 157.22402 142.67859) (xy 157.23222 142.67859) (xy 157.23222 142.67039) (xy 157.24041 142.67039)
			(xy 157.24041 142.6622) (xy 157.2486 142.6622) (xy 157.2486 142.654) (xy 157.2568 142.654) (xy 157.2568 142.64581)
			(xy 157.26499 142.64581) (xy 157.26499 142.63761) (xy 157.27319 142.63761) (xy 157.27319 142.62942)
			(xy 157.28138 142.62942) (xy 157.28138 142.62123) (xy 157.28958 142.62123) (xy 157.28958 142.61303)
			(xy 157.29777 142.61303) (xy 157.29777 142.60484) (xy 157.30597 142.60484) (xy 157.30597 142.59664)
			(xy 157.31416 142.59664) (xy 157.31416 142.58845) (xy 157.32235 142.58845) (xy 157.32235 142.58025)
			(xy 157.33055 142.58025) (xy 157.33055 142.57206) (xy 157.33875 142.57206) (xy 157.33875 142.56387)
			(xy 157.34694 142.56387) (xy 157.34694 142.55567) (xy 157.35513 142.55567) (xy 157.35513 142.54747)
			(xy 157.36333 142.54747) (xy 157.36333 142.53928) (xy 157.37152 142.53928) (xy 157.37152 142.53108)
			(xy 157.37972 142.53108) (xy 157.37972 142.52289) (xy 157.38791 142.52289) (xy 157.38791 142.5147)
			(xy 157.39611 142.5147) (xy 157.39611 142.5065) (xy 157.4043 142.5065) (xy 157.4043 142.49831) (xy 157.41249 142.49831)
			(xy 157.41249 142.49011) (xy 157.42069 142.49011) (xy 157.42069 142.48192) (xy 157.42888 142.48192)
			(xy 157.42888 142.47372) (xy 157.43708 142.47372) (xy 157.43708 142.46553) (xy 157.44527 142.46553)
			(xy 157.44527 142.45734) (xy 157.45347 142.45734) (xy 157.45347 142.44914) (xy 157.46166 142.44914)
			(xy 157.46166 142.44095) (xy 157.46986 142.44095) (xy 157.46986 142.43275) (xy 157.47805 142.43275)
			(xy 157.47805 142.42456) (xy 157.48624 142.42456) (xy 157.48624 142.41636) (xy 157.49444 142.41636)
			(xy 157.49444 142.40817) (xy 157.50263 142.40817) (xy 157.50263 142.39997) (xy 157.51083 142.39997)
			(xy 157.51083 142.39178) (xy 157.51902 142.39178) (xy 157.51902 142.38359) (xy 157.52722 142.38359)
			(xy 157.52722 142.37539) (xy 157.53541 142.37539) (xy 157.53541 142.3672) (xy 157.54361 142.3672)
			(xy 157.54361 142.359) (xy 157.5518 142.359) (xy 157.5518 142.35081) (xy 157.55999 142.35081) (xy 157.55999 142.34261)
			(xy 157.56819 142.34261) (xy 157.56819 142.33442) (xy 157.57639 142.33442) (xy 157.57639 142.32622)
			(xy 157.58458 142.32622) (xy 157.58458 142.31803) (xy 157.59277 142.31803) (xy 157.59277 142.30984)
			(xy 157.60097 142.30984) (xy 157.60097 142.30164) (xy 157.60916 142.30164) (xy 157.60916 142.29344)
			(xy 157.61736 142.29344) (xy 157.61736 142.28525) (xy 157.62555 142.28525) (xy 157.62555 142.27706)
			(xy 157.63375 142.27706) (xy 157.63375 142.26886) (xy 157.64194 142.26886) (xy 157.64194 142.26067)
			(xy 157.65013 142.26067) (xy 157.65013 142.25247) (xy 157.65833 142.25247) (xy 157.65833 142.24428)
			(xy 157.66652 142.24428) (xy 157.66652 142.23608) (xy 157.67472 142.23608) (xy 157.67472 142.22789)
			(xy 157.68291 142.22789) (xy 157.68291 142.21969) (xy 157.69111 142.21969) (xy 157.69111 142.2115)
			(xy 157.6993 142.2115) (xy 157.6993 142.20331) (xy 157.7075 142.20331) (xy 157.7075 142.19511) (xy 157.71569 142.19511)
			(xy 157.71569 142.18692) (xy 157.72389 142.18692) (xy 157.72389 142.17872) (xy 157.73208 142.17872)
			(xy 157.73208 142.17053) (xy 157.74028 142.17053) (xy 157.74028 142.16233) (xy 157.74847 142.16233)
			(xy 157.74847 142.15414) (xy 157.75666 142.15414) (xy 157.75666 142.14594) (xy 157.76486 142.14594)
			(xy 157.76486 142.13775) (xy 157.77305 142.13775) (xy 157.77305 142.12956) (xy 157.78125 142.12956)
			(xy 157.78125 142.12136) (xy 157.78944 142.12136) (xy 157.78944 142.11317) (xy 157.79763 142.11317)
			(xy 157.79763 142.10497) (xy 157.80583 142.10497) (xy 157.80583 142.09678) (xy 157.81403 142.09678)
			(xy 157.81403 142.08858) (xy 157.82222 142.08858) (xy 157.82222 142.08039) (xy 157.83861 142.08039)
			(xy 157.83861 142.07219) (xy 157.8468 142.07219) (xy 157.8468 142.064) (xy 157.855 142.064) (xy 157.855 142.0558)
			(xy 157.86319 142.0558) (xy 157.86319 142.04761) (xy 157.87139 142.04761) (xy 157.87139 142.03942)
			(xy 157.87958 142.03942) (xy 157.87958 142.03122) (xy 157.88778 142.03122) (xy 157.88778 142.02303)
			(xy 157.89597 142.02303) (xy 157.89597 142.01483) (xy 157.90416 142.01483) (xy 157.90416 142.00664)
			(xy 157.91236 142.00664) (xy 157.91236 141.99844) (xy 157.92055 141.99844) (xy 157.92055 141.99025)
			(xy 157.92875 141.99025) (xy 157.92875 141.98205) (xy 157.93694 141.98205) (xy 157.93694 141.97386)
			(xy 157.94514 141.97386) (xy 157.94514 141.96567) (xy 157.95333 141.96567) (xy 157.95333 141.95747)
			(xy 157.96153 141.95747) (xy 157.96153 141.94927) (xy 157.96972 141.94927) (xy 157.96972 141.94108)
			(xy 157.97791 141.94108) (xy 157.97791 141.93289) (xy 157.98611 141.93289) (xy 157.98611 141.92469)
			(xy 157.9943 141.92469) (xy 157.9943 141.9165) (xy 158.0025 141.9165) (xy 158.0025 141.9083) (xy 158.01069 141.9083)
			(xy 158.01069 141.90011) (xy 158.01889 141.90011) (xy 158.01889 141.89192) (xy 158.02708 141.89192)
			(xy 158.02708 141.88372) (xy 158.03528 141.88372) (xy 158.03528 141.87553) (xy 158.04347 141.87553)
			(xy 158.04347 141.86733) (xy 158.05167 141.86733) (xy 158.05167 141.85914) (xy 158.05986 141.85914)
			(xy 158.05986 141.85094) (xy 158.06805 141.85094) (xy 158.06805 141.84275) (xy 158.07625 141.84275)
			(xy 158.07625 141.83456) (xy 158.08444 141.83456) (xy 158.08444 141.82636) (xy 158.08444 141.81816)
			(xy 158.09264 141.81816) (xy 158.09264 141.80997) (xy 158.10083 141.80997) (xy 158.10083 141.80177)
			(xy 158.10083 141.79358) (xy 158.10903 141.79358) (xy 158.10903 141.78539) (xy 158.10903 141.77719)
			(xy 158.11722 141.77719) (xy 158.11722 141.769) (xy 158.11722 141.7608) (xy 158.12542 141.7608) (xy 158.12542 141.75261)
			(xy 158.12542 141.74441) (xy 158.12542 141.73622) (xy 158.12542 141.72803) (xy 158.13361 141.72803)
			(xy 158.13361 141.71983) (xy 158.13361 141.71164) (xy 158.13361 141.70344) (xy 158.13361 141.69525)
			(xy 158.13361 141.68705) (xy 158.13361 141.67886) (xy 158.13361 141.67066) (xy 158.13361 141.66247)
			(xy 158.13361 141.65427) (xy 158.13361 141.64608) (xy 158.13361 141.63789) (xy 158.13361 141.62969)
			(xy 158.13361 141.6215) (xy 158.13361 141.6133) (xy 158.13361 141.60511) (xy 158.13361 141.59692)
			(xy 158.13361 141.58872) (xy 158.13361 141.58052) (xy 158.13361 141.57233) (xy 158.13361 141.56413)
			(xy 158.13361 141.55594) (xy 158.13361 141.54775) (xy 158.13361 141.53955) (xy 158.13361 141.53136)
			(xy 158.13361 141.52316) (xy 158.13361 141.51497) (xy 158.13361 141.50677) (xy 158.13361 141.49858)
			(xy 158.13361 141.49039) (xy 158.13361 141.48219) (xy 158.13361 141.474) (xy 158.13361 141.4658)
			(xy 158.13361 141.45761) (xy 158.13361 141.44941) (xy 158.13361 141.44122) (xy 158.13361 141.43302)
			(xy 158.13361 141.42483) (xy 158.13361 141.41663) (xy 158.13361 141.40844) (xy 158.13361 141.40025)
			(xy 158.13361 141.39205) (xy 158.13361 141.38386) (xy 158.13361 141.37566) (xy 158.13361 141.36747)
			(xy 158.13361 141.35927) (xy 158.13361 141.35108) (xy 158.13361 141.34289) (xy 158.13361 141.33469)
			(xy 158.13361 141.32649) (xy 158.13361 141.3183) (xy 158.13361 141.31011) (xy 158.13361 141.30191)
			(xy 158.13361 141.29372) (xy 158.13361 141.28552) (xy 158.13361 141.27733) (xy 158.13361 141.26913)
			(xy 158.13361 141.26094) (xy 158.13361 141.25274) (xy 158.13361 141.24455) (xy 158.13361 141.23636)
			(xy 158.13361 141.22816) (xy 158.13361 141.21997) (xy 158.13361 141.21177) (xy 158.13361 141.20358)
			(xy 158.13361 141.19538) (xy 158.13361 141.18719) (xy 158.13361 141.179) (xy 158.13361 141.1708)
			(xy 158.13361 141.16261) (xy 158.13361 141.15441) (xy 158.13361 141.14622) (xy 158.13361 141.13802)
			(xy 158.13361 141.12983) (xy 158.13361 141.12163) (xy 158.13361 141.11344) (xy 158.13361 141.10525)
			(xy 158.13361 141.09705) (xy 158.13361 141.08885) (xy 158.13361 141.08066) (xy 158.13361 141.07247)
			(xy 158.13361 141.06427) (xy 158.13361 141.05608) (xy 158.13361 141.04788) (xy 158.13361 141.03969)
			(xy 158.13361 141.03149) (xy 158.13361 141.0233) (xy 158.13361 141.0151) (xy 158.13361 141.00691)
			(xy 158.13361 140.99872) (xy 158.13361 140.99052) (xy 158.13361 140.98233) (xy 158.13361 140.97413)
			(xy 158.13361 140.96594) (xy 158.13361 140.95774) (xy 158.13361 140.94955) (xy 158.13361 140.94135)
			(xy 158.13361 140.93316) (xy 158.13361 140.92496) (xy 158.13361 140.91677) (xy 158.13361 140.90858)
			(xy 158.13361 140.90038) (xy 158.13361 140.89219) (xy 158.13361 140.88399) (xy 158.13361 140.8758)
			(xy 158.13361 140.86761) (xy 158.13361 140.85941) (xy 158.13361 140.85121) (xy 158.13361 140.84302)
			(xy 158.13361 140.83482) (xy 158.13361 140.82663) (xy 158.13361 140.81844) (xy 158.13361 140.81024)
			(xy 158.13361 140.80205) (xy 158.13361 140.79385) (xy 158.13361 140.78566) (xy 158.13361 140.77746)
			(xy 158.13361 140.76927) (xy 158.13361 140.76108) (xy 158.13361 140.75288) (xy 158.13361 140.74469)
			(xy 158.13361 140.73649) (xy 158.13361 140.7283) (xy 158.13361 140.7201) (xy 158.13361 140.71191)
			(xy 158.13361 140.70371) (xy 158.13361 140.69552) (xy 158.13361 140.68732) (xy 158.13361 140.67913)
			(xy 158.13361 140.67094) (xy 158.13361 140.66274) (xy 158.13361 140.65455) (xy 158.13361 140.64635)
			(xy 158.13361 140.63816) (xy 158.13361 140.62996) (xy 158.13361 140.62177) (xy 158.13361 140.61357)
			(xy 158.13361 140.60538) (xy 158.13361 140.59718) (xy 158.13361 140.58899) (xy 158.13361 140.5808)
			(xy 158.13361 140.5726) (xy 158.13361 140.56441) (xy 158.13361 140.55621) (xy 158.13361 140.54802)
			(xy 158.13361 140.53982) (xy 158.13361 140.53163) (xy 158.13361 140.52344) (xy 158.13361 140.51524)
			(xy 158.13361 140.50704) (xy 158.13361 140.49885) (xy 158.13361 140.49066) (xy 158.13361 140.48246)
			(xy 158.13361 140.47427) (xy 158.13361 140.46607) (xy 158.13361 140.45788) (xy 158.13361 140.44969)
			(xy 158.13361 140.44149) (xy 158.13361 140.4333) (xy 158.13361 140.4251) (xy 158.13361 140.41691)
			(xy 158.13361 140.40871) (xy 158.13361 140.40052) (xy 158.13361 140.39232) (xy 158.13361 140.38413)
			(xy 158.13361 140.37593) (xy 158.13361 140.36774) (xy 158.13361 140.35954) (xy 158.13361 140.35135)
			(xy 158.13361 140.34316) (xy 158.13361 140.33496) (xy 158.13361 140.32677) (xy 158.13361 140.31857)
			(xy 158.13361 140.31038) (xy 158.13361 140.30218) (xy 158.13361 140.29399) (xy 158.13361 140.28579)
			(xy 158.13361 140.2776) (xy 158.13361 140.2694) (xy 158.13361 140.26121) (xy 158.13361 140.25302)
			(xy 158.13361 140.24482) (xy 158.13361 140.23663) (xy 158.13361 140.22843) (xy 158.13361 140.22024)
			(xy 158.13361 140.21204) (xy 158.13361 140.20385) (xy 158.13361 140.19565) (xy 158.13361 140.18746)
			(xy 158.33028 140.18746) (xy 158.33028 140.19565) (xy 158.33028 140.20385) (xy 158.33028 140.21204)
			(xy 158.33028 140.22024) (xy 158.33028 140.22843) (xy 158.33028 140.23663) (xy 158.33028 140.24482)
			(xy 158.33028 140.25302) (xy 158.33028 140.26121) (xy 158.33028 140.2694) (xy 158.33028 140.2776)
			(xy 158.33028 140.28579) (xy 158.33028 140.29399) (xy 158.33028 140.30218) (xy 158.33028 140.31038)
			(xy 158.33028 140.31857) (xy 158.33028 140.32677) (xy 158.33028 140.33496) (xy 158.33028 140.34316)
			(xy 158.33028 140.35135) (xy 158.33028 140.35954) (xy 158.33028 140.36774) (xy 158.33028 140.37593)
			(xy 158.33028 140.38413) (xy 158.33028 140.39232) (xy 158.33028 140.40052) (xy 158.33028 140.40871)
			(xy 158.33028 140.41691) (xy 158.33028 140.4251) (xy 158.33028 140.4333) (xy 158.33028 140.44149)
			(xy 158.33028 140.44969) (xy 158.33028 140.45788) (xy 158.33028 140.46607) (xy 158.33028 140.47427)
			(xy 158.33028 140.48246) (xy 158.33028 140.49066) (xy 158.33028 140.49885) (xy 158.33028 140.50704)
			(xy 158.33028 140.51524) (xy 158.33028 140.52344) (xy 158.33028 140.53163) (xy 158.33028 140.53982)
			(xy 158.33028 140.54802) (xy 158.33028 140.55621) (xy 158.33028 140.56441) (xy 158.33028 140.5726)
			(xy 158.33028 140.5808) (xy 158.33028 140.58899) (xy 158.33028 140.59718) (xy 158.33028 140.60538)
			(xy 158.33028 140.61357) (xy 158.33028 140.62177) (xy 158.33028 140.62996) (xy 158.33028 140.63816)
			(xy 158.33028 140.64635) (xy 158.33028 140.65455) (xy 158.33028 140.66274) (xy 158.33028 140.67094)
			(xy 158.33028 140.67913) (xy 158.33028 140.68732) (xy 158.33028 140.69552) (xy 158.33028 140.70371)
			(xy 158.33028 140.71191) (xy 158.33028 140.7201) (xy 158.33028 140.7283) (xy 158.33028 140.73649)
			(xy 158.33028 140.74469) (xy 158.33028 140.75288) (xy 158.33028 140.76108) (xy 158.33028 140.76927)
			(xy 158.33028 140.77746) (xy 158.33028 140.78566) (xy 158.33028 140.79385) (xy 158.33028 140.80205)
			(xy 158.33028 140.81024) (xy 158.33028 140.81844) (xy 158.33028 140.82663) (xy 158.33028 140.83482)
			(xy 158.33028 140.84302) (xy 158.33028 140.85121) (xy 158.33028 140.85941) (xy 158.33028 140.86761)
			(xy 158.33028 140.8758) (xy 158.33028 140.88399) (xy 158.33028 140.89219) (xy 158.33028 140.90038)
			(xy 158.33028 140.90858) (xy 158.33028 140.91677) (xy 158.33028 140.92496) (xy 158.33028 140.93316)
			(xy 158.33028 140.94135) (xy 158.33028 140.94955) (xy 158.33028 140.95774) (xy 158.33028 140.96594)
			(xy 158.33028 140.97413) (xy 158.33028 140.98233) (xy 158.33028 140.99052) (xy 158.33028 140.99872)
			(xy 158.33028 141.00691) (xy 158.33028 141.0151) (xy 158.33028 141.0233) (xy 158.33028 141.03149)
			(xy 158.33028 141.03969) (xy 158.33028 141.04788) (xy 158.33028 141.05608) (xy 158.33028 141.06427)
			(xy 158.33028 141.07247) (xy 158.33028 141.08066) (xy 158.33028 141.08885) (xy 158.33028 141.09705)
			(xy 158.33028 141.10525) (xy 158.33028 141.11344) (xy 158.33028 141.12163) (xy 158.33028 141.12983)
			(xy 158.33028 141.13802) (xy 158.33028 141.14622) (xy 158.33028 141.15441) (xy 158.33028 141.16261)
			(xy 158.33028 141.1708) (xy 158.33028 141.179) (xy 158.33028 141.18719) (xy 158.33028 141.19538)
			(xy 158.33028 141.20358) (xy 158.33028 141.21177) (xy 158.33028 141.21997) (xy 158.33028 141.22816)
			(xy 158.33028 141.23636) (xy 158.33028 141.24455) (xy 158.33028 141.25274) (xy 158.33028 141.26094)
			(xy 158.33028 141.26913) (xy 158.33028 141.27733) (xy 158.33028 141.28552) (xy 158.33028 141.29372)
			(xy 158.33028 141.30191) (xy 158.33028 141.31011) (xy 158.33028 141.3183) (xy 158.33028 141.32649)
			(xy 158.33847 141.32649) (xy 158.33847 141.33469) (xy 158.33847 141.34289) (xy 158.33847 141.35108)
			(xy 158.33847 141.35927) (xy 158.33847 141.36747) (xy 158.34667 141.36747) (xy 158.34667 141.37566)
			(xy 158.34667 141.38386) (xy 158.35486 141.38386) (xy 158.35486 141.39205) (xy 158.35486 141.40025)
			(xy 158.36306 141.40025) (xy 158.36306 141.40844) (xy 158.37125 141.40844) (xy 158.37125 141.41663)
			(xy 158.37944 141.41663) (xy 158.37944 141.42483) (xy 158.38764 141.42483) (xy 158.38764 141.43302)
			(xy 158.39584 141.43302) (xy 158.39584 141.44122) (xy 158.40403 141.44122) (xy 158.40403 141.44941)
			(xy 158.41222 141.44941) (xy 158.41222 141.45761) (xy 158.42042 141.45761) (xy 158.42042 141.4658)
			(xy 158.42861 141.4658) (xy 158.42861 141.474) (xy 158.43681 141.474) (xy 158.43681 141.48219) (xy 158.445 141.48219)
			(xy 158.445 141.49039) (xy 158.4532 141.49039) (xy 158.4532 141.49858) (xy 158.46139 141.49858) (xy 158.46139 141.50677)
			(xy 158.46958 141.50677) (xy 158.46958 141.51497) (xy 158.47778 141.51497) (xy 158.47778 141.52316)
			(xy 158.48597 141.52316) (xy 158.48597 141.53136) (xy 158.49417 141.53136) (xy 158.49417 141.53955)
			(xy 158.50236 141.53955) (xy 158.50236 141.54775) (xy 158.51055 141.54775) (xy 158.51055 141.55594)
			(xy 158.51875 141.55594) (xy 158.51875 141.56413) (xy 158.52694 141.56413) (xy 158.52694 141.57233)
			(xy 158.53514 141.57233) (xy 158.53514 141.58052) (xy 158.54334 141.58052) (xy 158.54334 141.58872)
			(xy 158.55153 141.58872) (xy 158.55153 141.59692) (xy 158.55972 141.59692) (xy 158.55972 141.60511)
			(xy 158.56792 141.60511) (xy 158.56792 141.6133) (xy 158.57611 141.6133) (xy 158.57611 141.6215)
			(xy 158.58431 141.6215) (xy 158.58431 141.62969) (xy 158.6007 141.62969) (xy 158.6007 141.63789)
			(xy 158.63347 141.63789) (xy 158.63347 141.64608) (xy 159.67417 141.64608) (xy 159.67417 141.63789)
			(xy 159.68237 141.63789) (xy 159.68237 141.62969) (xy 159.69056 141.62969) (xy 159.69056 141.6215)
			(xy 159.69056 141.6133) (xy 159.69876 141.6133) (xy 159.69876 141.60511) (xy 159.69876 141.59692)
			(xy 159.69876 141.58872) (xy 159.69876 141.58052) (xy 159.69876 141.57233) (xy 159.69876 141.56413)
			(xy 159.69876 141.55594) (xy 159.69876 141.54775) (xy 159.69876 141.53955) (xy 159.69876 141.53136)
			(xy 159.69876 141.52316) (xy 159.69876 141.51497) (xy 159.69876 141.50677) (xy 159.69876 141.49858)
			(xy 159.69876 141.49039) (xy 159.69876 141.48219) (xy 159.69876 141.474) (xy 159.69876 141.4658)
			(xy 159.69876 141.45761) (xy 159.69876 141.44941) (xy 159.69876 141.44122) (xy 159.69876 141.43302)
			(xy 159.69876 141.42483) (xy 159.69876 141.41663) (xy 159.69876 141.40844) (xy 159.69876 141.40025)
			(xy 159.69876 141.39205) (xy 159.69876 141.38386) (xy 159.69876 141.37566) (xy 159.69876 141.36747)
			(xy 159.69876 141.35927) (xy 159.69876 141.35108) (xy 159.69876 141.34289) (xy 159.69876 141.33469)
			(xy 159.69876 141.32649) (xy 159.69876 141.3183) (xy 159.69876 141.31011) (xy 159.69876 141.30191)
			(xy 159.69876 141.29372) (xy 159.69876 141.28552) (xy 159.69876 141.27733) (xy 159.69876 141.26913)
			(xy 159.69876 141.26094) (xy 159.69056 141.26094) (xy 159.69056 141.25274) (xy 159.69056 141.24455)
			(xy 159.68237 141.24455) (xy 159.68237 141.23636) (xy 159.66598 141.23636) (xy 159.66598 141.22816)
			(xy 158.78917 141.22816) (xy 158.78917 141.21997) (xy 158.78098 141.21997) (xy 158.78098 141.21177)
			(xy 158.78098 141.20358) (xy 158.78098 141.19538) (xy 158.78098 141.18719) (xy 158.78098 141.179)
			(xy 158.78098 141.1708) (xy 158.78098 141.16261) (xy 158.78098 141.15441) (xy 158.78098 141.14622)
			(xy 158.78098 141.13802) (xy 158.78098 141.12983) (xy 158.78098 141.12163) (xy 158.78098 141.11344)
			(xy 158.78098 141.10525) (xy 158.78098 141.09705) (xy 158.78098 141.08885) (xy 158.78098 141.08066)
			(xy 158.78098 141.07247) (xy 158.78098 141.06427) (xy 158.78098 141.05608) (xy 158.78098 141.04788)
			(xy 158.78098 141.03969) (xy 158.78098 141.03149) (xy 158.78098 141.0233) (xy 158.78098 141.0151)
			(xy 158.78098 141.00691) (xy 158.78098 140.99872) (xy 158.78098 140.99052) (xy 158.78098 140.98233)
			(xy 158.78098 140.97413) (xy 158.78098 140.96594) (xy 158.78098 140.95774) (xy 158.78098 140.94955)
			(xy 158.78098 140.94135) (xy 158.78917 140.94135) (xy 158.78917 140.93316) (xy 159.54306 140.93316)
			(xy 159.54306 140.92496) (xy 159.55945 140.92496) (xy 159.55945 140.91677) (xy 159.55945 140.90858)
			(xy 159.56765 140.90858) (xy 159.56765 140.90038) (xy 159.56765 140.89219) (xy 159.56765 140.88399)
			(xy 159.56765 140.8758) (xy 159.56765 140.86761) (xy 159.56765 140.85941) (xy 159.56765 140.85121)
			(xy 159.56765 140.84302) (xy 159.56765 140.83482) (xy 159.56765 140.82663) (xy 159.56765 140.81844)
			(xy 159.56765 140.81024) (xy 159.56765 140.80205) (xy 159.56765 140.79385) (xy 159.56765 140.78566)
			(xy 159.56765 140.77746) (xy 159.56765 140.76927) (xy 159.56765 140.76108) (xy 159.56765 140.75288)
			(xy 159.56765 140.74469) (xy 159.56765 140.73649) (xy 159.56765 140.7283) (xy 159.56765 140.7201)
			(xy 159.56765 140.71191) (xy 159.56765 140.70371) (xy 159.56765 140.69552) (xy 159.56765 140.68732)
			(xy 159.56765 140.67913) (xy 159.56765 140.67094) (xy 159.56765 140.66274) (xy 159.56765 140.65455)
			(xy 159.56765 140.64635) (xy 159.56765 140.63816) (xy 159.56765 140.62996) (xy 159.56765 140.62177)
			(xy 159.56765 140.61357) (xy 159.56765 140.60538) (xy 159.55945 140.60538) (xy 159.55945 140.59718)
			(xy 159.55945 140.58899) (xy 159.54306 140.58899) (xy 159.54306 140.5808) (xy 158.78917 140.5808)
			(xy 158.78917 140.5726) (xy 158.78098 140.5726) (xy 158.78098 140.56441) (xy 158.78098 140.55621)
			(xy 158.78098 140.54802) (xy 158.78098 140.53982) (xy 158.78098 140.53163) (xy 158.78098 140.52344)
			(xy 158.78098 140.51524) (xy 158.78098 140.50704) (xy 158.78098 140.49885) (xy 158.78098 140.49066)
			(xy 158.78098 140.48246) (xy 158.78098 140.47427) (xy 158.78098 140.46607) (xy 158.78098 140.45788)
			(xy 158.78098 140.44969) (xy 158.78098 140.44149) (xy 158.78098 140.4333) (xy 158.78098 140.4251)
			(xy 158.78098 140.41691) (xy 158.78098 140.40871) (xy 158.78098 140.40052) (xy 158.78098 140.39232)
			(xy 158.78098 140.38413) (xy 158.78098 140.37593) (xy 158.78098 140.36774) (xy 158.78098 140.35954)
			(xy 158.78098 140.35135) (xy 158.78098 140.34316) (xy 158.78098 140.33496) (xy 158.78098 140.32677)
			(xy 158.78098 140.31857) (xy 158.78098 140.31038) (xy 158.78098 140.30218) (xy 158.78098 140.29399)
			(xy 158.78098 140.28579) (xy 158.78917 140.28579) (xy 158.78917 140.2776) (xy 159.67417 140.2776)
			(xy 159.67417 140.2694) (xy 159.68237 140.2694) (xy 159.68237 140.26121) (xy 159.69056 140.26121)
			(xy 159.69056 140.25302) (xy 159.69876 140.25302) (xy 159.69876 140.24482) (xy 159.69876 140.23663)
			(xy 159.69876 140.22843) (xy 159.69876 140.22024) (xy 159.69876 140.21204) (xy 159.69876 140.20385)
			(xy 159.69876 140.19565) (xy 159.69876 140.18746) (xy 159.69876 140.17927) (xy 159.69876 140.17107)
			(xy 159.69876 140.16288) (xy 159.69876 140.15468) (xy 159.69876 140.14649) (xy 159.69876 140.1383)
			(xy 159.69876 140.1301) (xy 159.69876 140.1219) (xy 159.69876 140.11371) (xy 159.69876 140.10552)
			(xy 159.69876 140.09732) (xy 159.69876 140.08913) (xy 159.69876 140.08093) (xy 159.69876 140.07274)
			(xy 159.69876 140.06454) (xy 159.69876 140.05635) (xy 159.69876 140.04815) (xy 159.69876 140.03996)
			(xy 159.69876 140.03176) (xy 159.69876 140.02357) (xy 159.69876 140.01538) (xy 159.69876 140.00718)
			(xy 159.69876 139.99899) (xy 159.69876 139.99079) (xy 159.69876 139.9826) (xy 159.69876 139.9744)
			(xy 159.69876 139.96621) (xy 159.69876 139.95802) (xy 159.69876 139.94982) (xy 159.69876 139.94163)
			(xy 159.69876 139.93343) (xy 159.69876 139.92524) (xy 159.69876 139.91704) (xy 159.69876 139.90885)
			(xy 159.69876 139.90065) (xy 159.69056 139.90065) (xy 159.69056 139.89246) (xy 159.69056 139.88426)
			(xy 159.68237 139.88426) (xy 159.68237 139.87607) (xy 159.67417 139.87607) (xy 159.67417 139.86787)
			(xy 159.65779 139.86787) (xy 159.65779 139.85968) (xy 159.6332 139.85968) (xy 159.6332 139.86787)
			(xy 159.62501 139.86787) (xy 159.62501 139.85968) (xy 158.66625 139.85968) (xy 158.66625 139.86787)
			(xy 158.62528 139.86787) (xy 158.62528 139.87607) (xy 158.6007 139.87607) (xy 158.6007 139.88426)
			(xy 158.58431 139.88426) (xy 158.58431 139.89246) (xy 158.57611 139.89246) (xy 158.57611 139.90065)
			(xy 158.56792 139.90065) (xy 158.56792 139.90885) (xy 158.55972 139.90885) (xy 158.55972 139.91704)
			(xy 158.55153 139.91704) (xy 158.55153 139.92524) (xy 158.54334 139.92524) (xy 158.54334 139.93343)
			(xy 158.53514 139.93343) (xy 158.53514 139.94163) (xy 158.52694 139.94163) (xy 158.52694 139.94982)
			(xy 158.51875 139.94982) (xy 158.51875 139.95802) (xy 158.51055 139.95802) (xy 158.51055 139.96621)
			(xy 158.50236 139.96621) (xy 158.50236 139.9744) (xy 158.49417 139.9744) (xy 158.49417 139.9826)
			(xy 158.48597 139.9826) (xy 158.48597 139.99079) (xy 158.47778 139.99079) (xy 158.47778 139.99899)
			(xy 158.46958 139.99899) (xy 158.46958 140.00718) (xy 158.46139 140.00718) (xy 158.46139 140.01538)
			(xy 158.4532 140.01538) (xy 158.4532 140.02357) (xy 158.445 140.02357) (xy 158.445 140.03176) (xy 158.43681 140.03176)
			(xy 158.43681 140.03996) (xy 158.42861 140.03996) (xy 158.42861 140.04815) (xy 158.42042 140.04815)
			(xy 158.42042 140.05635) (xy 158.41222 140.05635) (xy 158.41222 140.06454) (xy 158.40403 140.06454)
			(xy 158.40403 140.07274) (xy 158.39584 140.07274) (xy 158.39584 140.08093) (xy 158.38764 140.08093)
			(xy 158.38764 140.08913) (xy 158.37944 140.08913) (xy 158.37944 140.09732) (xy 158.37125 140.09732)
			(xy 158.37125 140.10552) (xy 158.36306 140.10552) (xy 158.36306 140.11371) (xy 158.35486 140.11371)
			(xy 158.35486 140.1219) (xy 158.34667 140.1219) (xy 158.34667 140.1301) (xy 158.34667 140.1383) (xy 158.34667 140.14649)
			(xy 158.33847 140.14649) (xy 158.33847 140.15468) (xy 158.33847 140.16288) (xy 158.33847 140.17107)
			(xy 158.33847 140.17927) (xy 158.33847 140.18746) (xy 158.33028 140.18746) (xy 158.13361 140.18746)
			(xy 158.13361 140.17927) (xy 158.13361 140.17107) (xy 158.13361 140.16288) (xy 158.13361 140.15468)
			(xy 158.13361 140.14649) (xy 158.13361 140.1383) (xy 158.13361 140.1301) (xy 158.13361 140.1219)
			(xy 158.13361 140.11371) (xy 158.13361 140.10552) (xy 158.13361 140.09732) (xy 158.13361 140.08913)
			(xy 158.13361 140.08093) (xy 158.13361 140.07274) (xy 158.13361 140.06454) (xy 158.13361 140.05635)
			(xy 158.13361 140.04815) (xy 158.13361 140.03996) (xy 158.13361 140.03176) (xy 158.13361 140.02357)
			(xy 158.13361 140.01538) (xy 158.13361 140.00718) (xy 158.13361 139.99899) (xy 158.13361 139.99079)
			(xy 158.13361 139.9826) (xy 158.13361 139.9744) (xy 158.13361 139.96621) (xy 158.13361 139.95802)
			(xy 158.13361 139.94982) (xy 158.13361 139.94163) (xy 158.13361 139.93343) (xy 158.13361 139.92524)
			(xy 158.13361 139.91704) (xy 158.13361 139.90885) (xy 158.13361 139.90065) (xy 158.13361 139.89246)
			(xy 158.13361 139.88426) (xy 158.13361 139.87607) (xy 158.13361 139.86787) (xy 158.13361 139.85968)
			(xy 158.13361 139.85149) (xy 158.13361 139.84329) (xy 158.13361 139.8351) (xy 158.13361 139.8269)
			(xy 158.13361 139.81871) (xy 158.13361 139.81051) (xy 158.13361 139.80232) (xy 158.13361 139.79413)
			(xy 158.13361 139.78593) (xy 158.13361 139.77773) (xy 158.13361 139.76954) (xy 158.13361 139.76135)
			(xy 158.13361 139.75315) (xy 158.13361 139.74496) (xy 158.13361 139.73676) (xy 158.13361 139.72857)
			(xy 158.13361 139.72038) (xy 158.13361 139.71218) (xy 158.13361 139.70398) (xy 158.13361 139.69579)
			(xy 158.13361 139.6876) (xy 158.13361 139.6794) (xy 158.13361 139.67121) (xy 158.13361 139.66301)
			(xy 158.13361 139.65482) (xy 158.13361 139.64662) (xy 158.13361 139.63843) (xy 158.13361 139.63023)
			(xy 158.13361 139.62204) (xy 158.13361 139.61385) (xy 158.13361 139.60565) (xy 158.13361 139.59746)
			(xy 158.13361 139.58926) (xy 158.13361 139.58107) (xy 158.13361 139.57287) (xy 158.13361 139.56468)
			(xy 158.13361 139.55649) (xy 158.13361 139.54829) (xy 158.13361 139.54009) (xy 158.13361 139.5319)
			(xy 158.13361 139.52371) (xy 158.13361 139.51551) (xy 158.13361 139.50732) (xy 158.13361 139.49912)
			(xy 158.13361 139.49093) (xy 158.13361 139.48273) (xy 158.13361 139.47454) (xy 158.13361 139.46634)
			(xy 158.13361 139.45815) (xy 158.13361 139.44996) (xy 158.13361 139.44176) (xy 158.13361 139.43357)
			(xy 158.13361 139.42537) (xy 158.13361 139.41718) (xy 158.13361 139.40898) (xy 158.13361 139.40079)
			(xy 158.13361 139.39259) (xy 158.13361 139.3844) (xy 158.13361 139.37621) (xy 158.13361 139.36801)
			(xy 158.13361 139.35982) (xy 158.13361 139.35162) (xy 158.13361 139.34342) (xy 158.13361 139.33523)
			(xy 158.13361 139.32704) (xy 158.13361 139.31884) (xy 158.13361 139.31065) (xy 158.13361 139.30245)
			(xy 158.13361 139.29426) (xy 158.13361 139.28607) (xy 158.13361 139.27787) (xy 158.13361 139.26968)
			(xy 158.13361 139.26148) (xy 158.13361 139.25329) (xy 158.13361 139.24509) (xy 158.13361 139.2369)
			(xy 158.13361 139.22871) (xy 158.13361 139.22051) (xy 158.13361 139.21232) (xy 158.13361 139.20412)
			(xy 158.13361 139.19593) (xy 158.13361 139.18773) (xy 158.13361 139.17954) (xy 158.12542 139.17954)
			(xy 158.12542 139.17134) (xy 158.12542 139.16315) (xy 158.12542 139.15495) (xy 158.12542 139.14676)
			(xy 158.11722 139.14676) (xy 158.11722 139.13857) (xy 158.11722 139.13037) (xy 158.10903 139.13037)
			(xy 158.10903 139.12218) (xy 158.10083 139.12218) (xy 158.10083 139.11398) (xy 158.09264 139.11398)
			(xy 158.09264 139.10579) (xy 158.08444 139.10579) (xy 158.08444 139.09759) (xy 158.07625 139.09759)
			(xy 158.07625 139.0894) (xy 158.06805 139.0894) (xy 158.06805 139.0812) (xy 158.05986 139.0812) (xy 158.05986 139.07301)
			(xy 158.05167 139.07301) (xy 158.05167 139.06481) (xy 158.04347 139.06481) (xy 158.04347 139.05662)
			(xy 158.03528 139.05662) (xy 158.03528 139.04842) (xy 158.02708 139.04842) (xy 158.02708 139.04023)
			(xy 158.01889 139.04023) (xy 158.01889 139.03204) (xy 158.01069 139.03204) (xy 158.01069 139.02384)
			(xy 158.0025 139.02384) (xy 158.0025 139.01565) (xy 157.9943 139.01565) (xy 157.9943 139.00745) (xy 157.98611 139.00745)
			(xy 157.98611 138.99926) (xy 157.97791 138.99926) (xy 157.97791 138.99107) (xy 157.96972 138.99107)
			(xy 157.96972 138.98287) (xy 157.96153 138.98287) (xy 157.96153 138.97467) (xy 157.95333 138.97467)
			(xy 157.95333 138.96648) (xy 157.94514 138.96648) (xy 157.94514 138.95829) (xy 157.93694 138.95829)
			(xy 157.93694 138.95009) (xy 157.92875 138.95009) (xy 157.92875 138.9419) (xy 157.92055 138.9419)
			(xy 157.92055 138.9337) (xy 157.91236 138.9337) (xy 157.91236 138.92551) (xy 157.90416 138.92551)
			(xy 157.90416 138.91731) (xy 157.89597 138.91731) (xy 157.89597 138.90912) (xy 157.88778 138.90912)
			(xy 157.88778 138.90092) (xy 157.87139 138.90092) (xy 157.87139 138.89273) (xy 157.83861 138.89273)
			(xy 157.83861 138.88454) (xy 157.69111 138.88454) (xy 157.69111 138.89273) (xy 157.69111 138.90092)
			(xy 157.69111 138.90912) (xy 157.69111 138.91731) (xy 157.69111 138.92551) (xy 157.69111 138.9337)
			(xy 157.69111 138.9419) (xy 157.69111 138.95009) (xy 157.69111 138.95829) (xy 157.69111 138.96648)
			(xy 157.69111 138.97467) (xy 157.69111 138.98287) (xy 157.69111 138.99107) (xy 157.69111 138.99926)
			(xy 157.69111 139.00745) (xy 157.69111 139.01565) (xy 157.69111 139.02384) (xy 157.69111 139.03204)
			(xy 157.69111 139.04023) (xy 157.69111 139.04842) (xy 157.69111 139.05662) (xy 157.69111 139.06481)
			(xy 157.69111 139.07301) (xy 157.69111 139.0812) (xy 157.69111 139.0894) (xy 157.69111 139.09759)
			(xy 157.69111 139.10579) (xy 157.69111 139.11398) (xy 157.69111 139.12218) (xy 157.69111 139.13037)
			(xy 157.69111 139.13857) (xy 157.69111 139.14676) (xy 157.69111 139.15495) (xy 157.69111 139.16315)
			(xy 157.69111 139.17134) (xy 157.69111 139.17954) (xy 157.69111 139.18773) (xy 157.69111 139.19593)
			(xy 157.69111 139.20412) (xy 157.69111 139.21232) (xy 157.69111 139.22051) (xy 157.69111 139.22871)
			(xy 157.69111 139.2369) (xy 157.69111 139.24509) (xy 157.69111 139.25329) (xy 157.69111 139.26148)
			(xy 157.69111 139.26968) (xy 157.69111 139.27787) (xy 157.69111 139.28607) (xy 157.69111 139.29426)
			(xy 157.69111 139.30245) (xy 157.69111 139.31065) (xy 157.69111 139.31884) (xy 157.69111 139.32704)
			(xy 157.69111 139.33523) (xy 157.69111 139.34342) (xy 157.69111 139.35162) (xy 157.69111 139.35982)
			(xy 157.69111 139.36801) (xy 157.69111 139.37621) (xy 157.69111 139.3844) (xy 157.69111 139.39259)
			(xy 157.69111 139.40079) (xy 157.69111 139.40898) (xy 157.69111 139.41718) (xy 157.69111 139.42537)
			(xy 157.69111 139.43357) (xy 157.69111 139.44176) (xy 157.69111 139.44996) (xy 157.69111 139.45815)
			(xy 157.69111 139.46634) (xy 157.69111 139.47454) (xy 157.69111 139.48273) (xy 157.69111 139.49093)
			(xy 157.69111 139.49912) (xy 157.69111 139.50732) (xy 157.69111 139.51551) (xy 157.69111 139.52371)
			(xy 157.69111 139.5319) (xy 157.69111 139.54009) (xy 157.69111 139.54829) (xy 157.69111 139.55649)
			(xy 157.69111 139.56468) (xy 157.69111 139.57287) (xy 157.69111 139.58107) (xy 157.69111 139.58926)
			(xy 157.69111 139.59746) (xy 157.69111 139.60565) (xy 157.69111 139.61385) (xy 157.69111 139.62204)
			(xy 157.69111 139.63023) (xy 157.69111 139.63843) (xy 157.69111 139.64662) (xy 157.69111 139.65482)
			(xy 157.69111 139.66301) (xy 157.69111 139.67121) (xy 157.69111 139.6794) (xy 157.69111 139.6876)
			(xy 157.69111 139.69579) (xy 157.69111 139.70398) (xy 157.69111 139.71218) (xy 157.69111 139.72038)
			(xy 157.69111 139.72857) (xy 157.69111 139.73676) (xy 157.69111 139.74496) (xy 157.69111 139.75315)
			(xy 157.69111 139.76135) (xy 157.69111 139.76954) (xy 157.69111 139.77773) (xy 157.69111 139.78593)
			(xy 157.69111 139.79413) (xy 157.69111 139.80232) (xy 157.69111 139.81051) (xy 157.69111 139.81871)
			(xy 157.69111 139.8269) (xy 157.69111 139.8351) (xy 157.69111 139.84329) (xy 157.69111 139.85149)
			(xy 157.69111 139.85968) (xy 157.69111 139.86787) (xy 157.69111 139.87607) (xy 157.69111 139.88426)
			(xy 157.69111 139.89246) (xy 157.69111 139.90065) (xy 157.69111 139.90885) (xy 157.69111 139.91704)
			(xy 157.69111 139.92524) (xy 157.69111 139.93343) (xy 157.69111 139.94163) (xy 157.69111 139.94982)
			(xy 157.69111 139.95802) (xy 157.69111 139.96621) (xy 157.69111 139.9744) (xy 157.69111 139.9826)
			(xy 157.69111 139.99079) (xy 157.69111 139.99899) (xy 157.69111 140.00718) (xy 157.69111 140.01538)
			(xy 157.69111 140.02357) (xy 157.69111 140.03176) (xy 157.69111 140.03996) (xy 157.69111 140.04815)
			(xy 157.69111 140.05635) (xy 157.69111 140.06454) (xy 157.69111 140.07274) (xy 157.69111 140.08093)
			(xy 157.69111 140.08913) (xy 157.69111 140.09732) (xy 157.69111 140.10552) (xy 157.69111 140.11371)
			(xy 157.69111 140.1219) (xy 157.69111 140.1301) (xy 157.69111 140.1383) (xy 157.69111 140.14649)
			(xy 157.69111 140.15468) (xy 157.69111 140.16288) (xy 157.69111 140.17107) (xy 157.69111 140.17927)
			(xy 157.69111 140.18746) (xy 157.69111 140.19565) (xy 157.69111 140.20385) (xy 157.69111 140.21204)
			(xy 157.69111 140.22024) (xy 157.69111 140.22843) (xy 157.69111 140.23663) (xy 157.69111 140.24482)
			(xy 157.69111 140.25302) (xy 157.69111 140.26121) (xy 157.69111 140.2694) (xy 157.69111 140.2776)
			(xy 157.69111 140.28579) (xy 157.69111 140.29399) (xy 157.69111 140.30218) (xy 157.69111 140.31038)
			(xy 157.69111 140.31857) (xy 157.69111 140.32677) (xy 157.69111 140.33496) (xy 157.69111 140.34316)
			(xy 157.69111 140.35135) (xy 157.69111 140.35954) (xy 157.69111 140.36774) (xy 157.69111 140.37593)
			(xy 157.69111 140.38413) (xy 157.69111 140.39232) (xy 157.69111 140.40052) (xy 157.69111 140.40871)
			(xy 157.69111 140.41691) (xy 157.69111 140.4251) (xy 157.69111 140.4333) (xy 157.69111 140.44149)
			(xy 157.69111 140.44969) (xy 157.69111 140.45788) (xy 157.69111 140.46607) (xy 157.69111 140.47427)
			(xy 157.69111 140.48246) (xy 157.69111 140.49066) (xy 157.69111 140.49885) (xy 157.69111 140.50704)
			(xy 157.69111 140.51524) (xy 157.69111 140.52344) (xy 157.69111 140.53163) (xy 157.69111 140.53982)
			(xy 157.69111 140.54802) (xy 157.69111 140.55621) (xy 157.69111 140.56441) (xy 157.69111 140.5726)
			(xy 157.69111 140.5808) (xy 157.69111 140.58899) (xy 157.69111 140.59718) (xy 157.69111 140.60538)
			(xy 157.69111 140.61357) (xy 157.69111 140.62177) (xy 157.69111 140.62996) (xy 157.69111 140.63816)
			(xy 157.69111 140.64635) (xy 157.69111 140.65455) (xy 157.69111 140.66274) (xy 157.69111 140.67094)
			(xy 157.69111 140.67913) (xy 157.69111 140.68732) (xy 157.69111 140.69552) (xy 157.69111 140.70371)
			(xy 157.69111 140.71191) (xy 157.69111 140.7201) (xy 157.69111 140.7283) (xy 157.69111 140.73649)
			(xy 157.69111 140.74469) (xy 157.69111 140.75288) (xy 157.69111 140.76108) (xy 157.69111 140.76927)
			(xy 157.69111 140.77746) (xy 157.69111 140.78566) (xy 157.69111 140.79385) (xy 157.69111 140.80205)
			(xy 157.69111 140.81024) (xy 157.69111 140.81844) (xy 157.69111 140.82663) (xy 157.69111 140.83482)
			(xy 157.69111 140.84302) (xy 157.69111 140.85121) (xy 157.69111 140.85941) (xy 157.69111 140.86761)
			(xy 157.69111 140.8758) (xy 157.69111 140.88399) (xy 157.69111 140.89219) (xy 157.69111 140.90038)
			(xy 157.69111 140.90858) (xy 157.69111 140.91677) (xy 157.69111 140.92496) (xy 157.69111 140.93316)
			(xy 157.69111 140.94135) (xy 157.69111 140.94955) (xy 157.69111 140.95774) (xy 157.69111 140.96594)
			(xy 157.69111 140.97413) (xy 157.69111 140.98233) (xy 157.69111 140.99052) (xy 157.69111 140.99872)
			(xy 157.69111 141.00691) (xy 157.69111 141.0151) (xy 157.69111 141.0233) (xy 157.69111 141.03149)
			(xy 157.69111 141.03969) (xy 157.69111 141.04788) (xy 157.69111 141.05608) (xy 157.69111 141.06427)
			(xy 157.69111 141.07247) (xy 157.69111 141.08066) (xy 157.69111 141.08885) (xy 157.69111 141.09705)
			(xy 157.69111 141.10525) (xy 157.69111 141.11344) (xy 157.69111 141.12163) (xy 157.69111 141.12983)
			(xy 157.69111 141.13802) (xy 157.69111 141.14622) (xy 157.69111 141.15441) (xy 157.69111 141.16261)
			(xy 157.69111 141.1708) (xy 157.69111 141.179) (xy 157.69111 141.18719) (xy 157.69111 141.19538)
			(xy 157.69111 141.20358) (xy 157.69111 141.21177) (xy 157.69111 141.21997) (xy 157.69111 141.22816)
			(xy 157.69111 141.23636) (xy 157.69111 141.24455) (xy 157.69111 141.25274) (xy 157.69111 141.26094)
			(xy 157.69111 141.26913) (xy 157.69111 141.27733) (xy 157.69111 141.28552) (xy 157.69111 141.29372)
			(xy 157.69111 141.30191) (xy 157.69111 141.31011) (xy 157.69111 141.3183) (xy 157.69111 141.32649)
			(xy 157.69111 141.33469) (xy 157.69111 141.34289) (xy 157.69111 141.35108) (xy 157.69111 141.35927)
			(xy 157.69111 141.36747) (xy 157.69111 141.37566) (xy 157.69111 141.38386) (xy 157.69111 141.39205)
			(xy 157.69111 141.40025) (xy 157.69111 141.40844) (xy 157.69111 141.41663) (xy 157.69111 141.42483)
			(xy 157.69111 141.43302) (xy 157.69111 141.44122) (xy 157.69111 141.44941) (xy 157.69111 141.45761)
			(xy 157.69111 141.4658) (xy 157.69111 141.474) (xy 157.69111 141.48219) (xy 157.69111 141.49039)
			(xy 157.69111 141.49858) (xy 157.69111 141.50677) (xy 157.69111 141.51497) (xy 157.69111 141.52316)
			(xy 157.69111 141.53136) (xy 157.69111 141.53955) (xy 157.69111 141.54775) (xy 157.69111 141.55594)
			(xy 157.69111 141.56413) (xy 157.69111 141.57233) (xy 157.69111 141.58052) (xy 157.69111 141.58872)
			(xy 157.69111 141.59692) (xy 157.68291 141.59692) (xy 157.68291 141.60511) (xy 157.67472 141.60511)
			(xy 157.67472 141.6133) (xy 157.66652 141.6133) (xy 157.66652 141.6215) (xy 157.65833 141.6215) (xy 157.65833 141.62969)
			(xy 157.65013 141.62969) (xy 157.65013 141.63789) (xy 157.64194 141.63789) (xy 157.64194 141.64608)
			(xy 157.63375 141.64608) (xy 157.63375 141.65427) (xy 157.62555 141.65427) (xy 157.62555 141.66247)
			(xy 157.61736 141.66247) (xy 157.61736 141.67066) (xy 157.60916 141.67066) (xy 157.60916 141.67886)
			(xy 157.60097 141.67886) (xy 157.60097 141.68705) (xy 157.59277 141.68705) (xy 157.59277 141.69525)
			(xy 157.58458 141.69525) (xy 157.58458 141.70344) (xy 157.57639 141.70344) (xy 157.57639 141.71164)
			(xy 157.56819 141.71164) (xy 157.56819 141.71983) (xy 157.55999 141.71983) (xy 157.55999 141.72803)
			(xy 157.5518 141.72803) (xy 157.5518 141.73622) (xy 157.53541 141.73622) (xy 157.53541 141.74441)
			(xy 157.52722 141.74441) (xy 157.52722 141.75261) (xy 157.51902 141.75261) (xy 157.51902 141.7608)
			(xy 157.51083 141.7608) (xy 157.51083 141.769) (xy 157.50263 141.769) (xy 157.50263 141.77719) (xy 157.49444 141.77719)
			(xy 157.49444 141.78539) (xy 157.48624 141.78539) (xy 157.48624 141.79358) (xy 157.47805 141.79358)
			(xy 157.47805 141.80177) (xy 157.46986 141.80177) (xy 157.46986 141.80997) (xy 157.46166 141.80997)
			(xy 157.46166 141.81816) (xy 157.45347 141.81816) (xy 157.45347 141.82636) (xy 157.44527 141.82636)
			(xy 157.44527 141.83456) (xy 157.43708 141.83456) (xy 157.43708 141.84275) (xy 157.42888 141.84275)
			(xy 157.42888 141.85094) (xy 157.42069 141.85094) (xy 157.42069 141.85914) (xy 157.41249 141.85914)
			(xy 157.41249 141.86733) (xy 157.4043 141.86733) (xy 157.4043 141.87553) (xy 157.39611 141.87553)
			(xy 157.39611 141.88372) (xy 157.38791 141.88372) (xy 157.38791 141.89192) (xy 157.37972 141.89192)
			(xy 157.37972 141.90011) (xy 157.37152 141.90011) (xy 157.37152 141.9083) (xy 157.36333 141.9083)
			(xy 157.36333 141.9165) (xy 157.35513 141.9165) (xy 157.35513 141.92469) (xy 157.34694 141.92469)
			(xy 157.34694 141.93289) (xy 157.33875 141.93289) (xy 157.33875 141.94108) (xy 157.33055 141.94108)
			(xy 157.33055 141.94927) (xy 157.32235 141.94927) (xy 157.32235 141.95747) (xy 157.31416 141.95747)
			(xy 157.31416 141.96567) (xy 157.30597 141.96567) (xy 157.30597 141.97386) (xy 157.29777 141.97386)
			(xy 157.29777 141.98205) (xy 157.28958 141.98205) (xy 157.28958 141.99025) (xy 157.28138 141.99025)
			(xy 157.28138 141.99844) (xy 157.27319 141.99844) (xy 157.27319 142.00664) (xy 157.26499 142.00664)
			(xy 157.26499 142.01483) (xy 157.2568 142.01483) (xy 157.2568 142.02303) (xy 157.2486 142.02303)
			(xy 157.2486 142.03122) (xy 157.24041 142.03122) (xy 157.24041 142.03942) (xy 157.23222 142.03942)
			(xy 157.23222 142.04761) (xy 157.22402 142.04761) (xy 157.22402 142.0558) (xy 157.21583 142.0558)
			(xy 157.21583 142.064) (xy 157.20763 142.064) (xy 157.20763 142.07219) (xy 157.19944 142.07219) (xy 157.19944 142.08039)
			(xy 157.19124 142.08039) (xy 157.19124 142.08858) (xy 157.18305 142.08858) (xy 157.18305 142.09678)
			(xy 157.17485 142.09678) (xy 157.17485 142.10497) (xy 157.16666 142.10497) (xy 157.16666 142.11317)
			(xy 157.15847 142.11317) (xy 157.15847 142.12136) (xy 157.15027 142.12136) (xy 157.15027 142.12956)
			(xy 157.14208 142.12956) (xy 157.14208 142.13775) (xy 157.13388 142.13775) (xy 157.13388 142.14594)
			(xy 157.12569 142.14594) (xy 157.12569 142.15414) (xy 157.11749 142.15414) (xy 157.11749 142.16233)
			(xy 157.1093 142.16233) (xy 157.1093 142.17053) (xy 157.1011 142.17053) (xy 157.1011 142.17872) (xy 157.09291 142.17872)
			(xy 157.09291 142.18692) (xy 157.08471 142.18692) (xy 157.08471 142.19511) (xy 157.07652 142.19511)
			(xy 157.07652 142.20331) (xy 157.06832 142.20331) (xy 157.06832 142.2115) (xy 157.06013 142.2115)
			(xy 157.06013 142.21969) (xy 157.05194 142.21969) (xy 157.05194 142.22789) (xy 157.04374 142.22789)
			(xy 157.04374 142.23608) (xy 157.03555 142.23608) (xy 157.03555 142.24428) (xy 157.02735 142.24428)
			(xy 157.02735 142.25247) (xy 157.01916 142.25247) (xy 157.01916 142.26067) (xy 157.01097 142.26067)
			(xy 157.01097 142.26886) (xy 157.00277 142.26886) (xy 157.00277 142.27706) (xy 156.99457 142.27706)
			(xy 156.99457 142.28525) (xy 156.97819 142.28525) (xy 156.97819 142.29344) (xy 156.96999 142.29344)
			(xy 156.96999 142.30164) (xy 156.9618 142.30164) (xy 156.9618 142.30984) (xy 156.9536 142.30984)
			(xy 156.9536 142.31803) (xy 156.94541 142.31803) (xy 156.94541 142.32622) (xy 156.93721 142.32622)
			(xy 156.93721 142.33442) (xy 156.92902 142.33442) (xy 156.92902 142.34261) (xy 156.92083 142.34261)
			(xy 156.92083 142.35081) (xy 156.91263 142.35081) (xy 156.91263 142.359) (xy 156.90444 142.359) (xy 156.90444 142.3672)
			(xy 156.89624 142.3672) (xy 156.89624 142.37539) (xy 156.88805 142.37539) (xy 156.88805 142.38359)
			(xy 156.87985 142.38359) (xy 156.87985 142.39178) (xy 156.87166 142.39178) (xy 156.87166 142.39997)
			(xy 156.86346 142.39997) (xy 156.86346 142.40817) (xy 156.85527 142.40817) (xy 156.85527 142.41636)
			(xy 156.84708 142.41636) (xy 156.84708 142.42456) (xy 156.84708 142.43275) (xy 156.83888 142.43275)
			(xy 156.83888 142.44095) (xy 156.83068 142.44095) (xy 156.83068 142.44914) (xy 156.83068 142.45734)
			(xy 156.82249 142.45734) (xy 156.82249 142.46553) (xy 156.82249 142.47372) (xy 156.8143 142.47372)
			(xy 156.10137 142.47372) (xy 156.10137 142.46553) (xy 156.10137 142.45734) (xy 156.10137 142.44914)
			(xy 156.10137 142.44095) (xy 156.10137 142.43275) (xy 156.10137 142.42456) (xy 156.10137 142.41636)
			(xy 156.10137 142.40817) (xy 156.10137 142.39997) (xy 156.10137 142.39178) (xy 156.10137 142.38359)
			(xy 156.10137 142.37539) (xy 156.10137 142.3672) (xy 156.10137 142.359) (xy 156.10137 142.35081)
			(xy 156.10137 142.34261) (xy 156.10137 142.33442) (xy 156.10137 142.32622) (xy 156.10137 142.31803)
			(xy 156.10137 142.30984) (xy 156.10137 142.30164) (xy 156.10137 142.29344) (xy 156.10137 142.28525)
			(xy 156.10137 142.27706) (xy 156.10137 142.26886) (xy 156.10137 142.26067) (xy 156.10137 142.25247)
			(xy 156.10957 142.25247) (xy 156.10957 142.24428) (xy 156.11776 142.24428) (xy 156.11776 142.23608)
			(xy 156.92902 142.23608) (xy 156.92902 142.22789) (xy 156.93721 142.22789) (xy 156.93721 142.23608)
			(xy 156.96999 142.23608) (xy 156.96999 142.22789) (xy 156.99457 142.22789) (xy 156.99457 142.21969)
			(xy 157.00277 142.21969) (xy 157.00277 142.2115) (xy 157.01097 142.2115) (xy 157.01097 142.20331)
			(xy 157.01097 142.19511) (xy 157.01097 142.18692) (xy 157.01097 142.17872) (xy 157.01097 142.17053)
			(xy 157.01097 142.16233) (xy 157.01097 142.15414) (xy 157.01097 142.14594) (xy 157.01097 142.13775)
			(xy 157.01097 142.12956) (xy 157.01097 142.12136) (xy 157.01097 142.11317) (xy 157.01097 142.10497)
			(xy 157.01097 142.09678) (xy 157.01097 142.08858) (xy 157.01097 142.08039) (xy 157.01097 142.07219)
			(xy 157.01097 142.064) (xy 157.01097 142.0558) (xy 157.01097 142.04761) (xy 157.01097 142.03942)
			(xy 157.01097 142.03122) (xy 157.01097 142.02303) (xy 157.01097 142.01483) (xy 157.01097 142.00664)
			(xy 157.01097 141.99844) (xy 157.01097 141.99025) (xy 157.01097 141.98205) (xy 157.01097 141.97386)
			(xy 157.01097 141.96567) (xy 157.01097 141.95747) (xy 157.01097 141.94927) (xy 157.01097 141.94108)
			(xy 157.01097 141.93289) (xy 157.01097 141.92469) (xy 157.01097 141.9165) (xy 157.01097 141.9083)
			(xy 157.01097 141.90011) (xy 157.01097 141.89192) (xy 157.01097 141.88372) (xy 157.01097 141.87553)
			(xy 157.01097 141.86733) (xy 157.01097 141.85914) (xy 157.01097 141.85094) (xy 157.01097 141.84275)
			(xy 157.01097 141.83456) (xy 157.01097 141.82636) (xy 157.01097 141.81816) (xy 157.00277 141.81816)
			(xy 157.00277 141.80997) (xy 156.99457 141.80997) (xy 156.99457 141.80177) (xy 156.96999 141.80177)
			(xy 156.96999 141.79358) (xy 156.9536 141.79358) (xy 156.9536 141.80177) (xy 156.94541 141.80177)
			(xy 156.94541 141.79358) (xy 155.96207 141.79358) (xy 155.96207 141.80177) (xy 155.93749 141.80177)
			(xy 155.93749 141.80997) (xy 155.9129 141.80997) (xy 155.9129 141.81816) (xy 155.89651 141.81816)
			(xy 155.89651 141.82636) (xy 155.88832 141.82636) (xy 155.88832 141.83456) (xy 155.88013 141.83456)
			(xy 155.88013 141.84275) (xy 155.87193 141.84275) (xy 155.87193 141.85094) (xy 155.86373 141.85094)
			(xy 155.86373 141.85914) (xy 155.85554 141.85914) (xy 155.85554 141.86733) (xy 155.84735 141.86733)
			(xy 155.84735 141.87553) (xy 155.83915 141.87553) (xy 155.83915 141.88372) (xy 155.83096 141.88372)
			(xy 155.83096 141.89192) (xy 155.82276 141.89192) (xy 155.82276 141.90011) (xy 155.81457 141.90011)
			(xy 155.81457 141.9083) (xy 155.80637 141.9083) (xy 155.80637 141.9165) (xy 155.79818 141.9165) (xy 155.79818 141.92469)
			(xy 155.78999 141.92469) (xy 155.78999 141.93289) (xy 155.78179 141.93289) (xy 155.78179 141.94108)
			(xy 155.7736 141.94108) (xy 155.7736 141.94927) (xy 155.7654 141.94927) (xy 155.7654 141.95747) (xy 155.75721 141.95747)
			(xy 155.75721 141.96567) (xy 155.74901 141.96567) (xy 155.74901 141.97386) (xy 155.74082 141.97386)
			(xy 155.74082 141.98205) (xy 155.73262 141.98205) (xy 155.73262 141.99025) (xy 155.72443 141.99025)
			(xy 155.72443 141.99844) (xy 155.71623 141.99844) (xy 155.71623 142.00664) (xy 155.70804 142.00664)
			(xy 155.70804 142.01483) (xy 155.69985 142.01483) (xy 155.69985 142.02303) (xy 155.69165 142.02303)
			(xy 155.69165 142.03122) (xy 155.68346 142.03122) (xy 155.68346 142.03942) (xy 155.67526 142.03942)
			(xy 155.67526 142.04761) (xy 155.66707 142.04761) (xy 155.66707 142.0558) (xy 155.66707 142.064)
			(xy 155.65887 142.064) (xy 155.65887 142.07219) (xy 155.65887 142.08039) (xy 155.65887 142.08858)
			(xy 155.65887 142.09678) (xy 155.65068 142.09678) (xy 154.92137 142.09678) (xy 154.92137 142.08858)
			(xy 154.92137 142.08039) (xy 154.92137 142.07219) (xy 154.92137 142.064) (xy 154.91317 142.064) (xy 154.91317 142.0558)
			(xy 154.91317 142.04761) (xy 154.91317 142.03942) (xy 154.91317 142.03122) (xy 154.91317 142.02303)
			(xy 154.91317 142.01483) (xy 154.91317 142.00664) (xy 154.91317 141.99844) (xy 154.91317 141.99025)
			(xy 154.91317 141.98205) (xy 154.90498 141.98205) (xy 154.90498 141.97386) (xy 154.90498 141.96567)
			(xy 154.90498 141.95747) (xy 154.90498 141.94927) (xy 154.90498 141.94108) (xy 154.90498 141.93289)
			(xy 154.90498 141.92469) (xy 154.90498 141.9165) (xy 154.90498 141.9083) (xy 154.90498 141.90011)
			(xy 154.90498 141.89192) (xy 154.90498 141.88372) (xy 154.90498 141.87553) (xy 154.90498 141.86733)
			(xy 154.90498 141.85914) (xy 154.90498 141.85094) (xy 154.89678 141.85094) (xy 154.89678 141.84275)
			(xy 154.89678 141.83456) (xy 154.89678 141.82636) (xy 154.89678 141.81816) (xy 154.89678 141.80997)
			(xy 154.89678 141.80177) (xy 154.79845 141.80177) (xy 154.79845 141.80997) (xy 153.70039 141.80997)
			(xy 153.70039 141.80177) (xy 153.70039 141.79358) (xy 153.70039 141.78539) (xy 153.70039 141.77719)
			(xy 153.70039 141.769) (xy 153.70039 141.7608) (xy 153.70039 141.75261) (xy 153.70039 141.74441)
			(xy 153.70039 141.73622) (xy 153.70039 141.72803) (xy 153.70039 141.71983) (xy 153.70039 141.71164)
			(xy 153.70039 141.70344) (xy 153.70039 141.69525) (xy 153.70039 141.68705) (xy 153.70039 141.67886)
			(xy 153.70039 141.67066) (xy 153.70039 141.66247) (xy 153.70039 141.65427) (xy 153.70039 141.64608)
			(xy 153.70039 141.63789) (xy 153.70039 141.62969) (xy 153.70039 141.6215) (xy 153.70039 141.6133)
			(xy 153.70039 141.60511) (xy 153.70039 141.59692) (xy 153.70039 141.58872) (xy 153.70039 141.58052)
			(xy 153.70039 141.57233) (xy 153.70039 141.56413) (xy 153.70039 141.55594) (xy 153.70039 141.54775)
			(xy 153.70039 141.53955) (xy 153.70039 141.53136) (xy 153.70039 141.52316) (xy 153.70039 141.51497)
			(xy 153.70039 141.50677) (xy 153.70039 141.49858) (xy 153.70039 141.49039) (xy 153.70039 141.48219)
			(xy 153.70039 141.474) (xy 153.70039 141.4658) (xy 153.70039 141.45761) (xy 153.70039 141.44941)
			(xy 153.70039 141.44122) (xy 153.70039 141.43302) (xy 153.70039 141.42483) (xy 153.70039 141.41663)
			(xy 153.70039 141.40844) (xy 153.70039 141.40025) (xy 153.70039 141.39205) (xy 153.70039 141.38386)
			(xy 153.70039 141.37566) (xy 153.70039 141.36747) (xy 153.70039 141.35927) (xy 153.70039 141.35108)
			(xy 153.70039 141.34289) (xy 153.70039 141.33469) (xy 153.70039 141.32649) (xy 153.70039 141.3183)
			(xy 153.70039 141.31011) (xy 153.70039 141.30191) (xy 153.70039 141.29372) (xy 153.70039 141.28552)
			(xy 153.70039 141.27733) (xy 153.70039 141.26913) (xy 153.70039 141.26094) (xy 153.70039 141.25274)
			(xy 153.70039 141.24455) (xy 153.70039 141.23636) (xy 153.70039 141.22816) (xy 153.70039 141.21997)
			(xy 153.70039 141.21177) (xy 153.70039 141.20358) (xy 153.70039 141.19538) (xy 153.70039 141.18719)
			(xy 153.70039 141.179) (xy 153.70039 141.1708) (xy 153.70039 141.16261) (xy 153.70039 141.15441)
			(xy 153.70039 141.14622) (xy 153.70039 141.13802) (xy 152.90552 141.13802) (xy 152.90552 141.12983)
			(xy 152.90552 141.12163) (xy 152.90552 141.11344) (xy 152.90552 141.10525) (xy 152.90552 141.09705)
			(xy 152.90552 141.08885) (xy 152.90552 141.08066) (xy 152.90552 141.07247) (xy 152.90552 141.06427)
			(xy 152.90552 141.05608) (xy 152.90552 141.04788) (xy 152.90552 141.03969) (xy 152.90552 141.03149)
			(xy 152.90552 141.0233) (xy 152.90552 141.0151) (xy 152.90552 141.00691) (xy 152.90552 140.99872)
			(xy 152.90552 140.99052) (xy 152.90552 140.98233) (xy 152.90552 140.97413) (xy 152.90552 140.96594)
			(xy 152.90552 140.95774) (xy 152.90552 140.94955) (xy 152.90552 140.94135) (xy 152.90552 140.93316)
			(xy 152.90552 140.92496) (xy 152.90552 140.91677) (xy 152.90552 140.90858) (xy 152.90552 140.90038)
			(xy 152.90552 140.89219) (xy 152.90552 140.88399) (xy 152.90552 140.8758) (xy 152.90552 140.86761)
			(xy 152.90552 140.85941) (xy 152.90552 140.85121) (xy 152.90552 140.84302) (xy 152.90552 140.83482)
			(xy 152.90552 140.82663) (xy 152.90552 140.81844) (xy 152.90552 140.81024) (xy 152.90552 140.80205)
			(xy 152.90552 140.79385) (xy 152.90552 140.78566) (xy 152.90552 140.77746) (xy 152.90552 140.76927)
			(xy 152.90552 140.76108) (xy 152.90552 140.75288) (xy 152.90552 140.74469) (xy 152.90552 140.73649)
			(xy 152.90552 140.7283) (xy 152.90552 140.7201) (xy 152.90552 140.71191) (xy 152.90552 140.70371)
			(xy 152.90552 140.69552) (xy 152.90552 140.68732) (xy 152.90552 140.67913) (xy 152.90552 140.67094)
			(xy 152.90552 140.66274) (xy 152.90552 140.65455) (xy 152.90552 140.64635) (xy 152.90552 140.63816)
			(xy 152.90552 140.62996) (xy 152.90552 140.62177) (xy 152.90552 140.61357) (xy 152.90552 140.60538)
			(xy 152.90552 140.59718) (xy 152.90552 140.58899) (xy 152.90552 140.5808) (xy 152.90552 140.5726)
			(xy 152.90552 140.56441) (xy 152.90552 140.55621) (xy 152.90552 140.54802) (xy 152.90552 140.53982)
			(xy 152.90552 140.53163) (xy 152.90552 140.52344) (xy 152.90552 140.51524) (xy 152.90552 140.50704)
			(xy 152.90552 140.49885) (xy 152.90552 140.49066) (xy 152.90552 140.48246) (xy 152.90552 140.47427)
			(xy 152.90552 140.46607) (xy 152.90552 140.45788) (xy 152.90552 140.44969) (xy 152.90552 140.44149)
			(xy 152.90552 140.4333) (xy 152.90552 140.4251) (xy 152.90552 140.41691) (xy 152.90552 140.40871)
			(xy 152.90552 140.40052) (xy 152.90552 140.39232) (xy 152.90552 140.38413) (xy 152.90552 140.37593)
			(xy 152.90552 140.36774) (xy 152.90552 140.35954) (xy 152.90552 140.35135) (xy 152.90552 140.34316)
			(xy 152.90552 140.33496) (xy 152.90552 140.32677) (xy 152.90552 140.31857) (xy 152.90552 140.31038)
			(xy 152.90552 140.30218) (xy 152.90552 140.29399) (xy 152.90552 140.28579) (xy 152.90552 140.2776)
			(xy 152.90552 140.2694) (xy 152.90552 140.26121) (xy 152.90552 140.25302) (xy 152.90552 140.24482)
			(xy 152.90552 140.23663) (xy 152.90552 140.22843) (xy 152.90552 140.22024) (xy 152.90552 140.21204)
			(xy 152.90552 140.20385) (xy 152.90552 140.19565) (xy 152.90552 140.18746) (xy 152.90552 140.17927)
			(xy 152.90552 140.17107) (xy 152.90552 140.16288) (xy 152.90552 140.15468) (xy 152.90552 140.14649)
			(xy 152.90552 140.1383) (xy 152.90552 140.1301) (xy 152.90552 140.1219) (xy 152.90552 140.11371)
			(xy 152.90552 140.10552) (xy 152.90552 140.09732) (xy 152.90552 140.08913) (xy 152.90552 140.08093)
			(xy 152.90552 140.07274) (xy 152.90552 140.06454) (xy 152.90552 140.05635) (xy 152.90552 140.04815)
			(xy 152.90552 140.03996) (xy 152.90552 140.03176) (xy 152.90552 140.02357) (xy 152.90552 140.01538)
			(xy 152.90552 140.00718) (xy 152.90552 139.99899) (xy 152.90552 139.99079) (xy 152.90552 139.9826)
			(xy 152.90552 139.9744) (xy 152.90552 139.96621) (xy 152.90552 139.95802) (xy 152.90552 139.94982)
			(xy 152.90552 139.94163) (xy 152.90552 139.93343) (xy 152.90552 139.92524) (xy 152.90552 139.91704)
			(xy 152.90552 139.90885) (xy 152.90552 139.90065) (xy 152.90552 139.89246) (xy 154.1347 139.89246)
			(xy 154.1347 139.90065) (xy 154.1347 139.90885) (xy 154.1347 139.91704) (xy 154.1347 139.92524) (xy 154.1347 139.93343)
			(xy 154.1347 139.94163) (xy 154.1347 139.94982) (xy 154.1347 139.95802) (xy 154.1347 139.96621) (xy 154.1347 139.9744)
			(xy 154.1347 139.9826) (xy 154.1347 139.99079) (xy 154.1347 139.99899) (xy 154.1347 140.00718) (xy 154.1347 140.01538)
			(xy 154.1347 140.02357) (xy 154.1347 140.03176) (xy 154.1347 140.03996) (xy 154.1347 140.04815) (xy 154.1347 140.05635)
			(xy 154.1347 140.06454) (xy 154.1347 140.07274) (xy 154.1347 140.08093) (xy 154.1347 140.08913) (xy 154.1347 140.09732)
			(xy 154.1347 140.10552) (xy 154.1347 140.11371) (xy 154.1347 140.1219) (xy 154.1347 140.1301) (xy 154.1347 140.1383)
			(xy 154.1347 140.14649) (xy 154.1347 140.15468) (xy 154.1347 140.16288) (xy 154.1347 140.17107) (xy 154.1347 140.17927)
			(xy 154.1347 140.18746) (xy 154.1347 140.19565) (xy 154.1347 140.20385) (xy 154.1347 140.21204) (xy 154.1347 140.22024)
			(xy 154.1347 140.22843) (xy 154.1347 140.23663) (xy 154.1347 140.24482) (xy 154.1347 140.25302) (xy 154.1347 140.26121)
			(xy 154.1347 140.2694) (xy 154.14289 140.2694) (xy 154.14289 140.2776) (xy 154.15109 140.2776) (xy 154.15109 140.28579)
			(xy 154.15928 140.28579) (xy 154.15928 140.29399) (xy 154.17567 140.29399) (xy 154.17567 140.30218)
			(xy 154.56901 140.30218) (xy 154.56901 140.31038) (xy 154.5772 140.31038) (xy 154.5772 140.31857)
			(xy 154.58539 140.31857) (xy 154.58539 140.32677) (xy 154.58539 140.33496) (xy 154.59359 140.33496)
			(xy 154.59359 140.34316) (xy 154.59359 140.35135) (xy 154.59359 140.35954) (xy 154.59359 140.36774)
			(xy 154.59359 140.37593) (xy 154.59359 140.38413) (xy 154.59359 140.39232) (xy 154.59359 140.40052)
			(xy 154.59359 140.40871) (xy 154.59359 140.41691) (xy 154.59359 140.4251) (xy 154.59359 140.4333)
			(xy 154.59359 140.44149) (xy 154.59359 140.44969) (xy 154.59359 140.45788) (xy 154.59359 140.46607)
			(xy 154.59359 140.47427) (xy 154.59359 140.48246) (xy 154.59359 140.49066) (xy 154.59359 140.49885)
			(xy 154.59359 140.50704) (xy 154.59359 140.51524) (xy 154.59359 140.52344) (xy 154.59359 140.53163)
			(xy 154.59359 140.53982) (xy 154.59359 140.54802) (xy 154.59359 140.55621) (xy 154.59359 140.56441)
			(xy 154.59359 140.5726) (xy 154.59359 140.5808) (xy 154.59359 140.58899) (xy 154.59359 140.59718)
			(xy 154.59359 140.60538) (xy 154.59359 140.61357) (xy 154.59359 140.62177) (xy 154.59359 140.62996)
			(xy 154.59359 140.63816) (xy 154.59359 140.64635) (xy 154.59359 140.65455) (xy 154.59359 140.66274)
			(xy 154.59359 140.67094) (xy 154.59359 140.67913) (xy 154.59359 140.68732) (xy 154.59359 140.69552)
			(xy 154.59359 140.70371) (xy 154.59359 140.71191) (xy 154.59359 140.7201) (xy 154.59359 140.7283)
			(xy 154.59359 140.73649) (xy 154.59359 140.74469) (xy 154.59359 140.75288) (xy 154.59359 140.76108)
			(xy 154.59359 140.76927) (xy 154.59359 140.77746) (xy 154.59359 140.78566) (xy 154.59359 140.79385)
			(xy 154.59359 140.80205) (xy 154.59359 140.81024) (xy 154.59359 140.81844) (xy 154.59359 140.82663)
			(xy 154.59359 140.83482) (xy 154.59359 140.84302) (xy 154.59359 140.85121) (xy 154.59359 140.85941)
			(xy 154.59359 140.86761) (xy 154.59359 140.8758) (xy 154.59359 140.88399) (xy 154.59359 140.89219)
			(xy 154.59359 140.90038) (xy 154.59359 140.90858) (xy 154.59359 140.91677) (xy 154.59359 140.92496)
			(xy 154.59359 140.93316) (xy 154.59359 140.94135) (xy 154.59359 140.94955) (xy 154.59359 140.95774)
			(xy 154.59359 140.96594) (xy 154.59359 140.97413) (xy 154.59359 140.98233) (xy 154.59359 140.99052)
			(xy 154.59359 140.99872) (xy 154.59359 141.00691) (xy 154.59359 141.0151) (xy 154.59359 141.0233)
			(xy 154.59359 141.03149) (xy 154.59359 141.03969) (xy 154.59359 141.04788) (xy 154.59359 141.05608)
			(xy 154.59359 141.06427) (xy 154.59359 141.07247) (xy 154.59359 141.08066) (xy 154.59359 141.08885)
			(xy 154.59359 141.09705) (xy 154.59359 141.10525) (xy 154.59359 141.11344) (xy 154.59359 141.12163)
			(xy 154.59359 141.12983) (xy 154.59359 141.13802) (xy 154.59359 141.14622) (xy 154.59359 141.15441)
			(xy 154.59359 141.16261) (xy 154.59359 141.1708) (xy 154.59359 141.179) (xy 154.59359 141.18719)
			(xy 154.59359 141.19538) (xy 154.59359 141.20358) (xy 154.59359 141.21177) (xy 154.59359 141.21997)
			(xy 154.59359 141.22816) (xy 154.59359 141.23636) (xy 154.59359 141.24455) (xy 154.59359 141.25274)
			(xy 154.59359 141.26094) (xy 154.59359 141.26913) (xy 154.59359 141.27733) (xy 154.59359 141.28552)
			(xy 154.59359 141.29372) (xy 154.59359 141.30191) (xy 154.59359 141.31011) (xy 154.59359 141.3183)
			(xy 154.59359 141.32649) (xy 154.59359 141.33469) (xy 154.59359 141.34289) (xy 154.59359 141.35108)
			(xy 154.59359 141.35927) (xy 154.59359 141.36747) (xy 154.59359 141.37566) (xy 154.59359 141.38386)
			(xy 154.59359 141.39205) (xy 154.59359 141.40025) (xy 154.59359 141.40844) (xy 154.59359 141.41663)
			(xy 154.59359 141.42483) (xy 154.59359 141.43302) (xy 154.59359 141.44122) (xy 154.59359 141.44941)
			(xy 154.59359 141.45761) (xy 154.59359 141.4658) (xy 154.59359 141.474) (xy 154.59359 141.48219)
			(xy 154.59359 141.49039) (xy 154.59359 141.49858) (xy 154.59359 141.50677) (xy 154.59359 141.51497)
			(xy 154.59359 141.52316) (xy 154.59359 141.53136) (xy 154.59359 141.53955) (xy 154.59359 141.54775)
			(xy 154.59359 141.55594) (xy 154.59359 141.56413) (xy 154.59359 141.57233) (xy 154.59359 141.58052)
			(xy 154.59359 141.58872) (xy 154.59359 141.59692) (xy 154.59359 141.60511) (xy 154.59359 141.6133)
			(xy 154.59359 141.6215) (xy 154.60178 141.6215) (xy 154.60178 141.62969) (xy 154.60998 141.62969)
			(xy 154.60998 141.63789) (xy 154.61817 141.63789) (xy 154.61817 141.64608) (xy 155.0197 141.64608)
			(xy 155.0197 141.63789) (xy 155.0279 141.63789) (xy 155.0279 141.62969) (xy 155.03609 141.62969)
			(xy 155.03609 141.6215) (xy 155.03609 141.6133) (xy 155.03609 141.60511) (xy 155.04428 141.60511)
			(xy 155.04428 141.59692) (xy 155.04428 141.58872) (xy 155.04428 141.58052) (xy 155.04428 141.57233)
			(xy 155.04428 141.56413) (xy 155.04428 141.55594) (xy 155.04428 141.54775) (xy 155.04428 141.53955)
			(xy 155.04428 141.53136) (xy 155.04428 141.52316) (xy 155.04428 141.51497) (xy 155.04428 141.50677)
			(xy 155.04428 141.49858) (xy 155.04428 141.49039) (xy 155.04428 141.48219) (xy 155.04428 141.474)
			(xy 155.04428 141.4658) (xy 155.04428 141.45761) (xy 155.04428 141.44941) (xy 155.04428 141.44122)
			(xy 155.04428 141.43302) (xy 155.04428 141.42483) (xy 155.04428 141.41663) (xy 155.04428 141.40844)
			(xy 155.04428 141.40025) (xy 155.04428 141.39205) (xy 155.04428 141.38386) (xy 155.04428 141.37566)
			(xy 155.04428 141.36747) (xy 155.04428 141.35927) (xy 155.04428 141.35108) (xy 155.04428 141.34289)
			(xy 155.04428 141.33469) (xy 155.04428 141.32649) (xy 155.04428 141.3183) (xy 155.04428 141.31011)
			(xy 155.04428 141.30191) (xy 155.04428 141.29372) (xy 155.04428 141.28552) (xy 155.04428 141.27733)
			(xy 155.04428 141.26913) (xy 155.04428 141.26094) (xy 155.04428 141.25274) (xy 155.04428 141.24455)
			(xy 155.04428 141.23636) (xy 155.04428 141.22816) (xy 155.04428 141.21997) (xy 155.04428 141.21177)
			(xy 155.04428 141.20358) (xy 155.04428 141.19538) (xy 155.04428 141.18719) (xy 155.04428 141.179)
			(xy 155.04428 141.1708) (xy 155.04428 141.16261) (xy 155.04428 141.15441) (xy 155.04428 141.14622)
			(xy 155.04428 141.13802) (xy 155.04428 141.12983) (xy 155.04428 141.12163) (xy 155.04428 141.11344)
			(xy 155.04428 141.10525) (xy 155.04428 141.09705) (xy 155.04428 141.08885) (xy 155.04428 141.08066)
			(xy 155.04428 141.07247) (xy 155.04428 141.06427) (xy 155.04428 141.05608) (xy 155.04428 141.04788)
			(xy 155.04428 141.03969) (xy 155.04428 141.03149) (xy 155.04428 141.0233) (xy 155.04428 141.0151)
			(xy 155.04428 141.00691) (xy 155.04428 140.99872) (xy 155.04428 140.99052) (xy 155.04428 140.98233)
			(xy 155.04428 140.97413) (xy 155.04428 140.96594) (xy 155.04428 140.95774) (xy 155.04428 140.94955)
			(xy 155.04428 140.94135) (xy 155.04428 140.93316) (xy 155.04428 140.92496) (xy 155.04428 140.91677)
			(xy 155.04428 140.90858) (xy 155.04428 140.90038) (xy 155.04428 140.89219) (xy 155.04428 140.88399)
			(xy 155.04428 140.8758) (xy 155.04428 140.86761) (xy 155.04428 140.85941) (xy 155.04428 140.85121)
			(xy 155.04428 140.84302) (xy 155.04428 140.83482) (xy 155.04428 140.82663) (xy 155.04428 140.81844)
			(xy 155.04428 140.81024) (xy 155.04428 140.80205) (xy 155.04428 140.79385) (xy 155.04428 140.78566)
			(xy 155.04428 140.77746) (xy 155.04428 140.76927) (xy 155.04428 140.76108) (xy 155.04428 140.75288)
			(xy 155.04428 140.74469) (xy 155.04428 140.73649) (xy 155.04428 140.7283) (xy 155.04428 140.7201)
			(xy 155.04428 140.71191) (xy 155.04428 140.70371) (xy 155.04428 140.69552) (xy 155.04428 140.68732)
			(xy 155.04428 140.67913) (xy 155.04428 140.67094) (xy 155.04428 140.66274) (xy 155.04428 140.65455)
			(xy 155.04428 140.64635) (xy 155.04428 140.63816) (xy 155.04428 140.62996) (xy 155.04428 140.62177)
			(xy 155.04428 140.61357) (xy 155.04428 140.60538) (xy 155.04428 140.59718) (xy 155.04428 140.58899)
			(xy 155.04428 140.5808) (xy 155.04428 140.5726) (xy 155.04428 140.56441) (xy 155.04428 140.55621)
			(xy 155.04428 140.54802) (xy 155.04428 140.53982) (xy 155.04428 140.53163) (xy 155.04428 140.52344)
			(xy 155.04428 140.51524) (xy 155.04428 140.50704) (xy 155.04428 140.49885) (xy 155.04428 140.49066)
			(xy 155.04428 140.48246) (xy 155.04428 140.47427) (xy 155.04428 140.46607) (xy 155.04428 140.45788)
			(xy 155.04428 140.44969) (xy 155.04428 140.44149) (xy 155.04428 140.4333) (xy 155.04428 140.4251)
			(xy 155.04428 140.41691) (xy 155.04428 140.40871) (xy 155.04428 140.40052) (xy 155.04428 140.39232)
			(xy 155.04428 140.38413) (xy 155.04428 140.37593) (xy 155.04428 140.36774) (xy 155.04428 140.35954)
			(xy 155.04428 140.35135) (xy 155.04428 140.34316) (xy 155.04428 140.33496) (xy 155.04428 140.32677)
			(xy 155.04428 140.31857) (xy 155.05248 140.31857) (xy 155.05248 140.31038) (xy 155.06068 140.31038)
			(xy 155.06068 140.30218) (xy 155.45401 140.30218) (xy 155.45401 140.29399) (xy 155.47859 140.29399)
			(xy 155.47859 140.28579) (xy 155.48679 140.28579) (xy 155.48679 140.2776) (xy 155.49498 140.2776)
			(xy 155.49498 140.2694) (xy 155.49498 140.26121) (xy 155.49498 140.25302) (xy 155.50318 140.25302)
			(xy 155.50318 140.24482) (xy 155.50318 140.23663) (xy 155.50318 140.22843) (xy 155.50318 140.22024)
			(xy 155.50318 140.21204) (xy 155.50318 140.20385) (xy 155.50318 140.19565) (xy 155.50318 140.18746)
			(xy 155.50318 140.17927) (xy 155.50318 140.17107) (xy 155.50318 140.16288) (xy 155.50318 140.15468)
			(xy 155.50318 140.14649) (xy 155.50318 140.1383) (xy 155.50318 140.1301) (xy 155.50318 140.1219)
			(xy 155.50318 140.11371) (xy 155.50318 140.10552) (xy 155.50318 140.09732) (xy 155.50318 140.08913)
			(xy 155.50318 140.08093) (xy 155.50318 140.07274) (xy 155.50318 140.06454) (xy 155.50318 140.05635)
			(xy 155.50318 140.04815) (xy 155.50318 140.03996) (xy 155.50318 140.03176) (xy 155.50318 140.02357)
			(xy 155.50318 140.01538) (xy 155.50318 140.00718) (xy 155.50318 139.99899) (xy 155.50318 139.99079)
			(xy 155.50318 139.9826) (xy 155.50318 139.9744) (xy 155.50318 139.96621) (xy 155.50318 139.95802)
			(xy 155.50318 139.94982) (xy 155.50318 139.94163) (xy 155.50318 139.93343) (xy 155.50318 139.92524)
			(xy 155.50318 139.91704) (xy 155.50318 139.90885) (xy 155.49498 139.90885) (xy 155.49498 139.90065)
			(xy 155.60151 139.90065) (xy 155.60151 139.90885) (xy 155.60151 139.91704) (xy 155.60151 139.92524)
			(xy 155.60151 139.93343) (xy 155.60151 139.94163) (xy 155.60151 139.94982) (xy 155.60151 139.95802)
			(xy 155.60151 139.96621) (xy 155.60151 139.9744) (xy 155.60151 139.9826) (xy 155.60151 139.99079)
			(xy 155.60151 139.99899) (xy 155.60151 140.00718) (xy 155.60151 140.01538) (xy 155.60151 140.02357)
			(xy 155.60151 140.03176) (xy 155.60151 140.03996) (xy 155.60151 140.04815) (xy 155.60151 140.05635)
			(xy 155.60151 140.06454) (xy 155.60151 140.07274) (xy 155.60151 140.08093) (xy 155.60151 140.08913)
			(xy 155.60151 140.09732) (xy 155.60151 140.10552) (xy 155.60151 140.11371) (xy 155.60151 140.1219)
			(xy 155.60151 140.1301) (xy 155.60151 140.1383) (xy 155.60151 140.14649) (xy 155.60151 140.15468)
			(xy 155.60151 140.16288) (xy 155.60151 140.17107) (xy 155.60151 140.17927) (xy 155.60151 140.18746)
			(xy 155.60151 140.19565) (xy 155.60151 140.20385) (xy 155.60151 140.21204) (xy 155.60151 140.22024)
			(xy 155.60151 140.22843) (xy 155.60151 140.23663) (xy 155.60151 140.24482) (xy 155.60151 140.25302)
			(xy 155.60151 140.26121) (xy 155.60151 140.2694) (xy 155.60151 140.2776) (xy 155.60151 140.28579)
			(xy 155.60151 140.29399) (xy 155.60151 140.30218) (xy 155.60151 140.31038) (xy 155.60151 140.31857)
			(xy 155.60151 140.32677) (xy 155.60151 140.33496) (xy 155.60151 140.34316) (xy 155.60151 140.35135)
			(xy 155.60151 140.35954) (xy 155.60151 140.36774) (xy 155.60151 140.37593) (xy 155.60151 140.38413)
			(xy 155.60151 140.39232) (xy 155.60151 140.40052) (xy 155.60151 140.40871) (xy 155.60151 140.41691)
			(xy 155.60151 140.4251) (xy 155.60151 140.4333) (xy 155.60151 140.44149) (xy 155.60151 140.44969)
			(xy 155.60151 140.45788) (xy 155.60151 140.46607) (xy 155.60151 140.47427) (xy 155.60151 140.48246)
			(xy 155.60151 140.49066) (xy 155.60151 140.49885) (xy 155.60151 140.50704) (xy 155.60151 140.51524)
			(xy 155.60151 140.52344) (xy 155.60151 140.53163) (xy 155.60151 140.53982) (xy 155.60151 140.54802)
			(xy 155.60151 140.55621) (xy 155.60151 140.56441) (xy 155.60151 140.5726) (xy 155.60151 140.5808)
			(xy 155.60151 140.58899) (xy 155.60151 140.59718) (xy 155.60151 140.60538) (xy 155.60151 140.61357)
			(xy 155.60151 140.62177) (xy 155.60151 140.62996) (xy 155.60151 140.63816) (xy 155.60151 140.64635)
			(xy 155.60151 140.65455) (xy 155.60151 140.66274) (xy 155.60151 140.67094) (xy 155.60151 140.67913)
			(xy 155.60151 140.68732) (xy 155.60151 140.69552) (xy 155.60151 140.70371) (xy 155.60151 140.71191)
			(xy 155.60151 140.7201) (xy 155.60151 140.7283) (xy 155.60151 140.73649) (xy 155.60151 140.74469)
			(xy 155.60151 140.75288) (xy 155.60151 140.76108) (xy 155.60151 140.76927) (xy 155.60151 140.77746)
			(xy 155.60151 140.78566) (xy 155.60151 140.79385) (xy 155.60151 140.80205) (xy 155.60151 140.81024)
			(xy 155.60151 140.81844) (xy 155.60151 140.82663) (xy 155.60151 140.83482) (xy 155.60151 140.84302)
			(xy 155.60151 140.85121) (xy 155.60151 140.85941) (xy 155.60151 140.86761) (xy 155.60151 140.8758)
			(xy 155.60151 140.88399) (xy 155.60151 140.89219) (xy 155.60151 140.90038) (xy 155.60151 140.90858)
			(xy 155.60151 140.91677) (xy 155.60151 140.92496) (xy 155.60151 140.93316) (xy 155.60151 140.94135)
			(xy 155.60151 140.94955) (xy 155.60151 140.95774) (xy 155.60151 140.96594) (xy 155.60151 140.97413)
			(xy 155.60151 140.98233) (xy 155.60151 140.99052) (xy 155.60151 140.99872) (xy 155.60151 141.00691)
			(xy 155.60151 141.0151) (xy 155.60151 141.0233) (xy 155.60151 141.03149) (xy 155.60151 141.03969)
			(xy 155.60151 141.04788) (xy 155.60151 141.05608) (xy 155.60151 141.06427) (xy 155.60151 141.07247)
			(xy 155.60151 141.08066) (xy 155.60151 141.08885) (xy 155.60151 141.09705) (xy 155.60151 141.10525)
			(xy 155.60151 141.11344) (xy 155.60151 141.12163) (xy 155.60151 141.12983) (xy 155.60151 141.13802)
			(xy 155.60151 141.14622) (xy 155.60151 141.15441) (xy 155.60151 141.16261) (xy 155.60151 141.1708)
			(xy 155.60151 141.179) (xy 155.60151 141.18719) (xy 155.60151 141.19538) (xy 155.60151 141.20358)
			(xy 155.60151 141.21177) (xy 155.60151 141.21997) (xy 155.60151 141.22816) (xy 155.60151 141.23636)
			(xy 155.60151 141.24455) (xy 155.60151 141.25274) (xy 155.60151 141.26094) (xy 155.60151 141.26913)
			(xy 155.60151 141.27733) (xy 155.60151 141.28552) (xy 155.60151 141.29372) (xy 155.60151 141.30191)
			(xy 155.60151 141.31011) (xy 155.60151 141.3183) (xy 155.60151 141.32649) (xy 155.60151 141.33469)
			(xy 155.60151 141.34289) (xy 155.60151 141.35108) (xy 155.60151 141.35927) (xy 155.60151 141.36747)
			(xy 155.60151 141.37566) (xy 155.60151 141.38386) (xy 155.60151 141.39205) (xy 155.60151 141.40025)
			(xy 155.60151 141.40844) (xy 155.60151 141.41663) (xy 155.60151 141.42483) (xy 155.60151 141.43302)
			(xy 155.60151 141.44122) (xy 155.60151 141.44941) (xy 155.60151 141.45761) (xy 155.60151 141.4658)
			(xy 155.60151 141.474) (xy 155.60151 141.48219) (xy 155.60151 141.49039) (xy 155.60151 141.49858)
			(xy 155.60151 141.50677) (xy 155.60151 141.51497) (xy 155.60151 141.52316) (xy 155.60151 141.53136)
			(xy 155.60151 141.53955) (xy 155.60151 141.54775) (xy 155.60151 141.55594) (xy 155.60151 141.56413)
			(xy 155.60151 141.57233) (xy 155.60151 141.58052) (xy 155.60151 141.58872) (xy 155.60151 141.59692)
			(xy 155.60151 141.60511) (xy 155.60151 141.6133) (xy 155.6097 141.6133) (xy 155.6097 141.6215) (xy 155.6097 141.62969)
			(xy 155.6179 141.62969) (xy 155.6179 141.63789) (xy 155.62609 141.63789) (xy 155.62609 141.64608)
			(xy 156.03582 141.64608) (xy 156.03582 141.63789) (xy 156.04401 141.63789) (xy 156.04401 141.62969)
			(xy 156.05221 141.62969) (xy 156.05221 141.6215) (xy 156.05221 141.6133) (xy 156.05221 141.60511)
			(xy 156.05221 141.59692) (xy 156.05221 141.58872) (xy 156.05221 141.58052) (xy 156.05221 141.57233)
			(xy 156.05221 141.56413) (xy 156.05221 141.55594) (xy 156.05221 141.54775) (xy 156.05221 141.53955)
			(xy 156.05221 141.53136) (xy 156.05221 141.52316) (xy 156.05221 141.51497) (xy 156.05221 141.50677)
			(xy 156.05221 141.49858) (xy 156.05221 141.49039) (xy 156.05221 141.48219) (xy 156.05221 141.474)
			(xy 156.05221 141.4658) (xy 156.05221 141.45761) (xy 156.05221 141.44941) (xy 156.05221 141.44122)
			(xy 156.05221 141.43302) (xy 156.05221 141.42483) (xy 156.05221 141.41663) (xy 156.05221 141.40844)
			(xy 156.05221 141.40025) (xy 156.05221 141.39205) (xy 156.05221 141.38386) (xy 156.05221 141.37566)
			(xy 156.05221 141.36747) (xy 156.05221 141.35927) (xy 156.05221 141.35108) (xy 156.05221 141.34289)
			(xy 156.05221 141.33469) (xy 156.05221 141.32649) (xy 156.05221 141.3183) (xy 156.05221 141.31011)
			(xy 156.05221 141.30191) (xy 156.05221 141.29372) (xy 156.05221 141.28552) (xy 156.05221 141.27733)
			(xy 156.05221 141.26913) (xy 156.05221 141.26094) (xy 156.05221 141.25274) (xy 156.05221 141.24455)
			(xy 156.05221 141.23636) (xy 156.05221 141.22816) (xy 156.05221 141.21997) (xy 156.05221 141.21177)
			(xy 156.05221 141.20358) (xy 156.05221 141.19538) (xy 156.05221 141.18719) (xy 156.05221 141.179)
			(xy 156.05221 141.1708) (xy 156.05221 141.16261) (xy 156.05221 141.15441) (xy 156.05221 141.14622)
			(xy 156.05221 141.13802) (xy 156.05221 141.12983) (xy 156.05221 141.12163) (xy 156.05221 141.11344)
			(xy 156.05221 141.10525) (xy 156.05221 141.09705) (xy 156.05221 141.08885) (xy 156.05221 141.08066)
			(xy 156.05221 141.07247) (xy 156.05221 141.06427) (xy 156.05221 141.05608) (xy 156.05221 141.04788)
			(xy 156.05221 141.03969) (xy 156.05221 141.03149) (xy 156.05221 141.0233) (xy 156.05221 141.0151)
			(xy 156.05221 141.00691) (xy 156.05221 140.99872) (xy 156.05221 140.99052) (xy 156.05221 140.98233)
			(xy 156.05221 140.97413) (xy 156.05221 140.96594) (xy 156.05221 140.95774) (xy 156.05221 140.94955)
			(xy 156.05221 140.94135) (xy 156.05221 140.93316) (xy 156.05221 140.92496) (xy 156.05221 140.91677)
			(xy 156.05221 140.90858) (xy 156.05221 140.90038) (xy 156.05221 140.89219) (xy 156.05221 140.88399)
			(xy 156.05221 140.8758) (xy 156.05221 140.86761) (xy 156.05221 140.85941) (xy 156.05221 140.85121)
			(xy 156.05221 140.84302) (xy 156.05221 140.83482) (xy 156.05221 140.82663) (xy 156.05221 140.81844)
			(xy 156.05221 140.81024) (xy 156.05221 140.80205) (xy 156.05221 140.79385) (xy 156.05221 140.78566)
			(xy 156.05221 140.77746) (xy 156.05221 140.76927) (xy 156.05221 140.76108) (xy 156.05221 140.75288)
			(xy 156.05221 140.74469) (xy 156.05221 140.73649) (xy 156.05221 140.7283) (xy 156.05221 140.7201)
			(xy 156.05221 140.71191) (xy 156.05221 140.70371) (xy 156.05221 140.69552) (xy 156.05221 140.68732)
			(xy 156.05221 140.67913) (xy 156.05221 140.67094) (xy 156.05221 140.66274) (xy 156.05221 140.65455)
			(xy 156.05221 140.64635) (xy 156.05221 140.63816) (xy 156.05221 140.62996) (xy 156.05221 140.62177)
			(xy 156.05221 140.61357) (xy 156.05221 140.60538) (xy 156.05221 140.59718) (xy 156.05221 140.58899)
			(xy 156.05221 140.5808) (xy 156.05221 140.5726) (xy 156.05221 140.56441) (xy 156.05221 140.55621)
			(xy 156.05221 140.54802) (xy 156.05221 140.53982) (xy 156.05221 140.53163) (xy 156.05221 140.52344)
			(xy 156.05221 140.51524) (xy 156.05221 140.50704) (xy 156.05221 140.49885) (xy 156.05221 140.49066)
			(xy 156.05221 140.48246) (xy 156.05221 140.47427) (xy 156.05221 140.46607) (xy 156.05221 140.45788)
			(xy 156.05221 140.44969) (xy 156.05221 140.44149) (xy 156.05221 140.4333) (xy 156.05221 140.4251)
			(xy 156.05221 140.41691) (xy 156.05221 140.40871) (xy 156.05221 140.40052) (xy 156.05221 140.39232)
			(xy 156.05221 140.38413) (xy 156.05221 140.37593) (xy 156.05221 140.36774) (xy 156.05221 140.35954)
			(xy 156.05221 140.35135) (xy 156.05221 140.34316) (xy 156.05221 140.33496) (xy 156.05221 140.32677)
			(xy 156.05221 140.31857) (xy 156.05221 140.31038) (xy 156.05221 140.30218) (xy 156.05221 140.29399)
			(xy 156.05221 140.28579) (xy 156.05221 140.2776) (xy 156.05221 140.2694) (xy 156.05221 140.26121)
			(xy 156.05221 140.25302) (xy 156.05221 140.24482) (xy 156.05221 140.23663) (xy 156.05221 140.22843)
			(xy 156.05221 140.22024) (xy 156.05221 140.21204) (xy 156.05221 140.20385) (xy 156.05221 140.19565)
			(xy 156.05221 140.18746) (xy 156.05221 140.17927) (xy 156.05221 140.17107) (xy 156.05221 140.16288)
			(xy 156.05221 140.15468) (xy 156.05221 140.14649) (xy 156.05221 140.1383) (xy 156.05221 140.1301)
			(xy 156.05221 140.1219) (xy 156.05221 140.11371) (xy 156.05221 140.10552) (xy 156.05221 140.09732)
			(xy 156.05221 140.08913) (xy 156.05221 140.08093) (xy 156.05221 140.07274) (xy 156.05221 140.06454)
			(xy 156.05221 140.05635) (xy 156.05221 140.04815) (xy 156.05221 140.03996) (xy 156.05221 140.03176)
			(xy 156.05221 140.02357) (xy 156.05221 140.01538) (xy 156.05221 140.00718) (xy 156.05221 139.99899)
			(xy 156.05221 139.99079) (xy 156.05221 139.9826) (xy 156.05221 139.9744) (xy 156.05221 139.96621)
			(xy 156.05221 139.95802) (xy 156.05221 139.94982) (xy 156.05221 139.94163) (xy 156.05221 139.93343)
			(xy 156.05221 139.92524) (xy 156.05221 139.91704) (xy 156.05221 139.90885) (xy 156.05221 139.90065)
			(xy 156.05221 139.89246) (xy 156.25707 139.89246) (xy 156.25707 139.90065) (xy 156.25707 139.90885)
			(xy 156.25707 139.91704) (xy 156.25707 139.92524) (xy 156.25707 139.93343) (xy 156.25707 139.94163)
			(xy 156.25707 139.94982) (xy 156.25707 139.95802) (xy 156.25707 139.96621) (xy 156.25707 139.9744)
			(xy 156.25707 139.9826) (xy 156.25707 139.99079) (xy 156.25707 139.99899) (xy 156.25707 140.00718)
			(xy 156.25707 140.01538) (xy 156.25707 140.02357) (xy 156.25707 140.03176) (xy 156.25707 140.03996)
			(xy 156.25707 140.04815) (xy 156.25707 140.05635) (xy 156.25707 140.06454) (xy 156.25707 140.07274)
			(xy 156.25707 140.08093) (xy 156.25707 140.08913) (xy 156.25707 140.09732) (xy 156.25707 140.10552)
			(xy 156.25707 140.11371) (xy 156.25707 140.1219) (xy 156.25707 140.1301) (xy 156.25707 140.1383)
			(xy 156.25707 140.14649) (xy 156.25707 140.15468) (xy 156.25707 140.16288) (xy 156.25707 140.17107)
			(xy 156.25707 140.17927) (xy 156.25707 140.18746) (xy 156.25707 140.19565) (xy 156.25707 140.20385)
			(xy 156.25707 140.21204) (xy 156.25707 140.22024) (xy 156.25707 140.22843) (xy 156.25707 140.23663)
			(xy 156.25707 140.24482) (xy 156.25707 140.25302) (xy 156.25707 140.26121) (xy 156.25707 140.2694)
			(xy 156.25707 140.2776) (xy 156.25707 140.28579) (xy 156.25707 140.29399) (xy 156.25707 140.30218)
			(xy 156.25707 140.31038) (xy 156.25707 140.31857) (xy 156.25707 140.32677) (xy 156.25707 140.33496)
			(xy 156.25707 140.34316) (xy 156.25707 140.35135) (xy 156.25707 140.35954) (xy 156.25707 140.36774)
			(xy 156.25707 140.37593) (xy 156.25707 140.38413) (xy 156.25707 140.39232) (xy 156.25707 140.40052)
			(xy 156.25707 140.40871) (xy 156.25707 140.41691) (xy 156.25707 140.4251) (xy 156.25707 140.4333)
			(xy 156.25707 140.44149) (xy 156.25707 140.44969) (xy 156.25707 140.45788) (xy 156.25707 140.46607)
			(xy 156.25707 140.47427) (xy 156.25707 140.48246) (xy 156.25707 140.49066) (xy 156.25707 140.49885)
			(xy 156.25707 140.50704) (xy 156.25707 140.51524) (xy 156.25707 140.52344) (xy 156.25707 140.53163)
			(xy 156.25707 140.53982) (xy 156.25707 140.54802) (xy 156.25707 140.55621) (xy 156.25707 140.56441)
			(xy 156.25707 140.5726) (xy 156.25707 140.5808) (xy 156.25707 140.58899) (xy 156.25707 140.59718)
			(xy 156.25707 140.60538) (xy 156.25707 140.61357) (xy 156.25707 140.62177) (xy 156.25707 140.62996)
			(xy 156.25707 140.63816) (xy 156.25707 140.64635) (xy 156.25707 140.65455) (xy 156.25707 140.66274)
			(xy 156.25707 140.67094) (xy 156.25707 140.67913) (xy 156.25707 140.68732) (xy 156.25707 140.69552)
			(xy 156.25707 140.70371) (xy 156.25707 140.71191) (xy 156.25707 140.7201) (xy 156.25707 140.7283)
			(xy 156.25707 140.73649) (xy 156.25707 140.74469) (xy 156.25707 140.75288) (xy 156.25707 140.76108)
			(xy 156.25707 140.76927) (xy 156.25707 140.77746) (xy 156.25707 140.78566) (xy 156.25707 140.79385)
			(xy 156.25707 140.80205) (xy 156.25707 140.81024) (xy 156.25707 140.81844) (xy 156.25707 140.82663)
			(xy 156.25707 140.83482) (xy 156.25707 140.84302) (xy 156.25707 140.85121) (xy 156.25707 140.85941)
			(xy 156.25707 140.86761) (xy 156.25707 140.8758) (xy 156.25707 140.88399) (xy 156.25707 140.89219)
			(xy 156.25707 140.90038) (xy 156.25707 140.90858) (xy 156.25707 140.91677) (xy 156.25707 140.92496)
			(xy 156.25707 140.93316) (xy 156.25707 140.94135) (xy 156.25707 140.94955) (xy 156.25707 140.95774)
			(xy 156.25707 140.96594) (xy 156.25707 140.97413) (xy 156.25707 140.98233) (xy 156.25707 140.99052)
			(xy 156.25707 140.99872) (xy 156.25707 141.00691) (xy 156.25707 141.0151) (xy 156.25707 141.0233)
			(xy 156.25707 141.03149) (xy 156.25707 141.03969) (xy 156.25707 141.04788) (xy 156.25707 141.05608)
			(xy 156.25707 141.06427) (xy 156.25707 141.07247) (xy 156.25707 141.08066) (xy 156.25707 141.08885)
			(xy 156.25707 141.09705) (xy 156.25707 141.10525) (xy 156.25707 141.11344) (xy 156.25707 141.12163)
			(xy 156.25707 141.12983) (xy 156.25707 141.13802) (xy 156.25707 141.14622) (xy 156.25707 141.15441)
			(xy 156.25707 141.16261) (xy 156.25707 141.1708) (xy 156.25707 141.179) (xy 156.25707 141.18719)
			(xy 156.25707 141.19538) (xy 156.25707 141.20358) (xy 156.25707 141.21177) (xy 156.25707 141.21997)
			(xy 156.25707 141.22816) (xy 156.25707 141.23636) (xy 156.25707 141.24455) (xy 156.25707 141.25274)
			(xy 156.25707 141.26094) (xy 156.25707 141.26913) (xy 156.25707 141.27733) (xy 156.25707 141.28552)
			(xy 156.25707 141.29372) (xy 156.25707 141.30191) (xy 156.25707 141.31011) (xy 156.25707 141.3183)
			(xy 156.25707 141.32649) (xy 156.25707 141.33469) (xy 156.25707 141.34289) (xy 156.25707 141.35108)
			(xy 156.25707 141.35927) (xy 156.25707 141.36747) (xy 156.25707 141.37566) (xy 156.25707 141.38386)
			(xy 156.25707 141.39205) (xy 156.25707 141.40025) (xy 156.25707 141.40844) (xy 156.25707 141.41663)
			(xy 156.25707 141.42483) (xy 156.25707 141.43302) (xy 156.25707 141.44122) (xy 156.25707 141.44941)
			(xy 156.25707 141.45761) (xy 156.25707 141.4658) (xy 156.25707 141.474) (xy 156.25707 141.48219)
			(xy 156.25707 141.49039) (xy 156.25707 141.49858) (xy 156.25707 141.50677) (xy 156.25707 141.51497)
			(xy 156.25707 141.52316) (xy 156.25707 141.53136) (xy 156.25707 141.53955) (xy 156.25707 141.54775)
			(xy 156.25707 141.55594) (xy 156.25707 141.56413) (xy 156.25707 141.57233) (xy 156.25707 141.58052)
			(xy 156.25707 141.58872) (xy 156.25707 141.59692) (xy 156.25707 141.60511) (xy 156.25707 141.6133)
			(xy 156.25707 141.6215) (xy 156.26527 141.6215) (xy 156.26527 141.62969) (xy 156.26527 141.63789)
			(xy 156.28166 141.63789) (xy 156.28166 141.64608) (xy 156.68318 141.64608) (xy 156.68318 141.63789)
			(xy 156.69138 141.63789) (xy 156.69138 141.62969) (xy 156.69957 141.62969) (xy 156.69957 141.6215)
			(xy 156.69957 141.6133) (xy 156.70777 141.6133) (xy 156.70777 141.60511) (xy 156.70777 141.59692)
			(xy 156.70777 141.58872) (xy 156.70777 141.58052) (xy 156.70777 141.57233) (xy 156.70777 141.56413)
			(xy 156.70777 141.55594) (xy 156.70777 141.54775) (xy 156.70777 141.53955) (xy 156.70777 141.53136)
			(xy 156.70777 141.52316) (xy 156.70777 141.51497) (xy 156.70777 141.50677) (xy 156.70777 141.49858)
			(xy 156.70777 141.49039) (xy 156.70777 141.48219) (xy 156.70777 141.474) (xy 156.70777 141.4658)
			(xy 156.70777 141.45761) (xy 156.70777 141.44941) (xy 156.70777 141.44122) (xy 156.70777 141.43302)
			(xy 156.70777 141.42483) (xy 156.70777 141.41663) (xy 156.70777 141.40844) (xy 156.70777 141.40025)
			(xy 156.70777 141.39205) (xy 156.70777 141.38386) (xy 156.70777 141.37566) (xy 156.70777 141.36747)
			(xy 156.70777 141.35927) (xy 156.70777 141.35108) (xy 156.70777 141.34289) (xy 156.70777 141.33469)
			(xy 156.70777 141.32649) (xy 156.70777 141.3183) (xy 156.70777 141.31011) (xy 156.70777 141.30191)
			(xy 156.70777 141.29372) (xy 156.70777 141.28552) (xy 156.70777 141.27733) (xy 156.70777 141.26913)
			(xy 156.70777 141.26094) (xy 156.70777 141.25274) (xy 156.70777 141.24455) (xy 156.70777 141.23636)
			(xy 156.70777 141.22816) (xy 156.70777 141.21997) (xy 156.70777 141.21177) (xy 156.70777 141.20358)
			(xy 156.70777 141.19538) (xy 156.70777 141.18719) (xy 156.70777 141.179) (xy 156.70777 141.1708)
			(xy 156.70777 141.16261) (xy 156.70777 141.15441) (xy 156.70777 141.14622) (xy 156.70777 141.13802)
			(xy 156.70777 141.12983) (xy 156.70777 141.12163) (xy 156.70777 141.11344) (xy 156.70777 141.10525)
			(xy 156.70777 141.09705) (xy 156.70777 141.08885) (xy 156.70777 141.08066) (xy 156.70777 141.07247)
			(xy 156.70777 141.06427) (xy 156.70777 141.05608) (xy 156.70777 141.04788) (xy 156.70777 141.03969)
			(xy 156.70777 141.03149) (xy 156.70777 141.0233) (xy 156.70777 141.0151) (xy 156.70777 141.00691)
			(xy 156.70777 140.99872) (xy 156.70777 140.99052) (xy 156.70777 140.98233) (xy 156.70777 140.97413)
			(xy 156.70777 140.96594) (xy 156.70777 140.95774) (xy 156.70777 140.94955) (xy 156.70777 140.94135)
			(xy 156.70777 140.93316) (xy 156.70777 140.92496) (xy 156.70777 140.91677) (xy 156.70777 140.90858)
			(xy 156.70777 140.90038) (xy 156.70777 140.89219) (xy 156.70777 140.88399) (xy 156.70777 140.8758)
			(xy 156.70777 140.86761) (xy 156.70777 140.85941) (xy 156.70777 140.85121) (xy 156.70777 140.84302)
			(xy 156.70777 140.83482) (xy 156.70777 140.82663) (xy 156.70777 140.81844) (xy 156.70777 140.81024)
			(xy 156.70777 140.80205) (xy 156.70777 140.79385) (xy 156.70777 140.78566) (xy 156.70777 140.77746)
			(xy 156.70777 140.76927) (xy 156.70777 140.76108) (xy 156.70777 140.75288) (xy 156.70777 140.74469)
			(xy 156.70777 140.73649) (xy 156.70777 140.7283) (xy 156.70777 140.7201) (xy 156.70777 140.71191)
			(xy 156.70777 140.70371) (xy 156.70777 140.69552) (xy 156.70777 140.68732) (xy 156.70777 140.67913)
			(xy 156.70777 140.67094) (xy 156.70777 140.66274) (xy 156.70777 140.65455) (xy 156.70777 140.64635)
			(xy 156.70777 140.63816) (xy 156.70777 140.62996) (xy 156.70777 140.62177) (xy 156.70777 140.61357)
			(xy 156.70777 140.60538) (xy 156.70777 140.59718) (xy 156.70777 140.58899) (xy 156.70777 140.5808)
			(xy 156.70777 140.5726) (xy 156.70777 140.56441) (xy 156.70777 140.55621) (xy 156.70777 140.54802)
			(xy 156.70777 140.53982) (xy 156.70777 140.53163) (xy 156.70777 140.52344) (xy 156.70777 140.51524)
			(xy 156.70777 140.50704) (xy 156.70777 140.49885) (xy 156.70777 140.49066) (xy 156.70777 140.48246)
			(xy 156.70777 140.47427) (xy 156.70777 140.46607) (xy 156.70777 140.45788) (xy 156.70777 140.44969)
			(xy 156.70777 140.44149) (xy 156.70777 140.4333) (xy 156.70777 140.4251) (xy 156.70777 140.41691)
			(xy 156.70777 140.40871) (xy 156.70777 140.40052) (xy 156.70777 140.39232) (xy 156.70777 140.38413)
			(xy 156.70777 140.37593) (xy 156.70777 140.36774) (xy 156.70777 140.35954) (xy 156.70777 140.35135)
			(xy 156.70777 140.34316) (xy 156.70777 140.33496) (xy 156.70777 140.32677) (xy 156.70777 140.31857)
			(xy 156.70777 140.31038) (xy 156.70777 140.30218) (xy 156.98638 140.30218) (xy 156.98638 140.31038)
			(xy 156.98638 140.31857) (xy 156.98638 140.32677) (xy 156.98638 140.33496) (xy 156.98638 140.34316)
			(xy 156.98638 140.35135) (xy 156.98638 140.35954) (xy 156.98638 140.36774) (xy 156.98638 140.37593)
			(xy 156.98638 140.38413) (xy 156.98638 140.39232) (xy 156.98638 140.40052) (xy 156.98638 140.40871)
			(xy 156.98638 140.41691) (xy 156.98638 140.4251) (xy 156.98638 140.4333) (xy 156.98638 140.44149)
			(xy 156.98638 140.44969) (xy 156.98638 140.45788) (xy 156.98638 140.46607) (xy 156.98638 140.47427)
			(xy 156.98638 140.48246) (xy 156.98638 140.49066) (xy 156.98638 140.49885) (xy 156.98638 140.50704)
			(xy 156.98638 140.51524) (xy 156.98638 140.52344) (xy 156.98638 140.53163) (xy 156.98638 140.53982)
			(xy 156.98638 140.54802) (xy 156.98638 140.55621) (xy 156.98638 140.56441) (xy 156.98638 140.5726)
			(xy 156.98638 140.5808) (xy 156.98638 140.58899) (xy 156.98638 140.59718) (xy 156.98638 140.60538)
			(xy 156.98638 140.61357) (xy 156.98638 140.62177) (xy 156.98638 140.62996) (xy 156.98638 140.63816)
			(xy 156.98638 140.64635) (xy 156.98638 140.65455) (xy 156.98638 140.66274) (xy 156.98638 140.67094)
			(xy 156.98638 140.67913) (xy 156.98638 140.68732) (xy 156.98638 140.69552) (xy 156.98638 140.70371)
			(xy 156.98638 140.71191) (xy 156.98638 140.7201) (xy 156.98638 140.7283) (xy 156.98638 140.73649)
			(xy 156.98638 140.74469) (xy 156.98638 140.75288) (xy 156.98638 140.76108) (xy 156.98638 140.76927)
			(xy 156.98638 140.77746) (xy 156.98638 140.78566) (xy 156.98638 140.79385) (xy 156.98638 140.80205)
			(xy 156.98638 140.81024) (xy 156.98638 140.81844) (xy 156.98638 140.82663) (xy 156.98638 140.83482)
			(xy 156.98638 140.84302) (xy 156.98638 140.85121) (xy 156.98638 140.85941) (xy 156.98638 140.86761)
			(xy 156.98638 140.8758) (xy 156.98638 140.88399) (xy 156.98638 140.89219) (xy 156.98638 140.90038)
			(xy 156.98638 140.90858) (xy 156.98638 140.91677) (xy 156.98638 140.92496) (xy 156.98638 140.93316)
			(xy 156.98638 140.94135) (xy 156.98638 140.94955) (xy 156.98638 140.95774) (xy 156.98638 140.96594)
			(xy 156.98638 140.97413) (xy 156.98638 140.98233) (xy 156.98638 140.99052) (xy 156.98638 140.99872)
			(xy 156.98638 141.00691) (xy 156.98638 141.0151) (xy 156.98638 141.0233) (xy 156.98638 141.03149)
			(xy 156.98638 141.03969) (xy 156.98638 141.04788) (xy 156.98638 141.05608) (xy 156.98638 141.06427)
			(xy 156.98638 141.07247) (xy 156.98638 141.08066) (xy 156.98638 141.08885) (xy 156.98638 141.09705)
			(xy 156.98638 141.10525) (xy 156.98638 141.11344) (xy 156.98638 141.12163) (xy 156.98638 141.12983)
			(xy 156.98638 141.13802) (xy 156.98638 141.14622) (xy 156.98638 141.15441) (xy 156.98638 141.16261)
			(xy 156.98638 141.1708) (xy 156.98638 141.179) (xy 156.98638 141.18719) (xy 156.98638 141.19538)
			(xy 156.98638 141.20358) (xy 156.98638 141.21177) (xy 156.98638 141.21997) (xy 156.98638 141.22816)
			(xy 156.98638 141.23636) (xy 156.98638 141.24455) (xy 156.98638 141.25274) (xy 156.98638 141.26094)
			(xy 156.98638 141.26913) (xy 156.98638 141.27733) (xy 156.98638 141.28552) (xy 156.98638 141.29372)
			(xy 156.98638 141.30191) (xy 156.98638 141.31011) (xy 156.98638 141.3183) (xy 156.98638 141.32649)
			(xy 156.98638 141.33469) (xy 156.98638 141.34289) (xy 156.98638 141.35108) (xy 156.98638 141.35927)
			(xy 156.98638 141.36747) (xy 156.98638 141.37566) (xy 156.98638 141.38386) (xy 156.98638 141.39205)
			(xy 156.98638 141.40025) (xy 156.98638 141.40844) (xy 156.98638 141.41663) (xy 156.98638 141.42483)
			(xy 156.98638 141.43302) (xy 156.98638 141.44122) (xy 156.98638 141.44941) (xy 156.98638 141.45761)
			(xy 156.98638 141.4658) (xy 156.98638 141.474) (xy 156.98638 141.48219) (xy 156.98638 141.49039)
			(xy 156.98638 141.49858) (xy 156.98638 141.50677) (xy 156.98638 141.51497) (xy 156.98638 141.52316)
			(xy 156.98638 141.53136) (xy 156.98638 141.53955) (xy 156.98638 141.54775) (xy 156.98638 141.55594)
			(xy 156.98638 141.56413) (xy 156.98638 141.57233) (xy 156.98638 141.58052) (xy 156.98638 141.58872)
			(xy 156.98638 141.59692) (xy 156.98638 141.60511) (xy 156.98638 141.6133) (xy 156.99457 141.6133)
			(xy 156.99457 141.6215) (xy 156.99457 141.62969) (xy 157.00277 141.62969) (xy 157.00277 141.63789)
			(xy 157.01916 141.63789) (xy 157.01916 141.64608) (xy 157.37972 141.64608) (xy 157.37972 141.63789)
			(xy 157.38791 141.63789) (xy 157.38791 141.62969) (xy 157.39611 141.62969) (xy 157.39611 141.6215)
			(xy 157.4043 141.6215) (xy 157.4043 141.6133) (xy 157.4043 141.60511) (xy 157.4043 141.59692) (xy 157.4043 141.58872)
			(xy 157.4043 141.58052) (xy 157.4043 141.57233) (xy 157.4043 141.56413) (xy 157.4043 141.55594) (xy 157.4043 141.54775)
			(xy 157.4043 141.53955) (xy 157.4043 141.53136) (xy 157.4043 141.52316) (xy 157.4043 141.51497) (xy 157.4043 141.50677)
			(xy 157.4043 141.49858) (xy 157.4043 141.49039) (xy 157.4043 141.48219) (xy 157.4043 141.474) (xy 157.4043 141.4658)
			(xy 157.4043 141.45761) (xy 157.4043 141.44941) (xy 157.4043 141.44122) (xy 157.4043 141.43302) (xy 157.4043 141.42483)
			(xy 157.4043 141.41663) (xy 157.4043 141.40844) (xy 157.4043 141.40025) (xy 157.4043 141.39205) (xy 157.4043 141.38386)
			(xy 157.4043 141.37566) (xy 157.4043 141.36747) (xy 157.4043 141.35927) (xy 157.4043 141.35108) (xy 157.4043 141.34289)
			(xy 157.4043 141.33469) (xy 157.4043 141.32649) (xy 157.4043 141.3183) (xy 157.4043 141.31011) (xy 157.4043 141.30191)
			(xy 157.4043 141.29372) (xy 157.4043 141.28552) (xy 157.4043 141.27733) (xy 157.4043 141.26913) (xy 157.4043 141.26094)
			(xy 157.4043 141.25274) (xy 157.4043 141.24455) (xy 157.4043 141.23636) (xy 157.4043 141.22816) (xy 157.4043 141.21997)
			(xy 157.4043 141.21177) (xy 157.4043 141.20358) (xy 157.4043 141.19538) (xy 157.4043 141.18719) (xy 157.4043 141.179)
			(xy 157.4043 141.1708) (xy 157.4043 141.16261) (xy 157.4043 141.15441) (xy 157.4043 141.14622) (xy 157.4043 141.13802)
			(xy 157.4043 141.12983) (xy 157.4043 141.12163) (xy 157.4043 141.11344) (xy 157.4043 141.10525) (xy 157.4043 141.09705)
			(xy 157.4043 141.08885) (xy 157.4043 141.08066) (xy 157.4043 141.07247) (xy 157.4043 141.06427) (xy 157.4043 141.05608)
			(xy 157.4043 141.04788) (xy 157.4043 141.03969) (xy 157.4043 141.03149) (xy 157.4043 141.0233) (xy 157.4043 141.0151)
			(xy 157.4043 141.00691) (xy 157.4043 140.99872) (xy 157.4043 140.99052) (xy 157.4043 140.98233) (xy 157.4043 140.97413)
			(xy 157.4043 140.96594) (xy 157.4043 140.95774) (xy 157.4043 140.94955) (xy 157.4043 140.94135) (xy 157.4043 140.93316)
			(xy 157.4043 140.92496) (xy 157.4043 140.91677) (xy 157.4043 140.90858) (xy 157.4043 140.90038) (xy 157.4043 140.89219)
			(xy 157.4043 140.88399) (xy 157.4043 140.8758) (xy 157.4043 140.86761) (xy 157.4043 140.85941) (xy 157.4043 140.85121)
			(xy 157.4043 140.84302) (xy 157.4043 140.83482) (xy 157.4043 140.82663) (xy 157.4043 140.81844) (xy 157.4043 140.81024)
			(xy 157.4043 140.80205) (xy 157.4043 140.79385) (xy 157.4043 140.78566) (xy 157.4043 140.77746) (xy 157.4043 140.76927)
			(xy 157.4043 140.76108) (xy 157.4043 140.75288) (xy 157.4043 140.74469) (xy 157.4043 140.73649) (xy 157.4043 140.7283)
			(xy 157.4043 140.7201) (xy 157.4043 140.71191) (xy 157.4043 140.70371) (xy 157.4043 140.69552) (xy 157.4043 140.68732)
			(xy 157.4043 140.67913) (xy 157.4043 140.67094) (xy 157.4043 140.66274) (xy 157.4043 140.65455) (xy 157.4043 140.64635)
			(xy 157.4043 140.63816) (xy 157.4043 140.62996) (xy 157.4043 140.62177) (xy 157.4043 140.61357) (xy 157.4043 140.60538)
			(xy 157.4043 140.59718) (xy 157.4043 140.58899) (xy 157.4043 140.5808) (xy 157.4043 140.5726) (xy 157.4043 140.56441)
			(xy 157.4043 140.55621) (xy 157.4043 140.54802) (xy 157.4043 140.53982) (xy 157.4043 140.53163) (xy 157.4043 140.52344)
			(xy 157.4043 140.51524) (xy 157.4043 140.50704) (xy 157.4043 140.49885) (xy 157.4043 140.49066) (xy 157.4043 140.48246)
			(xy 157.4043 140.47427) (xy 157.4043 140.46607) (xy 157.4043 140.45788) (xy 157.4043 140.44969) (xy 157.4043 140.44149)
			(xy 157.4043 140.4333) (xy 157.4043 140.4251) (xy 157.4043 140.41691) (xy 157.4043 140.40871) (xy 157.4043 140.40052)
			(xy 157.4043 140.39232) (xy 157.4043 140.38413) (xy 157.4043 140.37593) (xy 157.4043 140.36774) (xy 157.4043 140.35954)
			(xy 157.4043 140.35135) (xy 157.4043 140.34316) (xy 157.4043 140.33496) (xy 157.4043 140.32677) (xy 157.4043 140.31857)
			(xy 157.4043 140.31038) (xy 157.4043 140.30218) (xy 157.51902 140.30218) (xy 157.51902 140.29399)
			(xy 157.52722 140.29399) (xy 157.52722 140.30218) (xy 157.5518 140.30218) (xy 157.5518 140.29399)
			(xy 157.5518 140.28579) (xy 157.5518 140.2776) (xy 157.5518 140.2694) (xy 157.5518 140.26121) (xy 157.5518 140.25302)
			(xy 157.5518 140.24482) (xy 157.5518 140.23663) (xy 157.5518 140.22843) (xy 157.5518 140.22024) (xy 157.5518 140.21204)
			(xy 157.5518 140.20385) (xy 157.5518 140.19565) (xy 157.5518 140.18746) (xy 157.5518 140.17927) (xy 157.5518 140.17107)
			(xy 157.5518 140.16288) (xy 157.5518 140.15468) (xy 157.5518 140.14649) (xy 157.5518 140.1383) (xy 157.5518 140.1301)
			(xy 157.5518 140.1219) (xy 157.5518 140.11371) (xy 157.5518 140.10552) (xy 157.5518 140.09732) (xy 157.5518 140.08913)
			(xy 157.5518 140.08093) (xy 157.5518 140.07274) (xy 157.5518 140.06454) (xy 157.5518 140.05635) (xy 157.5518 140.04815)
			(xy 157.5518 140.03996) (xy 157.5518 140.03176) (xy 157.5518 140.02357) (xy 157.5518 140.01538) (xy 157.5518 140.00718)
			(xy 157.5518 139.99899) (xy 157.5518 139.99079) (xy 157.5518 139.9826) (xy 157.5518 139.9744) (xy 157.5518 139.96621)
			(xy 157.5518 139.95802) (xy 157.5518 139.94982) (xy 157.5518 139.94163) (xy 157.5518 139.93343) (xy 157.5518 139.92524)
			(xy 157.5518 139.91704) (xy 157.5518 139.90885) (xy 157.5518 139.90065) (xy 157.5518 139.89246) (xy 157.5518 139.88426)
			(xy 157.5518 139.87607) (xy 157.5518 139.86787) (xy 157.5518 139.85968) (xy 156.29804 139.85968)
			(xy 156.29804 139.86787) (xy 156.27346 139.86787) (xy 156.27346 139.87607) (xy 156.26527 139.87607)
			(xy 156.26527 139.88426) (xy 156.26527 139.89246) (xy 156.25707 139.89246) (xy 156.05221 139.89246)
			(xy 156.05221 139.88426) (xy 156.04401 139.88426) (xy 156.04401 139.87607) (xy 156.03582 139.87607)
			(xy 156.03582 139.86787) (xy 156.01943 139.86787) (xy 156.01943 139.85968) (xy 155.64249 139.85968)
			(xy 155.64249 139.86787) (xy 155.6179 139.86787) (xy 155.6179 139.87607) (xy 155.6179 139.88426)
			(xy 155.6097 139.88426) (xy 155.6097 139.89246) (xy 155.6097 139.90065) (xy 155.60151 139.90065)
			(xy 155.49498 139.90065) (xy 155.49498 139.89246) (xy 155.49498 139.88426) (xy 155.48679 139.88426)
			(xy 155.48679 139.87607) (xy 155.47859 139.87607) (xy 155.47859 139.86787) (xy 155.46221 139.86787)
			(xy 155.46221 139.85968) (xy 155.44582 139.85968) (xy 155.44582 139.86787) (xy 155.43762 139.86787)
			(xy 155.43762 139.85968) (xy 154.17567 139.85968) (xy 154.17567 139.86787) (xy 154.15109 139.86787)
			(xy 154.15109 139.87607) (xy 154.14289 139.87607) (xy 154.14289 139.88426) (xy 154.14289 139.89246)
			(xy 154.1347 139.89246) (xy 152.90552 139.89246) (xy 152.90552 139.88426) (xy 152.90552 139.87607)
			(xy 152.90552 139.86787) (xy 152.90552 139.85968) (xy 152.90552 139.85149) (xy 152.90552 139.84329)
			(xy 152.90552 139.8351) (xy 152.90552 139.8269) (xy 152.90552 139.81871) (xy 152.90552 139.81051)
			(xy 152.90552 139.80232) (xy 152.90552 139.79413) (xy 152.90552 139.78593) (xy 152.90552 139.77773)
			(xy 152.90552 139.76954) (xy 152.90552 139.76135) (xy 152.90552 139.75315) (xy 152.90552 139.74496)
			(xy 152.90552 139.73676) (xy 152.90552 139.72857) (xy 152.90552 139.72038) (xy 155.49498 139.72038)
			(xy 155.49498 139.72857) (xy 155.62609 139.72857) (xy 155.62609 139.72038) (xy 155.63429 139.72038)
			(xy 155.63429 139.71218) (xy 155.64249 139.71218) (xy 155.64249 139.70398) (xy 155.64249 139.69579)
			(xy 155.65068 139.69579) (xy 155.65068 139.6876) (xy 155.65887 139.6876) (xy 155.65887 139.6794)
			(xy 155.66707 139.6794) (xy 155.66707 139.67121) (xy 155.67526 139.67121) (xy 155.67526 139.66301)
			(xy 155.68346 139.66301) (xy 155.68346 139.65482) (xy 155.69165 139.65482) (xy 155.69165 139.64662)
			(xy 155.69985 139.64662) (xy 155.69985 139.63843) (xy 155.70804 139.63843) (xy 155.70804 139.63023)
			(xy 155.70804 139.62204) (xy 155.71623 139.62204) (xy 155.71623 139.61385) (xy 155.72443 139.61385)
			(xy 155.72443 139.60565) (xy 155.73262 139.60565) (xy 155.73262 139.59746) (xy 155.74082 139.59746)
			(xy 155.74082 139.58926) (xy 155.74901 139.58926) (xy 155.74901 139.58107) (xy 155.75721 139.58107)
			(xy 155.75721 139.57287) (xy 155.7654 139.57287) (xy 155.7654 139.56468) (xy 155.7736 139.56468)
			(xy 155.7736 139.55649) (xy 155.78179 139.55649) (xy 155.78179 139.54829) (xy 155.78999 139.54829)
			(xy 155.78999 139.54009) (xy 155.79818 139.54009) (xy 155.79818 139.5319) (xy 155.80637 139.5319)
			(xy 155.80637 139.52371) (xy 155.81457 139.52371) (xy 155.81457 139.51551) (xy 155.82276 139.51551)
			(xy 155.82276 139.50732) (xy 155.83096 139.50732) (xy 155.83096 139.49912) (xy 155.83915 139.49912)
			(xy 155.83915 139.49093) (xy 155.84735 139.49093) (xy 155.84735 139.48273) (xy 155.85554 139.48273)
			(xy 155.85554 139.47454) (xy 155.86373 139.47454) (xy 155.86373 139.46634) (xy 155.87193 139.46634)
			(xy 155.87193 139.45815) (xy 155.88832 139.45815) (xy 155.88832 139.44996) (xy 155.89651 139.44996)
			(xy 155.89651 139.44176) (xy 155.90471 139.44176) (xy 155.90471 139.43357) (xy 155.9129 139.43357)
			(xy 155.9129 139.42537) (xy 155.9211 139.42537) (xy 155.9211 139.41718) (xy 155.92929 139.41718)
			(xy 155.92929 139.40898) (xy 155.93749 139.40898) (xy 155.93749 139.40079) (xy 155.94568 139.40079)
			(xy 155.94568 139.39259) (xy 155.95388 139.39259) (xy 155.95388 139.3844) (xy 155.97026 139.3844)
			(xy 155.97026 139.37621) (xy 155.97846 139.37621) (xy 155.97846 139.36801) (xy 155.98666 139.36801)
			(xy 155.98666 139.35982) (xy 155.99485 139.35982) (xy 155.99485 139.35162) (xy 156.00304 139.35162)
			(xy 156.00304 139.34342) (xy 156.01943 139.34342) (xy 156.01943 139.33523) (xy 156.02763 139.33523)
			(xy 156.02763 139.32704) (xy 156.03582 139.32704) (xy 156.03582 139.31884) (xy 156.04401 139.31884)
			(xy 156.04401 139.31065) (xy 156.0604 139.31065) (xy 156.0604 139.30245) (xy 156.0686 139.30245)
			(xy 156.0686 139.29426) (xy 156.07679 139.29426) (xy 156.07679 139.28607) (xy 156.08499 139.28607)
			(xy 156.08499 139.27787) (xy 156.10137 139.27787) (xy 156.10137 139.26968) (xy 156.10957 139.26968)
			(xy 156.10957 139.26148) (xy 156.11776 139.26148) (xy 156.11776 139.25329) (xy 156.13415 139.25329)
			(xy 156.13415 139.24509) (xy 156.14235 139.24509) (xy 156.14235 139.2369) (xy 156.15054 139.2369)
			(xy 156.15054 139.22871) (xy 156.16693 139.22871) (xy 156.16693 139.22051) (xy 156.17513 139.22051)
			(xy 156.17513 139.21232) (xy 156.18332 139.21232) (xy 156.18332 139.20412) (xy 156.19971 139.20412)
			(xy 156.19971 139.19593) (xy 156.2079 139.19593) (xy 156.2079 139.18773) (xy 156.22429 139.18773)
			(xy 156.22429 139.17954) (xy 156.23249 139.17954) (xy 156.23249 139.17134) (xy 156.24888 139.17134)
			(xy 156.24888 139.16315) (xy 156.25707 139.16315) (xy 156.25707 139.15495) (xy 156.27346 139.15495)
			(xy 156.27346 139.14676) (xy 156.28166 139.14676) (xy 156.28166 139.13857) (xy 156.29804 139.13857)
			(xy 156.29804 139.13037) (xy 156.30624 139.13037) (xy 156.30624 139.12218) (xy 156.32263 139.12218)
			(xy 156.32263 139.11398) (xy 156.33082 139.11398) (xy 156.33082 139.10579) (xy 156.34721 139.10579)
			(xy 156.34721 139.09759) (xy 156.3636 139.09759) (xy 156.3636 139.0894) (xy 156.3718 139.0894) (xy 156.3718 139.0812)
			(xy 156.38818 139.0812) (xy 156.38818 139.07301) (xy 156.40457 139.07301) (xy 156.40457 139.06481)
			(xy 156.41277 139.06481) (xy 156.41277 139.05662) (xy 156.42916 139.05662) (xy 156.42916 139.04842)
			(xy 156.44554 139.04842) (xy 156.44554 139.04023) (xy 156.45374 139.04023) (xy 156.45374 139.03204)
			(xy 156.47013 139.03204) (xy 156.47013 139.02384) (xy 156.48652 139.02384) (xy 156.48652 139.01565)
			(xy 156.50291 139.01565) (xy 156.50291 139.00745) (xy 156.5193 139.00745) (xy 156.5193 138.99926)
			(xy 156.53568 138.99926) (xy 156.53568 138.99107) (xy 156.55207 138.99107) (xy 156.55207 138.98287)
			(xy 156.56027 138.98287) (xy 156.56027 138.97467) (xy 156.57666 138.97467) (xy 156.57666 138.96648)
			(xy 156.59304 138.96648) (xy 156.59304 138.95829) (xy 156.60944 138.95829) (xy 156.60944 138.95009)
			(xy 156.62582 138.95009) (xy 156.62582 138.9419) (xy 156.65041 138.9419) (xy 156.65041 138.9337)
			(xy 156.6668 138.9337) (xy 156.6668 138.92551) (xy 156.68318 138.92551) (xy 156.68318 138.91731)
			(xy 156.69957 138.91731) (xy 156.69957 138.90912) (xy 156.71596 138.90912) (xy 156.71596 138.90092)
			(xy 156.73235 138.90092) (xy 156.73235 138.89273) (xy 156.75693 138.89273) (xy 156.75693 138.88454)
			(xy 156.77332 138.88454) (xy 156.77332 138.87634) (xy 156.78971 138.87634) (xy 156.78971 138.86815)
			(xy 156.8143 138.86815) (xy 156.8143 138.85995) (xy 156.83068 138.85995) (xy 156.83068 138.85176)
			(xy 156.85527 138.85176) (xy 156.85527 138.84356) (xy 156.87985 138.84356) (xy 156.87985 138.83537)
			(xy 156.89624 138.83537) (xy 156.89624 138.82718) (xy 156.92083 138.82718) (xy 156.92083 138.81898)
			(xy 156.94541 138.81898) (xy 156.94541 138.81078) (xy 156.96999 138.81078) (xy 156.96999 138.80259)
			(xy 156.98638 138.80259) (xy 156.98638 138.7944) (xy 157.01916 138.7944) (xy 157.01916 138.7862)
			(xy 157.04374 138.7862) (xy 157.04374 138.77801) (xy 157.06832 138.77801) (xy 157.06832 138.76981)
			(xy 157.09291 138.76981) (xy 157.09291 138.76162) (xy 157.12569 138.76162) (xy 157.12569 138.75342)
			(xy 157.15027 138.75342) (xy 157.15027 138.74523) (xy 157.18305 138.74523) (xy 157.18305 138.73704)
			(xy 157.21583 138.73704) (xy 157.21583 138.72884) (xy 157.2486 138.72884) (xy 157.2486 138.72065)
			(xy 157.28138 138.72065) (xy 157.28138 138.71245) (xy 157.32235 138.71245) (xy 157.32235 138.70426)
			(xy 157.36333 138.70426) (xy 157.36333 138.69607) (xy 157.39611 138.69607) (xy 157.39611 138.68787)
			(xy 157.45347 138.68787) (xy 157.45347 138.67967) (xy 157.50263 138.67967) (xy 157.50263 138.67148)
			(xy 157.55999 138.67148) (xy 157.55999 138.66328) (xy 157.62555 138.66328) (xy 157.62555 138.65509)
			(xy 157.71569 138.65509) (xy 157.71569 138.6469) (xy 157.86319 138.6469) (xy 157.86319 138.6387)
			(xy 158.06805 138.6387) (xy 158.06805 138.6469) (xy 158.07625 138.6469) (xy 158.07625 138.6387) (xy 158.08444 138.6387)
			(xy 158.08444 138.6469) (xy 158.21555 138.6469) (xy 158.21555 138.65509) (xy 158.3057 138.65509)
			(xy 158.3057 138.66328) (xy 158.37944 138.66328) (xy 158.37944 138.67148) (xy 158.42861 138.67148)
			(xy 158.42861 138.67967) (xy 158.47778 138.67967) (xy 158.47778 138.68787) (xy 158.52694 138.68787)
			(xy 158.52694 138.69607) (xy 158.56792 138.69607) (xy 158.56792 138.70426) (xy 158.60889 138.70426)
			(xy 158.60889 138.71245) (xy 158.64986 138.71245) (xy 158.64986 138.72065) (xy 158.68264 138.72065)
			(xy 158.68264 138.72884) (xy 158.71542 138.72884) (xy 158.71542 138.73704) (xy 158.7482 138.73704)
			(xy 158.7482 138.74523) (xy 158.78098 138.74523) (xy 158.78098 138.75342) (xy 158.80556 138.75342)
			(xy 158.80556 138.76162) (xy 158.83834 138.76162) (xy 158.83834 138.76981) (xy 158.86292 138.76981)
			(xy 158.86292 138.77801) (xy 158.88751 138.77801) (xy 158.88751 138.7862) (xy 158.91209 138.7862)
			(xy 158.91209 138.7944) (xy 158.93667 138.7944) (xy 158.93667 138.80259) (xy 158.96126 138.80259)
			(xy 158.96126 138.81078) (xy 158.98584 138.81078) (xy 158.98584 138.81898) (xy 159.01042 138.81898)
			(xy 159.01042 138.82718) (xy 159.035 138.82718) (xy 159.035 138.83537) (xy 159.05139 138.83537) (xy 159.05139 138.84356)
			(xy 159.07598 138.84356) (xy 159.07598 138.85176) (xy 159.09237 138.85176) (xy 159.09237 138.85995)
			(xy 159.11695 138.85995) (xy 159.11695 138.86815) (xy 159.13334 138.86815) (xy 159.13334 138.87634)
			(xy 159.15792 138.87634) (xy 159.15792 138.88454) (xy 159.17431 138.88454) (xy 159.17431 138.89273)
			(xy 159.1907 138.89273) (xy 159.1907 138.90092) (xy 159.21528 138.90092) (xy 159.21528 138.90912)
			(xy 159.23167 138.90912) (xy 159.23167 138.91731) (xy 159.24806 138.91731) (xy 159.24806 138.92551)
			(xy 159.26445 138.92551) (xy 159.26445 138.9337) (xy 159.28084 138.9337) (xy 159.28084 138.9419)
			(xy 159.30542 138.9419) (xy 159.30542 138.95009) (xy 159.32181 138.95009) (xy 159.32181 138.95829)
			(xy 159.33001 138.95829) (xy 159.33001 138.96648) (xy 159.34639 138.96648) (xy 159.34639 138.97467)
			(xy 159.36278 138.97467) (xy 159.36278 138.98287) (xy 159.37918 138.98287) (xy 159.37918 138.99107)
			(xy 159.39556 138.99107) (xy 159.39556 138.99926) (xy 159.41195 138.99926) (xy 159.41195 139.00745)
			(xy 159.42834 139.00745) (xy 159.42834 139.01565) (xy 159.44473 139.01565) (xy 159.44473 139.02384)
			(xy 159.46112 139.02384) (xy 159.46112 139.03204) (xy 159.46931 139.03204) (xy 159.46931 139.04023)
			(xy 159.4857 139.04023) (xy 159.4857 139.04842) (xy 159.50209 139.04842) (xy 159.50209 139.05662)
			(xy 159.51848 139.05662) (xy 159.51848 139.06481) (xy 159.52667 139.06481) (xy 159.52667 139.07301)
			(xy 159.54306 139.07301) (xy 159.54306 139.0812) (xy 159.55945 139.0812) (xy 159.55945 139.0894)
			(xy 159.56765 139.0894) (xy 159.56765 139.09759) (xy 159.58403 139.09759) (xy 159.58403 139.10579)
			(xy 159.60042 139.10579) (xy 159.60042 139.11398) (xy 159.60862 139.11398) (xy 159.60862 139.12218)
			(xy 159.62501 139.12218) (xy 159.62501 139.13037) (xy 159.6332 139.13037) (xy 159.6332 139.13857)
			(xy 159.64959 139.13857) (xy 159.64959 139.14676) (xy 159.65779 139.14676) (xy 159.65779 139.15495)
			(xy 159.67417 139.15495) (xy 159.67417 139.16315) (xy 159.68237 139.16315) (xy 159.68237 139.17134)
			(xy 159.69876 139.17134) (xy 159.69876 139.17954) (xy 159.70695 139.17954) (xy 159.70695 139.18773)
			(xy 159.72334 139.18773) (xy 159.72334 139.19593) (xy 159.73153 139.19593) (xy 159.73153 139.20412)
			(xy 159.73973 139.20412) (xy 159.73973 139.21232) (xy 159.75612 139.21232) (xy 159.75612 139.22051)
			(xy 159.76431 139.22051) (xy 159.76431 139.22871) (xy 159.7807 139.22871) (xy 159.7807 139.2369)
			(xy 159.7889 139.2369) (xy 159.7889 139.24509) (xy 159.79709 139.24509) (xy 159.79709 139.25329)
			(xy 159.81348 139.25329) (xy 159.81348 139.26148) (xy 159.82168 139.26148) (xy 159.82168 139.26968)
			(xy 159.82987 139.26968) (xy 159.82987 139.27787) (xy 159.84626 139.27787) (xy 159.84626 139.28607)
			(xy 159.85445 139.28607) (xy 159.85445 139.29426) (xy 159.86265 139.29426) (xy 159.86265 139.30245)
			(xy 159.87084 139.30245) (xy 159.87084 139.31065) (xy 159.88723 139.31065) (xy 159.88723 139.31884)
			(xy 159.89543 139.31884) (xy 159.89543 139.32704) (xy 159.90362 139.32704) (xy 159.90362 139.33523)
			(xy 159.91182 139.33523) (xy 159.91182 139.34342) (xy 159.9282 139.34342) (xy 159.9282 139.35162)
			(xy 159.9364 139.35162) (xy 159.9364 139.35982) (xy 159.94459 139.35982) (xy 159.94459 139.36801)
			(xy 159.95279 139.36801) (xy 159.95279 139.37621) (xy 159.96098 139.37621) (xy 159.96098 139.3844)
			(xy 159.96917 139.3844) (xy 159.96917 139.39259) (xy 159.98557 139.39259) (xy 159.98557 139.40079)
			(xy 159.99376 139.40079) (xy 159.99376 139.40898) (xy 160.00195 139.40898) (xy 160.00195 139.41718)
			(xy 160.01015 139.41718) (xy 160.01015 139.42537) (xy 160.01834 139.42537) (xy 160.01834 139.43357)
			(xy 160.02654 139.43357) (xy 160.02654 139.44176) (xy 160.03473 139.44176) (xy 160.03473 139.44996)
			(xy 160.04293 139.44996) (xy 160.04293 139.45815) (xy 160.05112 139.45815) (xy 160.05112 139.46634)
			(xy 160.06751 139.46634) (xy 160.06751 139.47454) (xy 160.0757 139.47454) (xy 160.0757 139.48273)
			(xy 160.0839 139.48273) (xy 160.0839 139.49093) (xy 160.09209 139.49093) (xy 160.09209 139.49912)
			(xy 160.10029 139.49912) (xy 160.10029 139.50732) (xy 160.10848 139.50732) (xy 160.10848 139.51551)
			(xy 160.11668 139.51551) (xy 160.11668 139.52371) (xy 160.12487 139.52371) (xy 160.12487 139.5319)
			(xy 160.13307 139.5319) (xy 160.13307 139.54009) (xy 160.14126 139.54009) (xy 160.14126 139.54829)
			(xy 160.14946 139.54829) (xy 160.14946 139.55649) (xy 160.15765 139.55649) (xy 160.15765 139.56468)
			(xy 160.16584 139.56468) (xy 160.16584 139.57287) (xy 160.17404 139.57287) (xy 160.17404 139.58107)
			(xy 160.18223 139.58107) (xy 160.18223 139.58926) (xy 160.19043 139.58926) (xy 160.19043 139.59746)
			(xy 160.19862 139.59746) (xy 160.19862 139.60565) (xy 160.20682 139.60565) (xy 160.20682 139.61385)
			(xy 160.20682 139.62204) (xy 160.21501 139.62204) (xy 160.21501 139.63023) (xy 160.22321 139.63023)
			(xy 160.22321 139.63843) (xy 160.2314 139.63843) (xy 160.2314 139.64662) (xy 160.2396 139.64662)
			(xy 160.2396 139.65482) (xy 160.24779 139.65482) (xy 160.24779 139.66301) (xy 160.25598 139.66301)
			(xy 160.25598 139.67121) (xy 160.26418 139.67121) (xy 160.26418 139.6794) (xy 160.27237 139.6794)
			(xy 160.27237 139.6876) (xy 160.28057 139.6876) (xy 160.28057 139.69579) (xy 160.28057 139.70398)
			(xy 160.28876 139.70398) (xy 160.28876 139.71218) (xy 160.29696 139.71218) (xy 160.29696 139.72038)
			(xy 160.30515 139.72038) (xy 160.30515 139.72857) (xy 160.31334 139.72857) (xy 160.31334 139.73676)
			(xy 160.32154 139.73676) (xy 160.32154 139.74496) (xy 160.32974 139.74496) (xy 160.32974 139.75315)
			(xy 160.32974 139.76135) (xy 160.33793 139.76135) (xy 160.33793 139.76954) (xy 160.34613 139.76954)
			(xy 160.34613 139.77773) (xy 160.35432 139.77773) (xy 160.35432 139.78593) (xy 160.36251 139.78593)
			(xy 160.36251 139.79413) (xy 160.36251 139.80232) (xy 160.37071 139.80232) (xy 160.37071 139.81051)
			(xy 160.3789 139.81051) (xy 160.3789 139.81871) (xy 160.3871 139.81871) (xy 160.3871 139.8269) (xy 160.39529 139.8269)
			(xy 160.39529 139.8351) (xy 160.39529 139.84329) (xy 160.40349 139.84329) (xy 160.40349 139.85149)
			(xy 160.41168 139.85149) (xy 160.41168 139.85968) (xy 160.41987 139.85968) (xy 160.41987 139.86787)
			(xy 160.41987 139.87607) (xy 160.42807 139.87607) (xy 160.42807 139.88426) (xy 160.43626 139.88426)
			(xy 160.43626 139.89246) (xy 160.44446 139.89246) (xy 160.44446 139.90065) (xy 160.44446 139.90885)
			(xy 160.45265 139.90885) (xy 160.45265 139.91704) (xy 160.46084 139.91704) (xy 160.46084 139.92524)
			(xy 160.46084 139.93343) (xy 160.46904 139.93343) (xy 160.46904 139.94163) (xy 160.47724 139.94163)
			(xy 160.47724 139.94982) (xy 160.48543 139.94982) (xy 160.48543 139.95802) (xy 160.48543 139.96621)
			(xy 160.49362 139.96621) (xy 160.49362 139.9744) (xy 160.50182 139.9744) (xy 160.50182 139.9826)
			(xy 160.50182 139.99079) (xy 160.51001 139.99079) (xy 160.51001 139.99899) (xy 160.51821 139.99899)
			(xy 160.51821 140.00718) (xy 160.51821 140.01538) (xy 160.5264 140.01538) (xy 160.5264 140.02357)
			(xy 160.5346 140.02357) (xy 160.5346 140.03176) (xy 160.5346 140.03996) (xy 160.54279 140.03996)
			(xy 160.54279 140.04815) (xy 160.55098 140.04815) (xy 160.55098 140.05635) (xy 160.55098 140.06454)
			(xy 160.55918 140.06454) (xy 160.55918 140.07274) (xy 160.56737 140.07274) (xy 160.56737 140.08093)
			(xy 160.56737 140.08913) (xy 160.57557 140.08913) (xy 160.57557 140.09732) (xy 160.57557 140.10552)
			(xy 160.58376 140.10552) (xy 160.58376 140.11371) (xy 160.59196 140.11371) (xy 160.59196 140.1219)
			(xy 160.59196 140.1301) (xy 160.60015 140.1301) (xy 160.60015 140.1383) (xy 160.60015 140.14649)
			(xy 160.60835 140.14649) (xy 160.60835 140.15468) (xy 160.61654 140.15468) (xy 160.61654 140.16288)
			(xy 160.61654 140.17107) (xy 160.62474 140.17107) (xy 160.62474 140.17927) (xy 160.62474 140.18746)
			(xy 160.63293 140.18746) (xy 160.63293 140.19565) (xy 160.63293 140.20385) (xy 160.64113 140.20385)
			(xy 160.64113 140.21204) (xy 160.64932 140.21204) (xy 160.64932 140.22024) (xy 160.64932 140.22843)
			(xy 160.65751 140.22843) (xy 160.65751 140.23663) (xy 160.65751 140.24482) (xy 160.66571 140.24482)
			(xy 160.66571 140.25302) (xy 160.66571 140.26121) (xy 160.6739 140.26121) (xy 160.6739 140.2694)
			(xy 160.6739 140.2776) (xy 160.6821 140.2776) (xy 160.6821 140.28579) (xy 160.6821 140.29399) (xy 160.69029 140.29399)
			(xy 160.69029 140.30218) (xy 160.69849 140.30218) (xy 160.69849 140.31038) (xy 160.69849 140.31857)
			(xy 160.70668 140.31857) (xy 160.70668 140.32677) (xy 160.70668 140.33496) (xy 160.71488 140.33496)
			(xy 160.71488 140.34316) (xy 160.71488 140.35135) (xy 160.72307 140.35135) (xy 160.72307 140.35954)
			(xy 160.72307 140.36774) (xy 160.73126 140.36774) (xy 160.73126 140.37593) (xy 160.73126 140.38413)
			(xy 160.73126 140.39232) (xy 160.73946 140.39232) (xy 160.73946 140.40052) (xy 160.73946 140.40871)
			(xy 160.74765 140.40871) (xy 160.74765 140.41691) (xy 160.74765 140.4251) (xy 160.75585 140.4251)
			(xy 160.75585 140.4333) (xy 160.75585 140.44149) (xy 160.76404 140.44149) (xy 160.76404 140.44969)
			(xy 160.76404 140.45788) (xy 160.77224 140.45788) (xy 160.77224 140.46607) (xy 160.77224 140.47427)
			(xy 160.78043 140.47427) (xy 160.78043 140.48246) (xy 160.78043 140.49066) (xy 160.78043 140.49885)
			(xy 160.78863 140.49885) (xy 160.78863 140.50704) (xy 160.78863 140.51524) (xy 160.79682 140.51524)
			(xy 160.79682 140.52344) (xy 160.79682 140.53163) (xy 160.80501 140.53163) (xy 160.80501 140.53982)
			(xy 160.80501 140.54802) (xy 160.80501 140.55621) (xy 160.81321 140.55621) (xy 160.81321 140.56441)
			(xy 160.81321 140.5726) (xy 160.82141 140.5726) (xy 160.82141 140.5808) (xy 160.82141 140.58899)
			(xy 160.82141 140.59718) (xy 160.8296 140.59718) (xy 160.8296 140.60538) (xy 160.8296 140.61357)
			(xy 160.83779 140.61357) (xy 160.83779 140.62177) (xy 160.83779 140.62996) (xy 160.83779 140.63816)
			(xy 160.84599 140.63816) (xy 160.84599 140.64635) (xy 160.84599 140.65455) (xy 160.84599 140.66274)
			(xy 160.85418 140.66274) (xy 160.85418 140.67094) (xy 160.85418 140.67913) (xy 160.85418 140.68732)
			(xy 160.86238 140.68732) (xy 160.86238 140.69552) (xy 160.86238 140.70371) (xy 160.87057 140.70371)
			(xy 160.87057 140.71191) (xy 160.87057 140.7201) (xy 160.87057 140.7283) (xy 160.87877 140.7283)
			(xy 160.87877 140.73649) (xy 160.87877 140.74469) (xy 160.87877 140.75288) (xy 160.88696 140.75288)
			(xy 160.88696 140.76108) (xy 160.88696 140.76927) (xy 160.88696 140.77746) (xy 160.88696 140.78566)
			(xy 160.89515 140.78566) (xy 160.89515 140.79385) (xy 160.89515 140.80205) (xy 160.89515 140.81024)
			(xy 160.90335 140.81024) (xy 160.90335 140.81844) (xy 160.90335 140.82663) (xy 160.90335 140.83482)
			(xy 160.91154 140.83482) (xy 160.91154 140.84302) (xy 160.91154 140.85121) (xy 160.91154 140.85941)
			(xy 160.91154 140.86761) (xy 160.91974 140.86761) (xy 160.91974 140.8758) (xy 160.91974 140.88399)
			(xy 160.91974 140.89219) (xy 160.92793 140.89219) (xy 160.92793 140.90038) (xy 160.92793 140.90858)
			(xy 160.92793 140.91677) (xy 160.92793 140.92496) (xy 160.93613 140.92496) (xy 160.93613 140.93316)
			(xy 160.93613 140.94135) (xy 160.93613 140.94955) (xy 160.93613 140.95774) (xy 160.94432 140.95774)
			(xy 160.94432 140.96594) (xy 160.94432 140.97413) (xy 160.94432 140.98233) (xy 160.94432 140.99052)
			(xy 160.95252 140.99052) (xy 160.95252 140.99872) (xy 160.95252 141.00691) (xy 160.95252 141.0151)
			(xy 160.95252 141.0233) (xy 160.96071 141.0233) (xy 160.96071 141.03149) (xy 160.96071 141.03969)
			(xy 160.96071 141.04788) (xy 160.96071 141.05608) (xy 160.96071 141.06427) (xy 160.9689 141.06427)
			(xy 160.9689 141.07247) (xy 160.9689 141.08066) (xy 160.9689 141.08885) (xy 160.9689 141.09705) (xy 160.9771 141.09705)
			(xy 160.9771 141.10525) (xy 160.9771 141.11344) (xy 160.9771 141.12163) (xy 160.9771 141.12983) (xy 160.9771 141.13802)
			(xy 160.9771 141.14622) (xy 160.98529 141.14622) (xy 160.98529 141.15441) (xy 160.98529 141.16261)
			(xy 160.98529 141.1708) (xy 160.98529 141.179) (xy 160.98529 141.18719) (xy 160.99349 141.18719)
			(xy 160.99349 141.19538) (xy 160.99349 141.20358) (xy 160.99349 141.21177) (xy 160.99349 141.21997)
			(xy 160.99349 141.22816) (xy 160.99349 141.23636) (xy 161.00168 141.23636) (xy 161.00168 141.24455)
			(xy 161.00168 141.25274) (xy 161.00168 141.26094) (xy 161.00168 141.26913) (xy 161.00168 141.27733)
			(xy 161.00168 141.28552) (xy 161.00168 141.29372) (xy 161.00988 141.29372) (xy 161.00988 141.30191)
			(xy 161.00988 141.31011) (xy 161.00988 141.3183) (xy 161.00988 141.32649) (xy 161.00988 141.33469)
			(xy 161.00988 141.34289) (xy 161.00988 141.35108) (xy 161.00988 141.35927) (xy 161.00988 141.36747)
			(xy 161.01807 141.36747) (xy 161.01807 141.37566) (xy 161.01807 141.38386) (xy 161.01807 141.39205)
			(xy 161.01807 141.40025) (xy 161.01807 141.40844) (xy 161.01807 141.41663) (xy 161.01807 141.42483)
			(xy 161.01807 141.43302) (xy 161.01807 141.44122) (xy 161.02627 141.44122) (xy 161.02627 141.44941)
			(xy 161.02627 141.45761) (xy 161.02627 141.4658) (xy 161.02627 141.474) (xy 161.02627 141.48219)
			(xy 161.02627 141.49039) (xy 161.02627 141.49858) (xy 161.02627 141.50677) (xy 161.02627 141.51497)
			(xy 161.02627 141.52316) (xy 161.02627 141.53136) (xy 161.02627 141.53955) (xy 161.02627 141.54775)
			(xy 161.02627 141.55594) (xy 161.02627 141.56413) (xy 161.02627 141.57233) (xy 161.02627 141.58052)
			(xy 161.03446 141.58052) (xy 161.03446 141.58872) (xy 161.03446 141.59692) (xy 161.03446 141.60511)
			(xy 161.03446 141.6133) (xy 161.03446 141.6215) (xy 161.03446 141.62969) (xy 161.03446 141.63789)
			(xy 161.03446 141.64608) (xy 161.03446 141.65427) (xy 161.03446 141.66247) (xy 161.03446 141.67066)
			(xy 161.1328 141.67066) (xy 161.1328 141.66247) (xy 161.1328 141.65427) (xy 161.1328 141.64608) (xy 161.1328 141.63789)
			(xy 161.1328 141.62969) (xy 161.1328 141.6215) (xy 161.1328 141.6133) (xy 161.1328 141.60511) (xy 161.1328 141.59692)
			(xy 161.1328 141.58872) (xy 161.1328 141.58052) (xy 161.1328 141.57233) (xy 161.1246 141.57233) (xy 161.1246 141.56413)
			(xy 161.1328 141.56413) (xy 161.1328 141.55594) (xy 161.1328 141.54775) (xy 161.1328 141.53955) (xy 161.1246 141.53955)
			(xy 161.1246 141.53136) (xy 161.1246 141.52316) (xy 161.1246 141.51497) (xy 161.1246 141.50677) (xy 161.1246 141.49858)
			(xy 161.1246 141.49039) (xy 161.1246 141.48219) (xy 161.1246 141.474) (xy 161.1246 141.4658) (xy 161.1246 141.45761)
			(xy 161.1246 141.44941) (xy 161.1246 141.44122) (xy 161.1246 141.43302) (xy 161.1246 141.42483) (xy 161.1164 141.42483)
			(xy 161.1164 141.41663) (xy 161.1164 141.40844) (xy 161.1164 141.40025) (xy 161.1164 141.39205) (xy 161.1164 141.38386)
			(xy 161.1164 141.37566) (xy 161.1164 141.36747) (xy 161.1164 141.35927) (xy 161.1164 141.35108) (xy 161.1164 141.34289)
			(xy 161.10821 141.34289) (xy 161.10821 141.33469) (xy 161.10821 141.32649) (xy 161.10821 141.3183)
			(xy 161.10821 141.31011) (xy 161.10821 141.30191) (xy 161.10821 141.29372) (xy 161.10821 141.28552)
			(xy 161.10821 141.27733) (xy 161.10002 141.27733) (xy 161.10002 141.26913) (xy 161.10002 141.26094)
			(xy 161.10002 141.25274) (xy 161.10002 141.24455) (xy 161.10002 141.23636) (xy 161.10002 141.22816)
			(xy 161.10002 141.21997) (xy 161.09182 141.21997) (xy 161.09182 141.21177) (xy 161.09182 141.20358)
			(xy 161.09182 141.19538) (xy 161.09182 141.18719) (xy 161.09182 141.179) (xy 161.09182 141.1708)
			(xy 161.08363 141.1708) (xy 161.08363 141.16261) (xy 161.08363 141.15441) (xy 161.08363 141.14622)
			(xy 161.08363 141.13802) (xy 161.08363 141.12983) (xy 161.07543 141.12983) (xy 161.07543 141.12163)
			(xy 161.07543 141.11344) (xy 161.07543 141.10525) (xy 161.07543 141.09705) (xy 161.07543 141.08885)
			(xy 161.06724 141.08885) (xy 161.06724 141.08066) (xy 161.06724 141.07247) (xy 161.06724 141.06427)
			(xy 161.06724 141.05608) (xy 161.06724 141.04788) (xy 161.05905 141.04788) (xy 161.05905 141.03969)
			(xy 161.05905 141.03149) (xy 161.05905 141.0233) (xy 161.05905 141.0151) (xy 161.05905 141.00691)
			(xy 161.05085 141.00691) (xy 161.05085 140.99872) (xy 161.05085 140.99052) (xy 161.05085 140.98233)
			(xy 161.05085 140.97413) (xy 161.04265 140.97413) (xy 161.04265 140.96594) (xy 161.04265 140.95774)
			(xy 161.04265 140.94955) (xy 161.04265 140.94135) (xy 161.03446 140.94135) (xy 161.03446 140.93316)
			(xy 161.03446 140.92496) (xy 161.03446 140.91677) (xy 161.03446 140.90858) (xy 161.02627 140.90858)
			(xy 161.02627 140.90038) (xy 161.02627 140.89219) (xy 161.02627 140.88399) (xy 161.02627 140.8758)
			(xy 161.01807 140.8758) (xy 161.01807 140.86761) (xy 161.01807 140.85941) (xy 161.01807 140.85121)
			(xy 161.00988 140.85121) (xy 161.00988 140.84302) (xy 161.00988 140.83482) (xy 161.00988 140.82663)
			(xy 161.00988 140.81844) (xy 161.00168 140.81844) (xy 161.00168 140.81024) (xy 161.00168 140.80205)
			(xy 161.00168 140.79385) (xy 160.99349 140.79385) (xy 160.99349 140.78566) (xy 160.99349 140.77746)
			(xy 160.99349 140.76927) (xy 160.99349 140.76108) (xy 160.98529 140.76108) (xy 160.98529 140.75288)
			(xy 160.98529 140.74469) (xy 160.98529 140.73649) (xy 160.9771 140.73649) (xy 160.9771 140.7283)
			(xy 160.9771 140.7201) (xy 160.9771 140.71191) (xy 160.9689 140.71191) (xy 160.9689 140.70371) (xy 160.9689 140.69552)
			(xy 160.9689 140.68732) (xy 160.96071 140.68732) (xy 160.96071 140.67913) (xy 160.96071 140.67094)
			(xy 160.96071 140.66274) (xy 160.95252 140.66274) (xy 160.95252 140.65455) (xy 160.95252 140.64635)
			(xy 160.95252 140.63816) (xy 160.94432 140.63816) (xy 160.94432 140.62996) (xy 160.94432 140.62177)
			(xy 160.93613 140.62177) (xy 160.93613 140.61357) (xy 160.93613 140.60538) (xy 160.93613 140.59718)
			(xy 160.92793 140.59718) (xy 160.92793 140.58899) (xy 160.92793 140.5808) (xy 160.92793 140.5726)
			(xy 160.91974 140.5726) (xy 160.91974 140.56441) (xy 160.91974 140.55621) (xy 160.91154 140.55621)
			(xy 160.91154 140.54802) (xy 160.91154 140.53982) (xy 160.91154 140.53163) (xy 160.90335 140.53163)
			(xy 160.90335 140.52344) (xy 160.90335 140.51524) (xy 160.89515 140.51524) (xy 160.89515 140.50704)
			(xy 160.89515 140.49885) (xy 160.89515 140.49066) (xy 160.88696 140.49066) (xy 160.88696 140.48246)
			(xy 160.88696 140.47427) (xy 160.87877 140.47427) (xy 160.87877 140.46607) (xy 160.87877 140.45788)
			(xy 160.87057 140.45788) (xy 160.87057 140.44969) (xy 160.87057 140.44149) (xy 160.87057 140.4333)
			(xy 160.86238 140.4333) (xy 160.86238 140.4251) (xy 160.86238 140.41691) (xy 160.85418 140.41691)
			(xy 160.85418 140.40871) (xy 160.85418 140.40052) (xy 160.84599 140.40052) (xy 160.84599 140.39232)
			(xy 160.84599 140.38413) (xy 160.83779 140.38413) (xy 160.83779 140.37593) (xy 160.83779 140.36774)
			(xy 160.83779 140.35954) (xy 160.8296 140.35954) (xy 160.8296 140.35135) (xy 160.8296 140.34316)
			(xy 160.82141 140.34316) (xy 160.82141 140.33496) (xy 160.82141 140.32677) (xy 160.81321 140.32677)
			(xy 160.81321 140.31857) (xy 160.81321 140.31038) (xy 160.80501 140.31038) (xy 160.80501 140.30218)
			(xy 160.80501 140.29399) (xy 160.79682 140.29399) (xy 160.79682 140.28579) (xy 160.79682 140.2776)
			(xy 160.78863 140.2776) (xy 160.78863 140.2694) (xy 160.78863 140.26121) (xy 160.78043 140.26121)
			(xy 160.78043 140.25302) (xy 160.78043 140.24482) (xy 160.77224 140.24482) (xy 160.77224 140.23663)
			(xy 160.77224 140.22843) (xy 160.76404 140.22843) (xy 160.76404 140.22024) (xy 160.76404 140.21204)
			(xy 160.75585 140.21204) (xy 160.75585 140.20385) (xy 160.74765 140.20385) (xy 160.74765 140.19565)
			(xy 160.74765 140.18746) (xy 160.73946 140.18746) (xy 160.73946 140.17927) (xy 160.73946 140.17107)
			(xy 160.73126 140.17107) (xy 160.73126 140.16288) (xy 160.73126 140.15468) (xy 160.72307 140.15468)
			(xy 160.72307 140.14649) (xy 160.72307 140.1383) (xy 160.71488 140.1383) (xy 160.71488 140.1301)
			(xy 160.70668 140.1301) (xy 160.70668 140.1219) (xy 160.70668 140.11371) (xy 160.69849 140.11371)
			(xy 160.69849 140.10552) (xy 160.69849 140.09732) (xy 160.69029 140.09732) (xy 160.69029 140.08913)
			(xy 160.6821 140.08913) (xy 160.6821 140.08093) (xy 160.6821 140.07274) (xy 160.6739 140.07274) (xy 160.6739 140.06454)
			(xy 160.6739 140.05635) (xy 160.66571 140.05635) (xy 160.66571 140.04815) (xy 160.65751 140.04815)
			(xy 160.65751 140.03996) (xy 160.65751 140.03176) (xy 160.64932 140.03176) (xy 160.64932 140.02357)
			(xy 160.64932 140.01538) (xy 160.64113 140.01538) (xy 160.64113 140.00718) (xy 160.63293 140.00718)
			(xy 160.63293 139.99899) (xy 160.63293 139.99079) (xy 160.62474 139.99079) (xy 160.62474 139.9826)
			(xy 160.61654 139.9826) (xy 160.61654 139.9744) (xy 160.61654 139.96621) (xy 160.60835 139.96621)
			(xy 160.60835 139.95802) (xy 160.60015 139.95802) (xy 160.60015 139.94982) (xy 160.60015 139.94163)
			(xy 160.59196 139.94163) (xy 160.59196 139.93343) (xy 160.58376 139.93343) (xy 160.58376 139.92524)
			(xy 160.58376 139.91704) (xy 160.57557 139.91704) (xy 160.57557 139.90885) (xy 160.56737 139.90885)
			(xy 160.56737 139.90065) (xy 160.56737 139.89246) (xy 160.55918 139.89246) (xy 160.55918 139.88426)
			(xy 160.55098 139.88426) (xy 160.55098 139.87607) (xy 160.54279 139.87607) (xy 160.54279 139.86787)
			(xy 160.54279 139.85968) (xy 160.5346 139.85968) (xy 160.5346 139.85149) (xy 160.5264 139.85149)
			(xy 160.5264 139.84329) (xy 160.5264 139.8351) (xy 160.51821 139.8351) (xy 160.51821 139.8269) (xy 160.51001 139.8269)
			(xy 160.51001 139.81871) (xy 160.50182 139.81871) (xy 160.50182 139.81051) (xy 160.50182 139.80232)
			(xy 160.49362 139.80232) (xy 160.49362 139.79413) (xy 160.48543 139.79413) (xy 160.48543 139.78593)
			(xy 160.47724 139.78593) (xy 160.47724 139.77773) (xy 160.46904 139.77773) (xy 160.46904 139.76954)
			(xy 160.46904 139.76135) (xy 160.46084 139.76135) (xy 160.46084 139.75315) (xy 160.45265 139.75315)
			(xy 160.45265 139.74496) (xy 160.44446 139.74496) (xy 160.44446 139.73676) (xy 160.44446 139.72857)
			(xy 160.43626 139.72857) (xy 160.43626 139.72038) (xy 160.42807 139.72038) (xy 160.42807 139.71218)
			(xy 160.41987 139.71218) (xy 160.41987 139.70398) (xy 160.41168 139.70398) (xy 160.41168 139.69579)
			(xy 160.40349 139.69579) (xy 160.40349 139.6876) (xy 160.40349 139.6794) (xy 160.39529 139.6794)
			(xy 160.39529 139.67121) (xy 160.3871 139.67121) (xy 160.3871 139.66301) (xy 160.3789 139.66301)
			(xy 160.3789 139.65482) (xy 160.37071 139.65482) (xy 160.37071 139.64662) (xy 160.36251 139.64662)
			(xy 160.36251 139.63843) (xy 160.36251 139.63023) (xy 160.35432 139.63023) (xy 160.35432 139.62204)
			(xy 160.34613 139.62204) (xy 160.34613 139.61385) (xy 160.33793 139.61385) (xy 160.33793 139.60565)
			(xy 160.32974 139.60565) (xy 160.32974 139.59746) (xy 160.32154 139.59746) (xy 160.32154 139.58926)
			(xy 160.31334 139.58926) (xy 160.31334 139.58107) (xy 160.30515 139.58107) (xy 160.30515 139.57287)
			(xy 160.29696 139.57287) (xy 160.29696 139.56468) (xy 160.29696 139.55649) (xy 160.28876 139.55649)
			(xy 160.28876 139.54829) (xy 160.28057 139.54829) (xy 160.28057 139.54009) (xy 160.27237 139.54009)
			(xy 160.27237 139.5319) (xy 160.26418 139.5319) (xy 160.26418 139.52371) (xy 160.25598 139.52371)
			(xy 160.25598 139.51551) (xy 160.24779 139.51551) (xy 160.24779 139.50732) (xy 160.2396 139.50732)
			(xy 160.2396 139.49912) (xy 160.2314 139.49912) (xy 160.2314 139.49093) (xy 160.22321 139.49093)
			(xy 160.22321 139.48273) (xy 160.21501 139.48273) (xy 160.21501 139.47454) (xy 160.20682 139.47454)
			(xy 160.20682 139.46634) (xy 160.19862 139.46634) (xy 160.19862 139.45815) (xy 160.19043 139.45815)
			(xy 160.19043 139.44996) (xy 160.18223 139.44996) (xy 160.18223 139.44176) (xy 160.17404 139.44176)
			(xy 160.17404 139.43357) (xy 160.16584 139.43357) (xy 160.16584 139.42537) (xy 160.15765 139.42537)
			(xy 160.15765 139.41718) (xy 160.14946 139.41718) (xy 160.14946 139.40898) (xy 160.14126 139.40898)
			(xy 160.14126 139.40079) (xy 160.13307 139.40079) (xy 160.13307 139.39259) (xy 160.12487 139.39259)
			(xy 160.12487 139.3844) (xy 160.10848 139.3844) (xy 160.10848 139.37621) (xy 160.10029 139.37621)
			(xy 160.10029 139.36801) (xy 160.09209 139.36801) (xy 160.09209 139.35982) (xy 160.0839 139.35982)
			(xy 160.0839 139.35162) (xy 160.0757 139.35162) (xy 160.0757 139.34342) (xy 160.06751 139.34342)
			(xy 160.06751 139.33523) (xy 160.05932 139.33523) (xy 160.05932 139.32704) (xy 160.05112 139.32704)
			(xy 160.05112 139.31884) (xy 160.04293 139.31884) (xy 160.04293 139.31065) (xy 160.02654 139.31065)
			(xy 160.02654 139.30245) (xy 160.01834 139.30245) (xy 160.01834 139.29426) (xy 160.01015 139.29426)
			(xy 160.01015 139.28607) (xy 160.00195 139.28607) (xy 160.00195 139.27787) (xy 159.99376 139.27787)
			(xy 159.99376 139.26968) (xy 159.97737 139.26968) (xy 159.97737 139.26148) (xy 159.96917 139.26148)
			(xy 159.96917 139.25329) (xy 159.96098 139.25329) (xy 159.96098 139.24509) (xy 159.95279 139.24509)
			(xy 159.95279 139.2369) (xy 159.94459 139.2369) (xy 159.94459 139.22871) (xy 159.9282 139.22871)
			(xy 159.9282 139.22051) (xy 159.92001 139.22051) (xy 159.92001 139.21232) (xy 159.91182 139.21232)
			(xy 159.91182 139.20412) (xy 159.89543 139.20412) (xy 159.89543 139.19593) (xy 159.88723 139.19593)
			(xy 159.88723 139.18773) (xy 159.87904 139.18773) (xy 159.87904 139.17954) (xy 159.87084 139.17954)
			(xy 159.87084 139.17134) (xy 159.85445 139.17134) (xy 159.85445 139.16315) (xy 159.84626 139.16315)
			(xy 159.84626 139.15495) (xy 159.82987 139.15495) (xy 159.82987 139.14676) (xy 159.82168 139.14676)
			(xy 159.82168 139.13857) (xy 159.81348 139.13857) (xy 159.81348 139.13037) (xy 159.79709 139.13037)
			(xy 159.79709 139.12218) (xy 159.7889 139.12218) (xy 159.7889 139.11398) (xy 159.7807 139.11398)
			(xy 159.7807 139.10579) (xy 159.76431 139.10579) (xy 159.76431 139.09759) (xy 159.75612 139.09759)
			(xy 159.75612 139.0894) (xy 159.73973 139.0894) (xy 159.73973 139.0812) (xy 159.73153 139.0812) (xy 159.73153 139.07301)
			(xy 159.71515 139.07301) (xy 159.71515 139.06481) (xy 159.70695 139.06481) (xy 159.70695 139.05662)
			(xy 159.69056 139.05662) (xy 159.69056 139.04842) (xy 159.68237 139.04842) (xy 159.68237 139.04023)
			(xy 159.66598 139.04023) (xy 159.66598 139.03204) (xy 159.64959 139.03204) (xy 159.64959 139.02384)
			(xy 159.6414 139.02384) (xy 159.6414 139.01565) (xy 159.62501 139.01565) (xy 159.62501 139.00745)
			(xy 159.61682 139.00745) (xy 159.61682 138.99926) (xy 159.60042 138.99926) (xy 159.60042 138.99107)
			(xy 159.58403 138.99107) (xy 159.58403 138.98287) (xy 159.57584 138.98287) (xy 159.57584 138.97467)
			(xy 159.55945 138.97467) (xy 159.55945 138.96648) (xy 159.54306 138.96648) (xy 159.54306 138.95829)
			(xy 159.52667 138.95829) (xy 159.52667 138.95009) (xy 159.51848 138.95009) (xy 159.51848 138.9419)
			(xy 159.50209 138.9419) (xy 159.50209 138.9337) (xy 159.4857 138.9337) (xy 159.4857 138.92551) (xy 159.46931 138.92551)
			(xy 159.46931 138.91731) (xy 159.45292 138.91731) (xy 159.45292 138.90912) (xy 159.44473 138.90912)
			(xy 159.44473 138.90092) (xy 159.42015 138.90092) (xy 159.42015 138.89273) (xy 159.41195 138.89273)
			(xy 159.41195 138.88454) (xy 159.39556 138.88454) (xy 159.39556 138.87634) (xy 159.37098 138.87634)
			(xy 159.37098 138.86815) (xy 159.35459 138.86815) (xy 159.35459 138.85995) (xy 159.34639 138.85995)
			(xy 159.34639 138.85176) (xy 159.33001 138.85176) (xy 159.33001 138.84356) (xy 159.30542 138.84356)
			(xy 159.30542 138.83537) (xy 159.28903 138.83537) (xy 159.28903 138.82718) (xy 159.27265 138.82718)
			(xy 159.27265 138.81898) (xy 159.25626 138.81898) (xy 159.25626 138.81078) (xy 159.23986 138.81078)
			(xy 159.23986 138.80259) (xy 159.21528 138.80259) (xy 159.21528 138.7944) (xy 159.19889 138.7944)
			(xy 159.19889 138.7862) (xy 159.18251 138.7862) (xy 159.18251 138.77801) (xy 159.15792 138.77801)
			(xy 159.15792 138.76981) (xy 159.14153 138.76981) (xy 159.14153 138.76162) (xy 159.11695 138.76162)
			(xy 159.11695 138.75342) (xy 159.09237 138.75342) (xy 159.09237 138.74523) (xy 159.07598 138.74523)
			(xy 159.07598 138.73704) (xy 159.05139 138.73704) (xy 159.05139 138.72884) (xy 159.02681 138.72884)
			(xy 159.02681 138.72065) (xy 159.00223 138.72065) (xy 159.00223 138.71245) (xy 158.98584 138.71245)
			(xy 158.98584 138.70426) (xy 158.96126 138.70426) (xy 158.96126 138.69607) (xy 158.93667 138.69607)
			(xy 158.93667 138.68787) (xy 158.90389 138.68787) (xy 158.90389 138.67967) (xy 158.87931 138.67967)
			(xy 158.87931 138.67148) (xy 158.85473 138.67148) (xy 158.85473 138.66328) (xy 158.82195 138.66328)
			(xy 158.82195 138.65509) (xy 158.79736 138.65509) (xy 158.79736 138.6469) (xy 158.76459 138.6469)
			(xy 158.76459 138.6387) (xy 158.73181 138.6387) (xy 158.73181 138.63051) (xy 158.69903 138.63051)
			(xy 158.69903 138.62231) (xy 158.66625 138.62231) (xy 158.66625 138.61412) (xy 158.62528 138.61412)
			(xy 158.62528 138.60592) (xy 158.58431 138.60592) (xy 158.58431 138.59773) (xy 158.54334 138.59773)
			(xy 158.54334 138.58954) (xy 158.49417 138.58954) (xy 158.49417 138.58134) (xy 158.445 138.58134)
			(xy 158.445 138.57315) (xy 158.37944 138.57315) (xy 158.37944 138.56495) (xy 158.31389 138.56495)
			(xy 158.31389 138.55675) (xy 158.24014 138.55675) (xy 158.24014 138.54856) (xy 158.11722 138.54856)
			(xy 158.11722 138.54037) (xy 157.81403 138.54037) (xy 157.81403 138.54856) (xy 157.69111 138.54856)
			(xy 157.69111 138.55675) (xy 157.60916 138.55675) (xy 157.60916 138.56495) (xy 157.54361 138.56495)
			(xy 157.54361 138.57315) (xy 157.49444 138.57315) (xy 157.49444 138.58134) (xy 157.43708 138.58134)
			(xy 157.43708 138.58954) (xy 157.38791 138.58954) (xy 157.38791 138.59773) (xy 157.34694 138.59773)
			(xy 157.34694 138.60592) (xy 157.30597 138.60592) (xy 157.30597 138.61412) (xy 157.26499 138.61412)
			(xy 157.26499 138.62231) (xy 157.23222 138.62231) (xy 157.23222 138.63051) (xy 157.19944 138.63051)
			(xy 157.19944 138.6387) (xy 157.16666 138.6387) (xy 157.16666 138.6469) (xy 157.13388 138.6469) (xy 157.13388 138.65509)
			(xy 157.1093 138.65509) (xy 157.1093 138.66328) (xy 157.07652 138.66328) (xy 157.07652 138.67148)
			(xy 157.05194 138.67148) (xy 157.05194 138.67967) (xy 157.02735 138.67967) (xy 157.02735 138.68787)
			(xy 156.99457 138.68787) (xy 156.99457 138.69607) (xy 156.96999 138.69607) (xy 156.96999 138.70426)
			(xy 156.94541 138.70426) (xy 156.94541 138.71245) (xy 156.92083 138.71245) (xy 156.92083 138.72065)
			(xy 156.90444 138.72065) (xy 156.90444 138.72884) (xy 156.87985 138.72884) (xy 156.87985 138.73704)
			(xy 156.85527 138.73704) (xy 156.85527 138.74523) (xy 156.83068 138.74523) (xy 156.83068 138.75342)
			(xy 156.8143 138.75342) (xy 156.8143 138.76162) (xy 156.78971 138.76162) (xy 156.78971 138.76981)
			(xy 156.77332 138.76981) (xy 156.77332 138.77801) (xy 156.74874 138.77801) (xy 156.74874 138.7862)
			(xy 156.73235 138.7862) (xy 156.73235 138.7944) (xy 156.71596 138.7944) (xy 156.71596 138.80259)
			(xy 156.69138 138.80259) (xy 156.69138 138.81078) (xy 156.67499 138.81078) (xy 156.67499 138.81898)
			(xy 156.6586 138.81898) (xy 156.6586 138.82718) (xy 156.64221 138.82718) (xy 156.64221 138.83537)
			(xy 156.61763 138.83537) (xy 156.61763 138.84356) (xy 156.60124 138.84356) (xy 156.60124 138.85176)
			(xy 156.58485 138.85176) (xy 156.58485 138.85995) (xy 156.56846 138.85995) (xy 156.56846 138.86815)
			(xy 156.55207 138.86815) (xy 156.55207 138.87634) (xy 156.53568 138.87634) (xy 156.53568 138.88454)
			(xy 156.5193 138.88454) (xy 156.5193 138.89273) (xy 156.50291 138.89273) (xy 156.50291 138.90092)
			(xy 156.48652 138.90092) (xy 156.48652 138.90912) (xy 156.47013 138.90912) (xy 156.47013 138.91731)
			(xy 156.46193 138.91731) (xy 156.46193 138.92551) (xy 156.44554 138.92551) (xy 156.44554 138.9337)
			(xy 156.42916 138.9337) (xy 156.42916 138.9419) (xy 156.41277 138.9419) (xy 156.41277 138.95009)
			(xy 156.39638 138.95009) (xy 156.39638 138.95829) (xy 156.38818 138.95829) (xy 156.38818 138.96648)
			(xy 156.3718 138.96648) (xy 156.3718 138.97467) (xy 156.3554 138.97467) (xy 156.3554 138.98287) (xy 156.34721 138.98287)
			(xy 156.34721 138.99107) (xy 156.33082 138.99107) (xy 156.33082 138.99926) (xy 156.31443 138.99926)
			(xy 156.31443 139.00745) (xy 156.30624 139.00745) (xy 156.30624 139.01565) (xy 156.28985 139.01565)
			(xy 156.28985 139.02384) (xy 156.27346 139.02384) (xy 156.27346 139.03204) (xy 156.26527 139.03204)
			(xy 156.26527 139.04023) (xy 156.24888 139.04023) (xy 156.24888 139.04842) (xy 156.24068 139.04842)
			(xy 156.24068 139.05662) (xy 156.22429 139.05662) (xy 156.22429 139.06481) (xy 156.2161 139.06481)
			(xy 156.2161 139.07301) (xy 156.19971 139.07301) (xy 156.19971 139.0812) (xy 156.19152 139.0812)
			(xy 156.19152 139.0894) (xy 156.17513 139.0894) (xy 156.17513 139.09759) (xy 156.16693 139.09759)
			(xy 156.16693 139.10579) (xy 156.15054 139.10579) (xy 156.15054 139.11398) (xy 156.14235 139.11398)
			(xy 156.14235 139.12218) (xy 156.13415 139.12218) (xy 156.13415 139.13037) (xy 156.11776 139.13037)
			(xy 156.11776 139.13857) (xy 156.10957 139.13857) (xy 156.10957 139.14676) (xy 156.09318 139.14676)
			(xy 156.09318 139.15495) (xy 156.08499 139.15495) (xy 156.08499 139.16315) (xy 156.07679 139.16315)
			(xy 156.07679 139.17134) (xy 156.0604 139.17134) (xy 156.0604 139.17954) (xy 156.05221 139.17954)
			(xy 156.05221 139.18773) (xy 156.04401 139.18773) (xy 156.04401 139.19593) (xy 156.02763 139.19593)
			(xy 156.02763 139.20412) (xy 156.01943 139.20412) (xy 156.01943 139.21232) (xy 156.01124 139.21232)
			(xy 156.01124 139.22051) (xy 156.00304 139.22051) (xy 156.00304 139.22871) (xy 155.98666 139.22871)
			(xy 155.98666 139.2369) (xy 155.97846 139.2369) (xy 155.97846 139.24509) (xy 155.97026 139.24509)
			(xy 155.97026 139.25329) (xy 155.96207 139.25329) (xy 155.96207 139.26148) (xy 155.94568 139.26148)
			(xy 155.94568 139.26968) (xy 155.93749 139.26968) (xy 155.93749 139.27787) (xy 155.92929 139.27787)
			(xy 155.92929 139.28607) (xy 155.9211 139.28607) (xy 155.9211 139.29426) (xy 155.9129 139.29426)
			(xy 155.9129 139.30245) (xy 155.89651 139.30245) (xy 155.89651 139.31065) (xy 155.88832 139.31065)
			(xy 155.88832 139.31884) (xy 155.88013 139.31884) (xy 155.88013 139.32704) (xy 155.87193 139.32704)
			(xy 155.87193 139.33523) (xy 155.86373 139.33523) (xy 155.86373 139.34342) (xy 155.85554 139.34342)
			(xy 155.85554 139.35162) (xy 155.84735 139.35162) (xy 155.84735 139.35982) (xy 155.83915 139.35982)
			(xy 155.83915 139.36801) (xy 155.82276 139.36801) (xy 155.82276 139.37621) (xy 155.81457 139.37621)
			(xy 155.81457 139.3844) (xy 155.80637 139.3844) (xy 155.80637 139.39259) (xy 155.79818 139.39259)
			(xy 155.79818 139.40079) (xy 155.78999 139.40079) (xy 155.78999 139.40898) (xy 155.78179 139.40898)
			(xy 155.78179 139.41718) (xy 155.7736 139.41718) (xy 155.7736 139.42537) (xy 155.7654 139.42537)
			(xy 155.7654 139.43357) (xy 155.75721 139.43357) (xy 155.75721 139.44176) (xy 155.74901 139.44176)
			(xy 155.74901 139.44996) (xy 155.74082 139.44996) (xy 155.74082 139.45815) (xy 155.73262 139.45815)
			(xy 155.73262 139.46634) (xy 155.72443 139.46634) (xy 155.72443 139.47454) (xy 155.71623 139.47454)
			(xy 155.71623 139.48273) (xy 155.70804 139.48273) (xy 155.70804 139.49093) (xy 155.69985 139.49093)
			(xy 155.69985 139.49912) (xy 155.69165 139.49912) (xy 155.69165 139.50732) (xy 155.68346 139.50732)
			(xy 155.68346 139.51551) (xy 155.67526 139.51551) (xy 155.67526 139.52371) (xy 155.66707 139.52371)
			(xy 155.66707 139.5319) (xy 155.65887 139.5319) (xy 155.65887 139.54009) (xy 155.65068 139.54009)
			(xy 155.65068 139.54829) (xy 155.64249 139.54829) (xy 155.64249 139.55649) (xy 155.63429 139.55649)
			(xy 155.63429 139.56468) (xy 155.62609 139.56468) (xy 155.62609 139.57287) (xy 155.62609 139.58107)
			(xy 155.6179 139.58107) (xy 155.6179 139.58926) (xy 155.6097 139.58926) (xy 155.6097 139.59746) (xy 155.60151 139.59746)
			(xy 155.60151 139.60565) (xy 155.59332 139.60565) (xy 155.59332 139.61385) (xy 155.58512 139.61385)
			(xy 155.58512 139.62204) (xy 155.57693 139.62204) (xy 155.57693 139.63023) (xy 155.56873 139.63023)
			(xy 155.56873 139.63843) (xy 155.56054 139.63843) (xy 155.56054 139.64662) (xy 155.56054 139.65482)
			(xy 155.55234 139.65482) (xy 155.55234 139.66301) (xy 155.54415 139.66301) (xy 155.54415 139.67121)
			(xy 155.53596 139.67121) (xy 155.53596 139.6794) (xy 155.52776 139.6794) (xy 155.52776 139.6876)
			(xy 155.51957 139.6876) (xy 155.51957 139.69579) (xy 155.51957 139.70398) (xy 155.51137 139.70398)
			(xy 155.51137 139.71218) (xy 155.50318 139.71218) (xy 155.50318 139.72038) (xy 155.49498 139.72038)
			(xy 152.90552 139.72038) (xy 152.90552 139.71218) (xy 152.90552 139.70398) (xy 152.90552 139.69579)
			(xy 152.90552 139.6876) (xy 152.90552 139.6794) (xy 152.90552 139.67121) (xy 152.90552 139.66301)
			(xy 152.90552 139.65482) (xy 152.90552 139.64662) (xy 152.90552 139.63843) (xy 152.90552 139.63023)
			(xy 152.90552 139.62204) (xy 152.90552 139.61385) (xy 152.90552 139.60565) (xy 152.90552 139.59746)
			(xy 152.90552 139.58926) (xy 152.90552 139.58107) (xy 152.90552 139.57287) (xy 152.90552 139.56468)
			(xy 152.90552 139.55649) (xy 152.90552 139.54829) (xy 152.90552 139.54009) (xy 152.90552 139.5319)
			(xy 152.90552 139.52371) (xy 152.90552 139.51551) (xy 152.90552 139.50732) (xy 152.90552 139.49912)
			(xy 152.90552 139.49093) (xy 152.90552 139.48273) (xy 152.90552 139.47454) (xy 152.90552 139.46634)
			(xy 152.90552 139.45815) (xy 152.90552 139.44996) (xy 152.90552 139.44176) (xy 152.90552 139.43357)
			(xy 152.90552 139.42537) (xy 152.90552 139.41718) (xy 152.90552 139.40898) (xy 152.90552 139.40079)
			(xy 152.90552 139.39259) (xy 152.90552 139.3844) (xy 152.90552 139.37621) (xy 152.90552 139.36801)
			(xy 152.90552 139.35982) (xy 152.90552 139.35162) (xy 152.90552 139.34342) (xy 152.90552 139.33523)
			(xy 152.90552 139.32704) (xy 152.90552 139.31884) (xy 152.90552 139.31065) (xy 152.90552 139.30245)
			(xy 152.90552 139.29426) (xy 152.90552 139.28607) (xy 152.90552 139.27787) (xy 152.90552 139.26968)
			(xy 152.90552 139.26148) (xy 152.90552 139.25329) (xy 152.90552 139.24509) (xy 152.90552 139.2369)
			(xy 152.90552 139.22871) (xy 152.90552 139.22051) (xy 152.90552 139.21232) (xy 152.90552 139.20412)
			(xy 152.90552 139.19593) (xy 152.90552 139.18773) (xy 152.90552 139.17954) (xy 152.90552 139.17134)
			(xy 152.90552 139.16315) (xy 152.90552 139.15495) (xy 152.90552 139.14676) (xy 152.90552 139.13857)
			(xy 152.90552 139.13037) (xy 152.90552 139.12218) (xy 152.90552 139.11398) (xy 152.90552 139.10579)
			(xy 152.90552 139.09759) (xy 152.90552 139.0894) (xy 152.90552 139.0812) (xy 152.90552 139.07301)
			(xy 152.90552 139.06481) (xy 152.90552 139.05662) (xy 152.90552 139.04842) (xy 152.90552 139.04023)
			(xy 152.90552 139.03204) (xy 152.90552 139.02384) (xy 152.90552 139.01565) (xy 152.90552 139.00745)
			(xy 152.90552 138.99926) (xy 152.90552 138.99107) (xy 152.90552 138.98287) (xy 152.90552 138.97467)
			(xy 152.90552 138.96648) (xy 152.90552 138.95829) (xy 152.90552 138.95009) (xy 152.90552 138.9419)
			(xy 152.90552 138.9337) (xy 152.90552 138.92551) (xy 152.90552 138.91731) (xy 152.90552 138.90912)
			(xy 152.90552 138.90092) (xy 152.90552 138.89273) (xy 152.90552 138.88454) (xy 152.90552 138.87634)
			(xy 152.90552 138.86815) (xy 152.90552 138.85995) (xy 152.90552 138.85176) (xy 152.90552 138.84356)
			(xy 152.90552 138.83537) (xy 152.90552 138.82718) (xy 152.90552 138.81898) (xy 152.90552 138.81078)
			(xy 152.90552 138.80259) (xy 152.90552 138.7944) (xy 152.90552 138.7862) (xy 152.90552 138.77801)
			(xy 152.90552 138.76981) (xy 152.90552 138.76162) (xy 152.90552 138.75342) (xy 152.90552 138.74523)
			(xy 152.90552 138.73704) (xy 152.90552 138.72884) (xy 152.90552 138.72065) (xy 152.90552 138.71245)
			(xy 152.90552 138.70426) (xy 152.90552 138.69607) (xy 152.90552 138.68787) (xy 152.90552 138.67967)
			(xy 152.90552 138.67148) (xy 152.90552 138.66328) (xy 152.90552 138.65509) (xy 152.90552 138.6469)
			(xy 152.90552 138.6387) (xy 152.90552 138.63051) (xy 152.90552 138.62231) (xy 152.90552 138.61412)
			(xy 152.90552 138.60592) (xy 152.90552 138.59773) (xy 152.90552 138.58954) (xy 152.90552 138.58134)
			(xy 152.90552 138.57315) (xy 152.90552 138.56495) (xy 152.90552 138.55675) (xy 152.90552 138.54856)
			(xy 152.90552 138.54037) (xy 152.90552 138.53217) (xy 152.90552 138.52398) (xy 152.90552 138.51578)
			(xy 152.90552 138.50759) (xy 152.90552 138.4994) (xy 152.90552 138.4912) (xy 152.90552 138.48301)
			(xy 152.90552 138.47481) (xy 152.90552 138.46662) (xy 152.90552 138.45842) (xy 152.90552 138.45023)
			(xy 152.90552 138.44203) (xy 152.90552 138.43384) (xy 152.90552 138.42564) (xy 152.90552 138.41745)
			(xy 152.90552 138.40926) (xy 152.90552 138.40106) (xy 152.90552 138.39287) (xy 152.90552 138.38467)
			(xy 152.90552 138.37648) (xy 152.90552 138.36828) (xy 152.90552 138.36009) (xy 152.90552 138.35189)
			(xy 152.90552 138.3437) (xy 152.90552 138.3355) (xy 152.90552 138.32731) (xy 152.90552 138.31911)
			(xy 152.90552 138.31092) (xy 152.90552 138.30273) (xy 152.90552 138.29453) (xy 152.90552 138.28634)
			(xy 152.90552 138.27814) (xy 152.90552 138.26995) (xy 152.90552 138.26175) (xy 152.90552 138.25356)
			(xy 152.90552 138.24537) (xy 152.90552 138.23717) (xy 152.90552 138.22898) (xy 152.90552 138.22078)
			(xy 152.90552 138.21259) (xy 152.90552 138.20439) (xy 152.90552 138.1962) (xy 152.90552 138.188)
			(xy 152.90552 138.17981) (xy 152.90552 138.17162) (xy 152.90552 138.16342) (xy 152.90552 138.15523)
			(xy 152.90552 138.14703) (xy 152.90552 138.13884) (xy 152.90552 138.13064) (xy 152.90552 138.12245)
			(xy 152.90552 138.11425) (xy 152.90552 138.10606) (xy 152.90552 138.09786) (xy 152.90552 138.08967)
			(xy 152.90552 138.08147) (xy 152.90552 138.07328) (xy 152.90552 138.06509) (xy 152.90552 138.05689)
			(xy 152.90552 138.0487) (xy 152.90552 138.0405) (xy 152.90552 138.03231) (xy 152.90552 138.02411)
			(xy 152.90552 138.01592) (xy 152.90552 138.00773) (xy 152.90552 137.99953) (xy 152.90552 137.99134)
			(xy 152.90552 137.98314) (xy 152.90552 137.97495) (xy 152.90552 137.96675) (xy 152.90552 137.95856)
			(xy 152.90552 137.95036) (xy 152.90552 137.94217) (xy 152.90552 137.93397) (xy 152.90552 137.92578)
			(xy 152.90552 137.91759) (xy 152.90552 137.90939) (xy 152.90552 137.9012) (xy 152.90552 137.893)
			(xy 152.90552 137.88481) (xy 152.90552 137.87661) (xy 152.90552 137.86842) (xy 152.91372 137.86842)
			(xy 152.91372 137.86023) (xy 163.25517 137.86023)
		)
		(stroke
			(width 0)
			(type default)
		)
		(fill yes)
		(layer "F.Cu")
	)
	(gr_rect
		(start 101.3261 154.6036)
		(end 103.8511 152.8786)
		(stroke
			(width 0)
			(type default)
		)
		(fill yes)
		(layer "F.Cu")
		(net "+12V_PCIE")
	)
	(gr_rect
		(start 101.4261 153.0786)
		(end 103.83346 145.6162)
		(stroke
			(width 0)
			(type default)
		)
		(fill yes)
		(layer "F.Cu")
		(net "+12V_PCIE")
	)
	(gr_rect
		(start 108.1261 154.5786)
		(end 110.93108 152.8786)
		(stroke
			(width 0)
			(type default)
		)
		(fill yes)
		(layer "F.Cu")
		(net "+3.3V_PCIE")
	)
	(gr_rect
		(start 101.9761 154.6036)
		(end 103.8511 152.8786)
		(stroke
			(width 0)
			(type default)
		)
		(fill yes)
		(layer "B.Cu")
		(net "+12V_PCIE")
	)
	(gr_rect
		(start 109.05608 154.62058)
		(end 110.93108 152.89558)
		(stroke
			(width 0)
			(type default)
		)
		(fill yes)
		(layer "B.Cu")
		(net "+3.3V_PCIE")
	)
	(gr_line
		(start 55.8761 49.4286)
		(end 55.8761 156.0786)
		(stroke
			(width 0.05)
			(type solid)
		)
		(layer "Edge.Cuts")
	)
	(gr_line
		(start 55.8761 156.0786)
		(end 70.8761 156.0786)
		(stroke
			(width 0.05)
			(type solid)
		)
		(layer "Edge.Cuts")
	)
	(gr_line
		(start 70.8761 147.8286)
		(end 89.2261 147.8286)
		(stroke
			(width 0.05)
			(type solid)
		)
		(layer "Edge.Cuts")
	)
	(gr_line
		(start 70.8761 156.0786)
		(end 70.8761 147.8286)
		(stroke
			(width 0.05)
			(type solid)
		)
		(layer "Edge.Cuts")
	)
	(gr_line
		(start 89.2261 147.8286)
		(end 89.2261 156.0786)
		(stroke
			(width 0.05)
			(type solid)
		)
		(layer "Edge.Cuts")
	)
	(gr_line
		(start 89.2261 156.0786)
		(end 97.2261 156.0786)
		(stroke
			(width 0.05)
			(type solid)
		)
		(layer "Edge.Cuts")
	)
	(gr_arc
		(start 97.2261 149.6536)
		(mid 99.0511 147.8286)
		(end 100.8761 149.6536)
		(stroke
			(width 0.05)
			(type solid)
		)
		(layer "Edge.Cuts")
	)
	(gr_line
		(start 97.2261 156.0786)
		(end 97.2261 149.6536)
		(stroke
			(width 0.05)
			(type solid)
		)
		(layer "Edge.Cuts")
	)
	(gr_line
		(start 100.8761 149.6536)
		(end 100.8761 160.0786)
		(stroke
			(width 0.05)
			(type solid)
		)
		(layer "Edge.Cuts")
	)
	(gr_line
		(start 100.8761 160.0786)
		(end 101.3761 160.5786)
		(stroke
			(width 0.05)
			(type solid)
		)
		(layer "Edge.Cuts")
	)
	(gr_line
		(start 101.3761 160.5786)
		(end 111.5761 160.5786)
		(stroke
			(width 0.05)
			(type solid)
		)
		(layer "Edge.Cuts")
	)
	(gr_line
		(start 111.5761 160.5786)
		(end 112.0761 160.0786)
		(stroke
			(width 0.05)
			(type solid)
		)
		(layer "Edge.Cuts")
	)
	(gr_arc
		(start 112.0761 153.1286)
		(mid 113.0261 152.1786)
		(end 113.9761 153.1286)
		(stroke
			(width 0.05)
			(type solid)
		)
		(layer "Edge.Cuts")
	)
	(gr_line
		(start 112.0761 160.0786)
		(end 112.0761 153.1286)
		(stroke
			(width 0.05)
			(type solid)
		)
		(layer "Edge.Cuts")
	)
	(gr_line
		(start 113.9761 153.1286)
		(end 113.9761 160.0786)
		(stroke
			(width 0.05)
			(type solid)
		)
		(layer "Edge.Cuts")
	)
	(gr_line
		(start 113.9761 160.0786)
		(end 114.4761 160.5786)
		(stroke
			(width 0.05)
			(type solid)
		)
		(layer "Edge.Cuts")
	)
	(gr_line
		(start 114.4761 160.5786)
		(end 134.6761 160.5786)
		(stroke
			(width 0.05)
			(type solid)
		)
		(layer "Edge.Cuts")
	)
	(gr_line
		(start 134.6761 160.5786)
		(end 135.1761 160.0786)
		(stroke
			(width 0.05)
			(type solid)
		)
		(layer "Edge.Cuts")
	)
	(gr_line
		(start 135.1761 147.8286)
		(end 241.1261 147.8286)
		(stroke
			(width 0.05)
			(type solid)
		)
		(layer "Edge.Cuts")
	)
	(gr_line
		(start 135.1761 160.0786)
		(end 135.1761 147.8286)
		(stroke
			(width 0.05)
			(type solid)
		)
		(layer "Edge.Cuts")
	)
	(gr_line
		(start 241.12609 49.4286)
		(end 55.8761 49.4286)
		(stroke
			(width 0.05)
			(type solid)
		)
		(layer "Edge.Cuts")
	)
	(gr_line
		(start 241.1261 147.8286)
		(end 241.12609 49.4286)
		(stroke
			(width 0.05)
			(type solid)
		)
		(layer "Edge.Cuts")
	)
	(gr_text "www.timingcard.com"
		(at 239.924435 129.9082 90)
		(layer "F.Cu")
		(effects
			(font
				(size 1.778 1.778)
				(thickness 0.508)
			)
			(justify left bottom)
		)
	)
	(gr_text "www.timingcard.com"
		(at 106.7611 144.64596 360)
		(layer "F.Cu")
		(effects
			(font
				(size 2.54 2.54)
				(thickness 0.635)
			)
			(justify left bottom)
		)
	)
	(via
		(at 237.1261 141.6162)
		(size 6.35)
		(drill 3.18)
		(layers "F.Cu" "B.Cu")
		(net "")
	)
	(via
		(at 228.6186 53.27359)
		(size 5.08)
		(drill 3.0988)
		(layers "F.Cu" "B.Cu")
		(net "")
	)
	(via
		(at 141.88361 53.23361)
		(size 5.08)
		(drill 3.0988)
		(layers "F.Cu" "B.Cu")
		(net "")
	)
	(via
		(at 168.11859 79.27359)
		(size 5.08)
		(drill 3.0988)
		(layers "F.Cu" "B.Cu")
		(net "")
	)
	(via
		(at 186.6261 141.6162)
		(size 6.35)
		(drill 3.18)
		(layers "F.Cu" "B.Cu")
		(net "")
	)
	(via
		(at 81.3836 79.23361)
		(size 5.08)
		(drill 3.0988)
		(layers "F.Cu" "B.Cu")
		(net "")
	)
	(via
		(at 141.88361 79.23361)
		(size 5.08)
		(drill 3.0988)
		(layers "F.Cu" "B.Cu")
		(net "")
	)
	(via
		(at 168.11859 53.27359)
		(size 5.08)
		(drill 3.0988)
		(layers "F.Cu" "B.Cu")
		(net "")
	)
	(via
		(at 228.6186 79.27359)
		(size 5.08)
		(drill 3.0988)
		(layers "F.Cu" "B.Cu")
		(net "")
	)
	(via
		(at 237.12611 55.1162)
		(size 6.35)
		(drill 3.18)
		(layers "F.Cu" "B.Cu")
		(net "")
	)
	(via
		(at 81.3836 53.23361)
		(size 5.08)
		(drill 3.0988)
		(layers "F.Cu" "B.Cu")
		(net "")
	)
	(segment
		(start 84.7261 85.0162)
		(end 85.8261 86.1162)
		(width 0.2032)
		(layer "F.Cu")
		(net "NetR108_2")
	)
	(segment
		(start 80.7261 85.0162)
		(end 80.7261 84.0162)
		(width 0.2032)
		(layer "F.Cu")
		(net "NetR108_2")
	)
	(segment
		(start 80.7261 84.0162)
		(end 80.7261 84.0162)
		(width 0.2032)
		(layer "F.Cu")
		(net "NetR108_2")
	)
	(segment
		(start 85.8261 86.1162)
		(end 87.0511 86.1162)
		(width 0.2032)
		(layer "F.Cu")
		(net "NetR108_2")
	)
	(segment
		(start 80.7261 85.0162)
		(end 84.7261 85.0162)
		(width 0.2032)
		(layer "F.Cu")
		(net "NetR108_2")
	)
	(segment
		(start 81.4261 83.5162)
		(end 82.1261 84.2162)
		(width 0.2032)
		(layer "F.Cu")
		(net "NetR40_2")
	)
	(segment
		(start 84.2761 83.1162)
		(end 85.5261 84.3662)
		(width 0.2032)
		(layer "F.Cu")
		(net "NetR40_2")
	)
	(segment
		(start 80.7261 83.1162)
		(end 81.1261 83.5162)
		(width 0.2032)
		(layer "F.Cu")
		(net "NetR40_2")
	)
	(segment
		(start 81.1261 83.5162)
		(end 81.4261 83.5162)
		(width 0.2032)
		(layer "F.Cu")
		(net "NetR40_2")
	)
	(segment
		(start 84.0261 83.8162)
		(end 84.0261 83.3662)
		(width 0.2032)
		(layer "F.Cu")
		(net "NetR40_2")
	)
	(segment
		(start 83.6261 84.2162)
		(end 84.0261 83.8162)
		(width 0.2032)
		(layer "F.Cu")
		(net "NetR40_2")
	)
	(segment
		(start 82.1261 84.2162)
		(end 83.6261 84.2162)
		(width 0.2032)
		(layer "F.Cu")
		(net "NetR40_2")
	)
	(segment
		(start 85.5261 84.8162)
		(end 86.3261 85.6162)
		(width 0.2032)
		(layer "F.Cu")
		(net "NetR40_2")
	)
	(segment
		(start 85.5261 84.8162)
		(end 85.5261 84.3662)
		(width 0.2032)
		(layer "F.Cu")
		(net "NetR40_2")
	)
	(segment
		(start 86.3261 85.6162)
		(end 87.0511 85.6162)
		(width 0.2032)
		(layer "F.Cu")
		(net "NetR40_2")
	)
	(segment
		(start 84.0261 83.3662)
		(end 84.2761 83.1162)
		(width 0.2032)
		(layer "F.Cu")
		(net "NetR40_2")
	)
	(segment
		(start 233.7261 80.54012)
		(end 233.7261 79.1162)
		(width 0.2032)
		(layer "F.Cu")
		(net "USB_VBUS")
	)
	(segment
		(start 233.8261 79.0162)
		(end 236.1261 79.0162)
		(width 0.2032)
		(layer "F.Cu")
		(net "USB_VBUS")
	)
	(segment
		(start 233.7261 79.1162)
		(end 233.8261 79.0162)
		(width 0.2032)
		(layer "F.Cu")
		(net "USB_VBUS")
	)
	(segment
		(start 233.7261 80.54012)
		(end 233.9261 80.74012)
		(width 0.2032)
		(layer "F.Cu")
		(net "USB_VBUS")
	)
	(segment
		(start 126.6261 87.6912)
		(end 126.6261 86.5662)
		(width 0.2032)
		(layer "F.Cu")
		(net "NetR99_2")
	)
	(segment
		(start 126.6261 87.6912)
		(end 127.2511 88.3162)
		(width 0.2032)
		(layer "F.Cu")
		(net "NetR99_2")
	)
	(segment
		(start 126.6261 84.6162)
		(end 126.8261 84.4162)
		(width 0.2032)
		(layer "F.Cu")
		(net "NetR98_2")
	)
	(segment
		(start 126.6261 85.2662)
		(end 126.6261 84.6162)
		(width 0.2032)
		(layer "F.Cu")
		(net "NetR98_2")
	)
	(segment
		(start 126.8261 84.4162)
		(end 127.6511 84.4162)
		(width 0.2032)
		(layer "F.Cu")
		(net "NetR98_2")
	)
	(segment
		(start 125.8261 87.4162)
		(end 125.8261 86.5662)
		(width 0.2032)
		(layer "F.Cu")
		(net "NetR97_2")
	)
	(segment
		(start 125.6261 87.6162)
		(end 125.8261 87.4162)
		(width 0.2032)
		(layer "F.Cu")
		(net "NetR97_2")
	)
	(segment
		(start 125.6261 88.1912)
		(end 125.6261 87.6162)
		(width 0.2032)
		(layer "F.Cu")
		(net "NetR97_2")
	)
	(segment
		(start 125.5011 88.3162)
		(end 125.6261 88.1912)
		(width 0.2032)
		(layer "F.Cu")
		(net "NetR97_2")
	)
	(segment
		(start 125.5011 84.1162)
		(end 125.8261 84.4412)
		(width 0.2032)
		(layer "F.Cu")
		(net "NetR96_2")
	)
	(segment
		(start 125.8261 85.2662)
		(end 125.8261 84.4412)
		(width 0.2032)
		(layer "F.Cu")
		(net "NetR96_2")
	)
	(segment
		(start 209.6261 80.6162)
		(end 210.1261 80.1162)
		(width 0.2032)
		(layer "F.Cu")
		(net "NetR93_2")
	)
	(segment
		(start 210.1261 80.1162)
		(end 210.1261 79.5162)
		(width 0.2032)
		(layer "F.Cu")
		(net "NetR93_2")
	)
	(segment
		(start 210.4261 79.2162)
		(end 210.8761 79.2162)
		(width 0.2032)
		(layer "F.Cu")
		(net "NetR93_2")
	)
	(segment
		(start 209.2761 80.6162)
		(end 209.6261 80.6162)
		(width 0.2032)
		(layer "F.Cu")
		(net "NetR93_2")
	)
	(segment
		(start 210.1261 79.5162)
		(end 210.4261 79.2162)
		(width 0.2032)
		(layer "F.Cu")
		(net "NetR93_2")
	)
	(segment
		(start 212.1761 79.2162)
		(end 212.8761 79.2162)
		(width 0.2032)
		(layer "F.Cu")
		(net "NetR92_2")
	)
	(segment
		(start 212.8761 79.2162)
		(end 213.6761 80.0162)
		(width 0.2032)
		(layer "F.Cu")
		(net "NetR92_2")
	)
	(segment
		(start 210.2761 78.4162)
		(end 210.8761 78.4162)
		(width 0.2032)
		(layer "F.Cu")
		(net "NetR91_2")
	)
	(segment
		(start 209.3761 77.5162)
		(end 210.2761 78.4162)
		(width 0.2032)
		(layer "F.Cu")
		(net "NetR91_2")
	)
	(segment
		(start 213.6261 78.1162)
		(end 214.0261 78.1162)
		(width 0.2032)
		(layer "F.Cu")
		(net "NetR90_2")
	)
	(segment
		(start 212.1761 78.4162)
		(end 213.3261 78.4162)
		(width 0.2032)
		(layer "F.Cu")
		(net "NetR90_2")
	)
	(segment
		(start 214.0261 78.1162)
		(end 214.0261 77.1662)
		(width 0.2032)
		(layer "F.Cu")
		(net "NetR90_2")
	)
	(segment
		(start 213.3261 78.4162)
		(end 213.6261 78.1162)
		(width 0.2032)
		(layer "F.Cu")
		(net "NetR90_2")
	)
	(segment
		(start 217.7761 79.2162)
		(end 219.2261 79.2162)
		(width 0.2032)
		(layer "F.Cu")
		(net "NetR87_2")
	)
	(segment
		(start 217.6761 79.3162)
		(end 217.7761 79.2162)
		(width 0.2032)
		(layer "F.Cu")
		(net "NetR87_2")
	)
	(segment
		(start 220.5261 79.2162)
		(end 221.1261 79.2162)
		(width 0.2032)
		(layer "F.Cu")
		(net "NetR86_2")
	)
	(segment
		(start 221.3261 79.4162)
		(end 221.6261 79.4162)
		(width 0.2032)
		(layer "F.Cu")
		(net "NetR86_2")
	)
	(segment
		(start 222.1761 80.4162)
		(end 222.1761 79.9662)
		(width 0.2032)
		(layer "F.Cu")
		(net "NetR86_2")
	)
	(segment
		(start 221.1261 79.2162)
		(end 221.3261 79.4162)
		(width 0.2032)
		(layer "F.Cu")
		(net "NetR86_2")
	)
	(segment
		(start 221.6261 79.4162)
		(end 222.1761 79.9662)
		(width 0.2032)
		(layer "F.Cu")
		(net "NetR86_2")
	)
	(segment
		(start 218.1261 77.9162)
		(end 218.6261 78.4162)
		(width 0.2032)
		(layer "F.Cu")
		(net "NetR85_2")
	)
	(segment
		(start 217.6761 77.9162)
		(end 218.1261 77.9162)
		(width 0.2032)
		(layer "F.Cu")
		(net "NetR85_2")
	)
	(segment
		(start 218.6261 78.4162)
		(end 219.2261 78.4162)
		(width 0.2032)
		(layer "F.Cu")
		(net "NetR85_2")
	)
	(segment
		(start 222.0761 77.2662)
		(end 222.0761 77.1162)
		(width 0.2032)
		(layer "F.Cu")
		(net "NetR84_2")
	)
	(segment
		(start 220.9261 78.4162)
		(end 222.0761 77.2662)
		(width 0.2032)
		(layer "F.Cu")
		(net "NetR84_2")
	)
	(segment
		(start 220.5261 78.4162)
		(end 220.9261 78.4162)
		(width 0.2032)
		(layer "F.Cu")
		(net "NetR84_2")
	)
	(segment
		(start 236.3761 65.6162)
		(end 237.0011 66.2412)
		(width 0.2032)
		(layer "F.Cu")
		(net "NetR42_1")
	)
	(segment
		(start 237.0011 67.2007)
		(end 237.0011 66.2412)
		(width 0.2032)
		(layer "F.Cu")
		(net "NetR42_1")
	)
	(segment
		(start 167.2261 87.3662)
		(end 167.2261 85.56473)
		(width 0.2032)
		(layer "F.Cu")
		(net "NetD25_1")
	)
	(segment
		(start 167.19755 85.53618)
		(end 167.2261 85.56473)
		(width 0.2032)
		(layer "F.Cu")
		(net "NetD25_1")
	)
	(segment
		(start 174.0261 87.2662)
		(end 174.0261 85.8162)
		(width 0.2032)
		(layer "F.Cu")
		(net "NetD24_1")
	)
	(segment
		(start 236.64039 71.93328)
		(end 237.0011 71.57256)
		(width 0.2032)
		(layer "F.Cu")
		(net "NetC92_1")
	)
	(segment
		(start 237.5261 65.08174)
		(end 239.39163 65.08174)
		(width 0.2032)
		(layer "F.Cu")
		(net "NetC92_1")
	)
	(segment
		(start 239.39163 65.08174)
		(end 239.4261 65.1162)
		(width 0.2032)
		(layer "F.Cu")
		(net "NetC92_1")
	)
	(segment
		(start 237.4511 65.15674)
		(end 237.5261 65.08174)
		(width 0.2032)
		(layer "F.Cu")
		(net "NetC92_1")
	)
	(segment
		(start 237.0011 71.57256)
		(end 237.0011 70.0317)
		(width 0.2032)
		(layer "F.Cu")
		(net "NetC92_1")
	)
	(segment
		(start 237.4511 66.17872)
		(end 237.4511 65.15674)
		(width 0.2032)
		(layer "F.Cu")
		(net "NetC92_1")
	)
	(segment
		(start 237.4511 67.2007)
		(end 237.4511 66.17872)
		(width 0.2032)
		(layer "F.Cu")
		(net "NetC92_1")
	)
	(via
		(at 237.4511 66.17872)
		(size 0.4064)
		(drill 0.2032)
		(layers "F.Cu" "B.Cu")
		(net "NetC92_1")
	)
	(via
		(at 236.64039 71.93328)
		(size 0.4064)
		(drill 0.2032)
		(layers "F.Cu" "B.Cu")
		(net "NetC92_1")
	)
	(segment
		(start 236.64039 71.93328)
		(end 236.64039 66.98943)
		(width 0.2032)
		(layer "B.Cu")
		(net "NetC92_1")
	)
	(segment
		(start 236.64039 66.98943)
		(end 237.4511 66.17872)
		(width 0.2032)
		(layer "B.Cu")
		(net "NetC92_1")
	)
	(segment
		(start 236.5511 70.73458)
		(end 236.5511 70.0317)
		(width 0.2032)
		(layer "F.Cu")
		(net "NetC91_1")
	)
	(segment
		(start 235.3511 72.3162)
		(end 235.3511 72.26791)
		(width 0.2032)
		(layer "F.Cu")
		(net "NetC91_1")
	)
	(segment
		(start 235.75641 71.8626)
		(end 235.7797 71.8626)
		(width 0.2032)
		(layer "F.Cu")
		(net "NetC91_1")
	)
	(segment
		(start 235.7261 63.7162)
		(end 236.1511 63.7162)
		(width 0.2032)
		(layer "F.Cu")
		(net "NetC91_1")
	)
	(segment
		(start 235.8669 71.41877)
		(end 236.5511 70.73458)
		(width 0.2032)
		(layer "F.Cu")
		(net "NetC91_1")
	)
	(segment
		(start 235.8669 71.77539)
		(end 235.8669 71.41877)
		(width 0.2032)
		(layer "F.Cu")
		(net "NetC91_1")
	)
	(segment
		(start 235.7261 64.51744)
		(end 235.7261 63.7162)
		(width 0.2032)
		(layer "F.Cu")
		(net "NetC91_1")
	)
	(segment
		(start 235.3511 72.26791)
		(end 235.75641 71.8626)
		(width 0.2032)
		(layer "F.Cu")
		(net "NetC91_1")
	)
	(segment
		(start 235.72353 64.52001)
		(end 235.7261 64.51744)
		(width 0.2032)
		(layer "F.Cu")
		(net "NetC91_1")
	)
	(segment
		(start 236.1511 63.7162)
		(end 237.3261 62.5412)
		(width 0.2032)
		(layer "F.Cu")
		(net "NetC91_1")
	)
	(segment
		(start 235.7797 71.8626)
		(end 235.8669 71.77539)
		(width 0.2032)
		(layer "F.Cu")
		(net "NetC91_1")
	)
	(via
		(at 235.8669 71.41877)
		(size 0.4064)
		(drill 0.2032)
		(layers "F.Cu" "B.Cu")
		(net "NetC91_1")
	)
	(via
		(at 235.72353 64.52001)
		(size 0.4064)
		(drill 0.2032)
		(layers "F.Cu" "B.Cu")
		(net "NetC91_1")
	)
	(segment
		(start 235.72353 71.2754)
		(end 235.72353 64.52001)
		(width 0.2032)
		(layer "B.Cu")
		(net "NetC91_1")
	)
	(segment
		(start 235.72353 71.2754)
		(end 235.8669 71.41877)
		(width 0.2032)
		(layer "B.Cu")
		(net "NetC91_1")
	)
	(segment
		(start 151.74069 124.31241)
		(end 154.60991 124.31241)
		(width 0.2032)
		(layer "F.Cu")
		(net "GPS2_TX_FPGA")
	)
	(segment
		(start 207.5261 77.5162)
		(end 208.4761 77.5162)
		(width 0.2032)
		(layer "F.Cu")
		(net "GPS2_TX_FPGA")
	)
	(segment
		(start 209.98069 75.63383)
		(end 209.99832 75.6162)
		(width 0.2032)
		(layer "F.Cu")
		(net "GPS2_TX_FPGA")
	)
	(segment
		(start 154.60991 124.31241)
		(end 154.6261 124.3286)
		(width 0.2032)
		(layer "F.Cu")
		(net "GPS2_TX_FPGA")
	)
	(segment
		(start 209.99832 75.6162)
		(end 210.8761 75.6162)
		(width 0.2032)
		(layer "F.Cu")
		(net "GPS2_TX_FPGA")
	)
	(via
		(at 207.5261 77.5162)
		(size 0.4064)
		(drill 0.2032)
		(layers "F.Cu" "B.Cu")
		(net "GPS2_TX_FPGA")
	)
	(via
		(at 154.6261 124.3286)
		(size 0.4064)
		(drill 0.2032)
		(layers "F.Cu" "B.Cu")
		(tenting
			(front yes)
			(back yes)
		)
		(net "GPS2_TX_FPGA")
	)
	(via
		(at 209.98069 75.63383)
		(size 0.4064)
		(drill 0.2032)
		(layers "F.Cu" "B.Cu")
		(net "GPS2_TX_FPGA")
	)
	(segment
		(start 154.6261 124.3286)
		(end 155.5137 124.3286)
		(width 0.2032)
		(layer "B.Cu")
		(net "GPS2_TX_FPGA")
	)
	(segment
		(start 155.5137 124.3286)
		(end 159.9261 119.9162)
		(width 0.2032)
		(layer "B.Cu")
		(net "GPS2_TX_FPGA")
	)
	(segment
		(start 207.24828 83.99402)
		(end 208.6261 82.6162)
		(width 0.2032)
		(layer "B.Cu")
		(net "GPS2_TX_FPGA")
	)
	(segment
		(start 202.0261 120.7162)
		(end 207.24828 115.49402)
		(width 0.2032)
		(layer "B.Cu")
		(net "GPS2_TX_FPGA")
	)
	(segment
		(start 207.5261 77.5162)
		(end 209.40847 75.63383)
		(width 0.2032)
		(layer "B.Cu")
		(net "GPS2_TX_FPGA")
	)
	(segment
		(start 207.8261 77.8162)
		(end 208.0261 77.8162)
		(width 0.2032)
		(layer "B.Cu")
		(net "GPS2_TX_FPGA")
	)
	(segment
		(start 195.2261 120.7162)
		(end 202.0261 120.7162)
		(width 0.2032)
		(layer "B.Cu")
		(net "GPS2_TX_FPGA")
	)
	(segment
		(start 194.4261 119.9162)
		(end 195.2261 120.7162)
		(width 0.2032)
		(layer "B.Cu")
		(net "GPS2_TX_FPGA")
	)
	(segment
		(start 207.24828 115.49402)
		(end 207.24828 83.99402)
		(width 0.2032)
		(layer "B.Cu")
		(net "GPS2_TX_FPGA")
	)
	(segment
		(start 209.40847 75.63383)
		(end 209.98069 75.63383)
		(width 0.2032)
		(layer "B.Cu")
		(net "GPS2_TX_FPGA")
	)
	(segment
		(start 208.0261 77.8162)
		(end 208.6261 78.4162)
		(width 0.2032)
		(layer "B.Cu")
		(net "GPS2_TX_FPGA")
	)
	(segment
		(start 159.9261 119.9162)
		(end 194.4261 119.9162)
		(width 0.2032)
		(layer "B.Cu")
		(net "GPS2_TX_FPGA")
	)
	(segment
		(start 208.6261 82.6162)
		(end 208.6261 78.4162)
		(width 0.2032)
		(layer "B.Cu")
		(net "GPS2_TX_FPGA")
	)
	(segment
		(start 207.5261 77.5162)
		(end 207.8261 77.8162)
		(width 0.2032)
		(layer "B.Cu")
		(net "GPS2_TX_FPGA")
	)
	(segment
		(start 208.3761 80.6162)
		(end 208.3761 80.1662)
		(width 0.2032)
		(layer "F.Cu")
		(net "GPS2_RX_FPGA")
	)
	(segment
		(start 208.3761 81.5662)
		(end 208.9261 82.1162)
		(width 0.2032)
		(layer "F.Cu")
		(net "GPS2_RX_FPGA")
	)
	(segment
		(start 208.3761 81.5662)
		(end 208.3761 80.6162)
		(width 0.2032)
		(layer "F.Cu")
		(net "GPS2_RX_FPGA")
	)
	(segment
		(start 145.92989 124.31241)
		(end 147.69091 124.31241)
		(width 0.2032)
		(layer "F.Cu")
		(net "GPS2_RX_FPGA")
	)
	(segment
		(start 145.9261 124.3162)
		(end 145.92989 124.31241)
		(width 0.2032)
		(layer "F.Cu")
		(net "GPS2_RX_FPGA")
	)
	(segment
		(start 207.2261 79.0162)
		(end 208.3761 80.1662)
		(width 0.2032)
		(layer "F.Cu")
		(net "GPS2_RX_FPGA")
	)
	(via
		(at 145.9261 124.3162)
		(size 0.4064)
		(drill 0.2032)
		(layers "F.Cu" "B.Cu")
		(tenting
			(front yes)
			(back yes)
		)
		(net "GPS2_RX_FPGA")
	)
	(via
		(at 207.2261 79.0162)
		(size 0.4064)
		(drill 0.2032)
		(layers "F.Cu" "B.Cu")
		(net "GPS2_RX_FPGA")
	)
	(segment
		(start 160.1261 107.4162)
		(end 177.2261 107.4162)
		(width 0.2032)
		(layer "In2.Cu")
		(net "GPS2_RX_FPGA")
	)
	(segment
		(start 160.1261 112.6162)
		(end 160.1261 107.4162)
		(width 0.2032)
		(layer "In2.Cu")
		(net "GPS2_RX_FPGA")
	)
	(segment
		(start 151.0261 120.8162)
		(end 152.5261 119.3162)
		(width 0.2032)
		(layer "In2.Cu")
		(net "GPS2_RX_FPGA")
	)
	(segment
		(start 153.4261 119.3162)
		(end 160.1261 112.6162)
		(width 0.2032)
		(layer "In2.Cu")
		(net "GPS2_RX_FPGA")
	)
	(segment
		(start 206.7261 79.5162)
		(end 207.2261 79.0162)
		(width 0.2032)
		(layer "In2.Cu")
		(net "GPS2_RX_FPGA")
	)
	(segment
		(start 152.5261 119.3162)
		(end 153.4261 119.3162)
		(width 0.2032)
		(layer "In2.Cu")
		(net "GPS2_RX_FPGA")
	)
	(segment
		(start 148.5261 120.8162)
		(end 151.0261 120.8162)
		(width 0.2032)
		(layer "In2.Cu")
		(net "GPS2_RX_FPGA")
	)
	(segment
		(start 145.9261 124.3162)
		(end 145.9261 123.4162)
		(width 0.2032)
		(layer "In2.Cu")
		(net "GPS2_RX_FPGA")
	)
	(segment
		(start 177.2261 107.4162)
		(end 181.5261 103.1162)
		(width 0.2032)
		(layer "In2.Cu")
		(net "GPS2_RX_FPGA")
	)
	(segment
		(start 183.0261 79.5162)
		(end 206.7261 79.5162)
		(width 0.2032)
		(layer "In2.Cu")
		(net "GPS2_RX_FPGA")
	)
	(segment
		(start 181.5261 103.1162)
		(end 181.5261 81.0162)
		(width 0.2032)
		(layer "In2.Cu")
		(net "GPS2_RX_FPGA")
	)
	(segment
		(start 181.5261 81.0162)
		(end 183.0261 79.5162)
		(width 0.2032)
		(layer "In2.Cu")
		(net "GPS2_RX_FPGA")
	)
	(segment
		(start 145.9261 123.4162)
		(end 148.5261 120.8162)
		(width 0.2032)
		(layer "In2.Cu")
		(net "GPS2_RX_FPGA")
	)
	(segment
		(start 233.85001 82.2162)
		(end 233.9261 82.29228)
		(width 0.2032)
		(layer "F.Cu")
		(net "FTDI_VBUS")
	)
	(segment
		(start 238.2565 71.9162)
		(end 238.96056 71.9162)
		(width 0.2032)
		(layer "F.Cu")
		(net "FTDI_VBUS")
	)
	(segment
		(start 236.2011 72.4162)
		(end 237.7565 72.4162)
		(width 0.2032)
		(layer "F.Cu")
		(net "FTDI_VBUS")
	)
	(segment
		(start 238.25048 71.92222)
		(end 238.25048 71.74058)
		(width 0.2032)
		(layer "F.Cu")
		(net "FTDI_VBUS")
	)
	(segment
		(start 237.4511 70.9412)
		(end 238.25048 71.74058)
		(width 0.2032)
		(layer "F.Cu")
		(net "FTDI_VBUS")
	)
	(segment
		(start 232.20466 83.2162)
		(end 232.20466 82.73764)
		(width 0.2032)
		(layer "F.Cu")
		(net "FTDI_VBUS")
	)
	(segment
		(start 238.25048 71.92222)
		(end 238.2565 71.9162)
		(width 0.2032)
		(layer "F.Cu")
		(net "FTDI_VBUS")
	)
	(segment
		(start 237.4511 70.9412)
		(end 237.4511 70.0317)
		(width 0.2032)
		(layer "F.Cu")
		(net "FTDI_VBUS")
	)
	(segment
		(start 232.7261 82.2162)
		(end 233.85001 82.2162)
		(width 0.2032)
		(layer "F.Cu")
		(net "FTDI_VBUS")
	)
	(segment
		(start 237.7565 72.4162)
		(end 238.25048 71.92222)
		(width 0.2032)
		(layer "F.Cu")
		(net "FTDI_VBUS")
	)
	(segment
		(start 236.1011 72.3162)
		(end 236.2011 72.4162)
		(width 0.2032)
		(layer "F.Cu")
		(net "FTDI_VBUS")
	)
	(segment
		(start 232.20466 82.73764)
		(end 232.7261 82.2162)
		(width 0.2032)
		(layer "F.Cu")
		(net "FTDI_VBUS")
	)
	(via
		(at 232.7261 82.2162)
		(size 0.4064)
		(drill 0.2032)
		(layers "F.Cu" "B.Cu")
		(net "FTDI_VBUS")
	)
	(via
		(at 238.25048 71.92222)
		(size 0.4064)
		(drill 0.2032)
		(layers "F.Cu" "B.Cu")
		(net "FTDI_VBUS")
	)
	(segment
		(start 236.8261 72.8162)
		(end 237.72008 71.92222)
		(width 0.2032)
		(layer "B.Cu")
		(net "FTDI_VBUS")
	)
	(segment
		(start 234.1261 80.8162)
		(end 234.1261 73.1162)
		(width 0.2032)
		(layer "B.Cu")
		(net "FTDI_VBUS")
	)
	(segment
		(start 234.1261 73.1162)
		(end 234.4261 72.8162)
		(width 0.2032)
		(layer "B.Cu")
		(net "FTDI_VBUS")
	)
	(segment
		(start 237.72008 71.92222)
		(end 238.25048 71.92222)
		(width 0.2032)
		(layer "B.Cu")
		(net "FTDI_VBUS")
	)
	(segment
		(start 232.7261 82.2162)
		(end 234.1261 80.8162)
		(width 0.2032)
		(layer "B.Cu")
		(net "FTDI_VBUS")
	)
	(segment
		(start 234.4261 72.8162)
		(end 236.8261 72.8162)
		(width 0.2032)
		(layer "B.Cu")
		(net "FTDI_VBUS")
	)
	(segment
		(start 234.46697 77.9162)
		(end 234.46697 77.67793)
		(width 0.2032)
		(layer "F.Cu")
		(net "FTDI_USB_R_P")
	)
	(segment
		(start 234.0161 76.1662)
		(end 234.7261 75.4562)
		(width 0.2032)
		(layer "F.Cu")
		(net "FTDI_USB_R_P")
	)
	(segment
		(start 234.46697 77.67793)
		(end 234.79717 77.67793)
		(width 0.2032)
		(layer "F.Cu")
		(net "FTDI_USB_R_P")
	)
	(segment
		(start 235.22898 77.9162)
		(end 235.42781 77.9162)
		(width 0.2032)
		(layer "F.Cu")
		(net "FTDI_USB_R_P")
	)
	(segment
		(start 233.4047 77.3162)
		(end 233.62956 77.54105)
		(width 0.2032)
		(layer "F.Cu")
		(net "FTDI_USB_R_P")
	)
	(segment
		(start 234.0047 77.9162)
		(end 234.46697 77.9162)
		(width 0.2032)
		(layer "F.Cu")
		(net "FTDI_USB_R_P")
	)
	(segment
		(start 235.43141 77.9126)
		(end 235.9297 77.9126)
		(width 0.2032)
		(layer "F.Cu")
		(net "FTDI_USB_R_P")
	)
	(segment
		(start 233.4047 77.3162)
		(end 233.4047 76.3876)
		(width 0.2032)
		(layer "F.Cu")
		(net "FTDI_USB_R_P")
	)
	(segment
		(start 235.42781 77.9162)
		(end 235.43141 77.9126)
		(width 0.2032)
		(layer "F.Cu")
		(net "FTDI_USB_R_P")
	)
	(segment
		(start 235.9297 77.9126)
		(end 236.1261 77.7162)
		(width 0.2032)
		(layer "F.Cu")
		(net "FTDI_USB_R_P")
	)
	(segment
		(start 233.4047 76.3876)
		(end 233.6261 76.1662)
		(width 0.2032)
		(layer "F.Cu")
		(net "FTDI_USB_R_P")
	)
	(segment
		(start 233.62956 77.54105)
		(end 234.0047 77.9162)
		(width 0.2032)
		(layer "F.Cu")
		(net "FTDI_USB_R_P")
	)
	(segment
		(start 234.79717 77.9162)
		(end 234.79717 77.67793)
		(width 0.2032)
		(layer "F.Cu")
		(net "FTDI_USB_R_P")
	)
	(segment
		(start 234.79717 77.9162)
		(end 235.22898 77.9162)
		(width 0.2032)
		(layer "F.Cu")
		(net "FTDI_USB_R_P")
	)
	(segment
		(start 233.6261 76.1662)
		(end 234.0161 76.1662)
		(width 0.2032)
		(layer "F.Cu")
		(net "FTDI_USB_R_P")
	)
	(segment
		(start 232.7261 76.1662)
		(end 233.0745 76.5146)
		(width 0.2032)
		(layer "F.Cu")
		(net "FTDI_USB_R_N")
	)
	(segment
		(start 236.0063 78.2464)
		(end 236.1261 78.3662)
		(width 0.2032)
		(layer "F.Cu")
		(net "FTDI_USB_R_N")
	)
	(segment
		(start 233.0745 77.45297)
		(end 233.86793 78.2464)
		(width 0.2032)
		(layer "F.Cu")
		(net "FTDI_USB_R_N")
	)
	(segment
		(start 233.0745 77.45297)
		(end 233.0745 76.5146)
		(width 0.2032)
		(layer "F.Cu")
		(net "FTDI_USB_R_N")
	)
	(segment
		(start 233.86793 78.2464)
		(end 236.0063 78.2464)
		(width 0.2032)
		(layer "F.Cu")
		(net "FTDI_USB_R_N")
	)
	(segment
		(start 231.4361 76.1662)
		(end 232.7261 76.1662)
		(width 0.2032)
		(layer "F.Cu")
		(net "FTDI_USB_R_N")
	)
	(segment
		(start 231.4261 76.1562)
		(end 231.4361 76.1662)
		(width 0.2032)
		(layer "F.Cu")
		(net "FTDI_USB_R_N")
	)
	(segment
		(start 235.4416 67.2007)
		(end 236.1011 67.2007)
		(width 0.2032)
		(layer "F.Cu")
		(net "FTDI_USB_P")
	)
	(segment
		(start 235.0261 68.2162)
		(end 235.0261 67.6162)
		(width 0.2032)
		(layer "F.Cu")
		(net "FTDI_USB_P")
	)
	(segment
		(start 235.0261 67.6162)
		(end 235.4416 67.2007)
		(width 0.2032)
		(layer "F.Cu")
		(net "FTDI_USB_P")
	)
	(segment
		(start 233.4428 75.0829)
		(end 233.6261 75.2662)
		(width 0.2032)
		(layer "F.Cu")
		(net "FTDI_USB_P")
	)
	(segment
		(start 233.4428 75.0829)
		(end 233.4428 74.0162)
		(width 0.2032)
		(layer "F.Cu")
		(net "FTDI_USB_P")
	)
	(via
		(at 233.4428 74.0162)
		(size 0.4064)
		(drill 0.2032)
		(layers "F.Cu" "B.Cu")
		(net "FTDI_USB_P")
	)
	(via
		(at 235.0261 68.2162)
		(size 0.4064)
		(drill 0.2032)
		(layers "F.Cu" "B.Cu")
		(net "FTDI_USB_P")
	)
	(segment
		(start 232.4959 72.32676)
		(end 232.4959 70.0162)
		(width 0.2032)
		(layer "In2.Cu")
		(net "FTDI_USB_P")
	)
	(segment
		(start 234.1261 68.4646)
		(end 234.4264 68.4646)
		(width 0.2032)
		(layer "In2.Cu")
		(net "FTDI_USB_P")
	)
	(segment
		(start 233.35697 74.39898)
		(end 233.50621 75.50583)
		(width 0.2032)
		(layer "In2.Cu")
		(net "FTDI_USB_P")
	)
	(segment
		(start 231.7045 73.27082)
		(end 232.39909 72.57623)
		(width 0.2032)
		(layer "In2.Cu")
		(net "FTDI_USB_P")
	)
	(segment
		(start 231.9531 76.3464)
		(end 232.8261 76.3464)
		(width 0.2032)
		(layer "In2.Cu")
		(net "FTDI_USB_P")
	)
	(segment
		(start 233.35697 74.39898)
		(end 233.35697 74.22341)
		(width 0.2032)
		(layer "In2.Cu")
		(net "FTDI_USB_P")
	)
	(segment
		(start 232.59194 69.78339)
		(end 233.7577 68.61763)
		(width 0.2032)
		(layer "In2.Cu")
		(net "FTDI_USB_P")
	)
	(segment
		(start 233.06026 76.24901)
		(end 233.13419 76.17509)
		(width 0.2032)
		(layer "In2.Cu")
		(net "FTDI_USB_P")
	)
	(segment
		(start 231.6229 76.0162)
		(end 231.6229 73.46783)
		(width 0.2032)
		(layer "In2.Cu")
		(net "FTDI_USB_P")
	)
	(arc
		(start 231.6229 73.46783)
		(mid 231.644108 73.361211)
		(end 231.704503 73.270823)
		(width 0.2032)
		(layer "In2.Cu")
		(net "FTDI_USB_P")
	)
	(arc
		(start 233.475948 75.696648)
		(mid 233.325056 75.949976)
		(end 233.134388 76.174895)
		(width 0.2032)
		(layer "In2.Cu")
		(net "FTDI_USB_P")
	)
	(arc
		(start 233.50621 75.505827)
		(mid 233.505462 75.602736)
		(end 233.476611 75.695254)
		(width 0.2032)
		(layer "In2.Cu")
		(net "FTDI_USB_P")
	)
	(arc
		(start 233.7577 68.617631)
		(mid 233.92664 68.504379)
		(end 234.1261 68.4646)
		(width 0.2032)
		(layer "In2.Cu")
		(net "FTDI_USB_P")
	)
	(arc
		(start 232.495897 72.326752)
		(mid 232.451502 72.453046)
		(end 232.399088 72.576228)
		(width 0.2032)
		(layer "In2.Cu")
		(net "FTDI_USB_P")
	)
	(arc
		(start 233.060258 76.249014)
		(mid 232.952901 76.321083)
		(end 232.8261 76.3464)
		(width 0.2032)
		(layer "In2.Cu")
		(net "FTDI_USB_P")
	)
	(arc
		(start 231.9531 76.3464)
		(mid 231.719613 76.249687)
		(end 231.6229 76.0162)
		(width 0.2032)
		(layer "In2.Cu")
		(net "FTDI_USB_P")
	)
	(arc
		(start 233.35697 74.22341)
		(mid 233.379277 74.111265)
		(end 233.442802 74.016192)
		(width 0.2032)
		(layer "In2.Cu")
		(net "FTDI_USB_P")
	)
	(arc
		(start 232.4959 70.0162)
		(mid 232.520853 69.890279)
		(end 232.59194 69.783389)
		(width 0.2032)
		(layer "In2.Cu")
		(net "FTDI_USB_P")
	)
	(arc
		(start 235.026097 68.216197)
		(mid 234.750954 68.400042)
		(end 234.4264 68.4646)
		(width 0.2032)
		(layer "In2.Cu")
		(net "FTDI_USB_P")
	)
	(segment
		(start 235.0261 69.6162)
		(end 235.4416 70.0317)
		(width 0.2032)
		(layer "F.Cu")
		(net "FTDI_USB_N")
	)
	(segment
		(start 235.4416 70.0317)
		(end 236.1011 70.0317)
		(width 0.2032)
		(layer "F.Cu")
		(net "FTDI_USB_N")
	)
	(segment
		(start 232.9094 75.0829)
		(end 232.9094 74.0162)
		(width 0.2032)
		(layer "F.Cu")
		(net "FTDI_USB_N")
	)
	(segment
		(start 232.7261 75.2662)
		(end 232.9094 75.0829)
		(width 0.2032)
		(layer "F.Cu")
		(net "FTDI_USB_N")
	)
	(segment
		(start 235.0261 69.6162)
		(end 235.0261 68.9162)
		(width 0.2032)
		(layer "F.Cu")
		(net "FTDI_USB_N")
	)
	(via
		(at 235.0261 68.9162)
		(size 0.4064)
		(drill 0.2032)
		(layers "F.Cu" "B.Cu")
		(net "FTDI_USB_N")
	)
	(via
		(at 232.9094 74.0162)
		(size 0.4064)
		(drill 0.2032)
		(layers "F.Cu" "B.Cu")
		(net "FTDI_USB_N")
	)
	(segment
		(start 234.1261 68.7948)
		(end 234.4264 68.7948)
		(width 0.2032)
		(layer "In2.Cu")
		(net "FTDI_USB_N")
	)
	(segment
		(start 232.1563 74.12216)
		(end 232.15633 74.12216)
		(width 0.2032)
		(layer "In2.Cu")
		(net "FTDI_USB_N")
	)
	(segment
		(start 233.0293 70.32101)
		(end 233.06784 70.32101)
		(width 0.2032)
		(layer "In2.Cu")
		(net "FTDI_USB_N")
	)
	(segment
		(start 231.9531 76.0162)
		(end 231.9531 75.86163)
		(width 0.2032)
		(layer "In2.Cu")
		(net "FTDI_USB_N")
	)
	(segment
		(start 233.0261 74.4162)
		(end 233.17922 75.55176)
		(width 0.2032)
		(layer "In2.Cu")
		(net "FTDI_USB_N")
	)
	(segment
		(start 232.8261 70.0162)
		(end 233.99192 68.85038)
		(width 0.2032)
		(layer "In2.Cu")
		(net "FTDI_USB_N")
	)
	(segment
		(start 232.8261 76.0162)
		(end 232.90184 75.94046)
		(width 0.2032)
		(layer "In2.Cu")
		(net "FTDI_USB_N")
	)
	(segment
		(start 231.9531 75.86163)
		(end 231.9531 74.65556)
		(width 0.2032)
		(layer "In2.Cu")
		(net "FTDI_USB_N")
	)
	(segment
		(start 231.9531 76.0162)
		(end 232.8261 76.0162)
		(width 0.2032)
		(layer "In2.Cu")
		(net "FTDI_USB_N")
	)
	(segment
		(start 232.9912 70.98141)
		(end 233.06784 70.98141)
		(width 0.2032)
		(layer "In2.Cu")
		(net "FTDI_USB_N")
	)
	(segment
		(start 232.1563 74.45236)
		(end 232.15633 74.45236)
		(width 0.2032)
		(layer "In2.Cu")
		(net "FTDI_USB_N")
	)
	(segment
		(start 233.17922 75.55177)
		(end 233.17922 75.55176)
		(width 0.2032)
		(layer "In2.Cu")
		(net "FTDI_USB_N")
	)
	(segment
		(start 232.9912 70.65121)
		(end 233.06784 70.65121)
		(width 0.2032)
		(layer "In2.Cu")
		(net "FTDI_USB_N")
	)
	(segment
		(start 233.0261 74.4162)
		(end 233.0261 74.29794)
		(width 0.2032)
		(layer "In2.Cu")
		(net "FTDI_USB_N")
	)
	(segment
		(start 232.1261 73.3162)
		(end 232.67241 72.76988)
		(width 0.2032)
		(layer "In2.Cu")
		(net "FTDI_USB_N")
	)
	(segment
		(start 231.9531 73.91896)
		(end 231.9531 73.81735)
		(width 0.2032)
		(layer "In2.Cu")
		(net "FTDI_USB_N")
	)
	(segment
		(start 232.8261 72.39885)
		(end 232.8261 71.51481)
		(width 0.2032)
		(layer "In2.Cu")
		(net "FTDI_USB_N")
	)
	(segment
		(start 232.8261 70.11781)
		(end 232.8261 70.0162)
		(width 0.2032)
		(layer "In2.Cu")
		(net "FTDI_USB_N")
	)
	(segment
		(start 231.9531 73.81735)
		(end 231.9531 73.54646)
		(width 0.2032)
		(layer "In2.Cu")
		(net "FTDI_USB_N")
	)
	(segment
		(start 233.0293 71.31161)
		(end 233.06784 71.31161)
		(width 0.2032)
		(layer "In2.Cu")
		(net "FTDI_USB_N")
	)
	(arc
		(start 232.909407 74.016193)
		(mid 232.99578 74.14546)
		(end 233.02611 74.29794)
		(width 0.2032)
		(layer "In2.Cu")
		(net "FTDI_USB_N")
	)
	(arc
		(start 233.17923 75.551769)
		(mid 233.056665 75.757626)
		(end 232.901846 75.940466)
		(width 0.2032)
		(layer "In2.Cu")
		(net "FTDI_USB_N")
	)
	(arc
		(start 232.15633 74.12216)
		(mid 232.32143 74.28726)
		(end 232.15633 74.45236)
		(width 0.2032)
		(layer "In2.Cu")
		(net "FTDI_USB_N")
	)
	(arc
		(start 233.06784 70.32101)
		(mid 233.23294 70.48611)
		(end 233.06784 70.65121)
		(width 0.2032)
		(layer "In2.Cu")
		(net "FTDI_USB_N")
	)
	(arc
		(start 232.8261 72.39885)
		(mid 232.825628 72.421103)
		(end 232.824213 72.443315)
		(width 0.2032)
		(layer "In2.Cu")
		(net "FTDI_USB_N")
	)
	(arc
		(start 234.774076 68.742338)
		(mid 234.602206 68.78161)
		(end 234.4264 68.7948)
		(width 0.2032)
		(layer "In2.Cu")
		(net "FTDI_USB_N")
	)
	(arc
		(start 233.991926 68.850376)
		(mid 234.053486 68.809243)
		(end 234.1261 68.794799)
		(width 0.2032)
		(layer "In2.Cu")
		(net "FTDI_USB_N")
	)
	(arc
		(start 231.953102 73.546459)
		(mid 232.031467 73.425218)
		(end 232.126099 73.316199)
		(width 0.2032)
		(layer "In2.Cu")
		(net "FTDI_USB_N")
	)
	(arc
		(start 232.824213 72.443315)
		(mid 232.777207 72.62003)
		(end 232.672413 72.769883)
		(width 0.2032)
		(layer "In2.Cu")
		(net "FTDI_USB_N")
	)
	(arc
		(start 233.0293 70.32101)
		(mid 232.885616 70.261494)
		(end 232.8261 70.11781)
		(width 0.2032)
		(layer "In2.Cu")
		(net "FTDI_USB_N")
	)
	(arc
		(start 232.1563 74.12216)
		(mid 232.012616 74.062644)
		(end 231.9531 73.91896)
		(width 0.2032)
		(layer "In2.Cu")
		(net "FTDI_USB_N")
	)
	(arc
		(start 233.06784 70.98141)
		(mid 233.23294 71.14651)
		(end 233.06784 71.31161)
		(width 0.2032)
		(layer "In2.Cu")
		(net "FTDI_USB_N")
	)
	(arc
		(start 232.8261 71.51481)
		(mid 232.885616 71.371126)
		(end 233.0293 71.31161)
		(width 0.2032)
		(layer "In2.Cu")
		(net "FTDI_USB_N")
	)
	(arc
		(start 232.9912 70.98141)
		(mid 232.8261 70.81631)
		(end 232.9912 70.65121)
		(width 0.2032)
		(layer "In2.Cu")
		(net "FTDI_USB_N")
	)
	(arc
		(start 231.9531 74.65556)
		(mid 232.012616 74.511876)
		(end 232.1563 74.45236)
		(width 0.2032)
		(layer "In2.Cu")
		(net "FTDI_USB_N")
	)
	(arc
		(start 234.774078 68.742331)
		(mid 234.907998 68.817795)
		(end 235.026097 68.916193)
		(width 0.2032)
		(layer "In2.Cu")
		(net "FTDI_USB_N")
	)
	(segment
		(start 215.96431 80.0162)
		(end 215.96921 80.0211)
		(width 0.2032)
		(layer "F.Cu")
		(net "FTDI_TX")
	)
	(segment
		(start 240.0261 68.15454)
		(end 240.0261 67.3662)
		(width 0.2032)
		(layer "F.Cu")
		(net "FTDI_TX")
	)
	(segment
		(start 214.5761 80.0162)
		(end 215.96431 80.0162)
		(width 0.2032)
		(layer "F.Cu")
		(net "FTDI_TX")
	)
	(segment
		(start 240.0261 68.15454)
		(end 240.05677 68.18521)
		(width 0.2032)
		(layer "F.Cu")
		(net "FTDI_TX")
	)
	(segment
		(start 216.0712 80.0211)
		(end 216.7761 79.3162)
		(width 0.2032)
		(layer "F.Cu")
		(net "FTDI_TX")
	)
	(segment
		(start 215.96921 80.0211)
		(end 216.0712 80.0211)
		(width 0.2032)
		(layer "F.Cu")
		(net "FTDI_TX")
	)
	(segment
		(start 215.96921 80.10931)
		(end 216.6761 80.8162)
		(width 0.2032)
		(layer "F.Cu")
		(net "FTDI_TX")
	)
	(segment
		(start 215.96921 80.10931)
		(end 215.96921 80.0211)
		(width 0.2032)
		(layer "F.Cu")
		(net "FTDI_TX")
	)
	(via
		(at 215.96921 80.0211)
		(size 0.4064)
		(drill 0.2032)
		(layers "F.Cu" "B.Cu")
		(net "FTDI_TX")
	)
	(via
		(at 240.05677 68.18521)
		(size 0.4064)
		(drill 0.2032)
		(layers "F.Cu" "B.Cu")
		(net "FTDI_TX")
	)
	(segment
		(start 219.2261 76.2162)
		(end 224.2261 71.2162)
		(width 0.2032)
		(layer "In2.Cu")
		(net "FTDI_TX")
	)
	(segment
		(start 218.4261 78.0162)
		(end 218.7261 77.7162)
		(width 0.2032)
		(layer "In2.Cu")
		(net "FTDI_TX")
	)
	(segment
		(start 218.8261 77.7162)
		(end 219.2261 77.3162)
		(width 0.2032)
		(layer "In2.Cu")
		(net "FTDI_TX")
	)
	(segment
		(start 219.2261 77.3162)
		(end 219.2261 76.2162)
		(width 0.2032)
		(layer "In2.Cu")
		(net "FTDI_TX")
	)
	(segment
		(start 227.1261 69.0162)
		(end 230.98655 69.0162)
		(width 0.2032)
		(layer "In2.Cu")
		(net "FTDI_TX")
	)
	(segment
		(start 224.2261 70.0162)
		(end 224.4261 69.8162)
		(width 0.2032)
		(layer "In2.Cu")
		(net "FTDI_TX")
	)
	(segment
		(start 226.3261 69.8162)
		(end 227.1261 69.0162)
		(width 0.2032)
		(layer "In2.Cu")
		(net "FTDI_TX")
	)
	(segment
		(start 217.2261 78.2162)
		(end 217.4261 78.0162)
		(width 0.2032)
		(layer "In2.Cu")
		(net "FTDI_TX")
	)
	(segment
		(start 218.7261 77.7162)
		(end 218.8261 77.7162)
		(width 0.2032)
		(layer "In2.Cu")
		(net "FTDI_TX")
	)
	(segment
		(start 217.4261 78.0162)
		(end 218.4261 78.0162)
		(width 0.2032)
		(layer "In2.Cu")
		(net "FTDI_TX")
	)
	(segment
		(start 215.96921 80.0211)
		(end 217.2261 78.76422)
		(width 0.2032)
		(layer "In2.Cu")
		(net "FTDI_TX")
	)
	(segment
		(start 217.2261 78.76422)
		(end 217.2261 78.2162)
		(width 0.2032)
		(layer "In2.Cu")
		(net "FTDI_TX")
	)
	(segment
		(start 230.98655 69.0162)
		(end 232.78655 67.2162)
		(width 0.2032)
		(layer "In2.Cu")
		(net "FTDI_TX")
	)
	(segment
		(start 224.2261 71.2162)
		(end 224.2261 70.0162)
		(width 0.2032)
		(layer "In2.Cu")
		(net "FTDI_TX")
	)
	(segment
		(start 224.4261 69.8162)
		(end 226.3261 69.8162)
		(width 0.2032)
		(layer "In2.Cu")
		(net "FTDI_TX")
	)
	(segment
		(start 232.78655 67.2162)
		(end 239.08776 67.2162)
		(width 0.2032)
		(layer "In2.Cu")
		(net "FTDI_TX")
	)
	(segment
		(start 239.08776 67.2162)
		(end 240.05677 68.18521)
		(width 0.2032)
		(layer "In2.Cu")
		(net "FTDI_TX")
	)
	(segment
		(start 234.7261 65.9162)
		(end 235.0261 65.6162)
		(width 0.2032)
		(layer "F.Cu")
		(net "FTDI_RX")
	)
	(segment
		(start 216.7761 77.9162)
		(end 216.7761 77.62649)
		(width 0.2032)
		(layer "F.Cu")
		(net "FTDI_RX")
	)
	(segment
		(start 216.0595 76.90989)
		(end 217.0532 75.9162)
		(width 0.2032)
		(layer "F.Cu")
		(net "FTDI_RX")
	)
	(segment
		(start 214.0261 76.2662)
		(end 215.27001 76.2662)
		(width 0.2032)
		(layer "F.Cu")
		(net "FTDI_RX")
	)
	(segment
		(start 235.0261 65.6162)
		(end 235.4761 65.6162)
		(width 0.2032)
		(layer "F.Cu")
		(net "FTDI_RX")
	)
	(segment
		(start 217.0532 75.9162)
		(end 217.6261 75.9162)
		(width 0.2032)
		(layer "F.Cu")
		(net "FTDI_RX")
	)
	(segment
		(start 215.27001 76.2662)
		(end 215.34291 76.1933)
		(width 0.2032)
		(layer "F.Cu")
		(net "FTDI_RX")
	)
	(segment
		(start 216.0595 76.90989)
		(end 216.7761 77.62649)
		(width 0.2032)
		(layer "F.Cu")
		(net "FTDI_RX")
	)
	(segment
		(start 215.34291 76.1933)
		(end 216.0595 76.90989)
		(width 0.2032)
		(layer "F.Cu")
		(net "FTDI_RX")
	)
	(via
		(at 215.34291 76.1933)
		(size 0.4064)
		(drill 0.2032)
		(layers "F.Cu" "B.Cu")
		(net "FTDI_RX")
	)
	(via
		(at 234.7261 65.9162)
		(size 0.4064)
		(drill 0.2032)
		(layers "F.Cu" "B.Cu")
		(net "FTDI_RX")
	)
	(segment
		(start 219.5261 74.1162)
		(end 219.5261 72.3162)
		(width 0.2032)
		(layer "In2.Cu")
		(net "FTDI_RX")
	)
	(segment
		(start 233.9261 66.7162)
		(end 234.7261 65.9162)
		(width 0.2032)
		(layer "In2.Cu")
		(net "FTDI_RX")
	)
	(segment
		(start 219.5261 72.3162)
		(end 225.1261 66.7162)
		(width 0.2032)
		(layer "In2.Cu")
		(net "FTDI_RX")
	)
	(segment
		(start 225.1261 66.7162)
		(end 233.9261 66.7162)
		(width 0.2032)
		(layer "In2.Cu")
		(net "FTDI_RX")
	)
	(segment
		(start 217.449 76.1933)
		(end 219.5261 74.1162)
		(width 0.2032)
		(layer "In2.Cu")
		(net "FTDI_RX")
	)
	(segment
		(start 215.34291 76.1933)
		(end 217.449 76.1933)
		(width 0.2032)
		(layer "In2.Cu")
		(net "FTDI_RX")
	)
	(segment
		(start 122.2535 85.4436)
		(end 122.7261 85.9162)
		(width 0.254)
		(layer "F.Cu")
		(net "FPGA_MAC_PPSDIFF_OUT")
	)
	(segment
		(start 122.7261 86.3162)
		(end 122.7261 85.9162)
		(width 0.254)
		(layer "F.Cu")
		(net "FPGA_MAC_PPSDIFF_OUT")
	)
	(segment
		(start 122.8261 86.2162)
		(end 123.4511 86.2162)
		(width 0.2032)
		(layer "F.Cu")
		(net "FPGA_MAC_PPSDIFF_OUT")
	)
	(segment
		(start 124.3261 88.3162)
		(end 124.7511 88.3162)
		(width 0.254)
		(layer "F.Cu")
		(net "FPGA_MAC_PPSDIFF_OUT")
	)
	(segment
		(start 122.7261 86.7162)
		(end 122.7261 86.3162)
		(width 0.254)
		(layer "F.Cu")
		(net "FPGA_MAC_PPSDIFF_OUT")
	)
	(segment
		(start 122.7261 86.3162)
		(end 122.8261 86.2162)
		(width 0.2032)
		(layer "F.Cu")
		(net "FPGA_MAC_PPSDIFF_OUT")
	)
	(segment
		(start 120.9761 85.4436)
		(end 122.2535 85.4436)
		(width 0.254)
		(layer "F.Cu")
		(net "FPGA_MAC_PPSDIFF_OUT")
	)
	(segment
		(start 122.7261 86.7162)
		(end 124.3261 88.3162)
		(width 0.254)
		(layer "F.Cu")
		(net "FPGA_MAC_PPSDIFF_OUT")
	)
	(segment
		(start 131.5761 87.9162)
		(end 131.5761 87.9162)
		(width 0.2032)
		(layer "F.Cu")
		(net "FPGA_MAC_PPS_DIFF_IN0")
	)
	(segment
		(start 129.1261 86.8162)
		(end 129.1261 86.0912)
		(width 0.2032)
		(layer "F.Cu")
		(net "FPGA_MAC_PPS_DIFF_IN0")
	)
	(segment
		(start 128.0011 88.3162)
		(end 128.4261 87.8912)
		(width 0.2032)
		(layer "F.Cu")
		(net "FPGA_MAC_PPS_DIFF_IN0")
	)
	(segment
		(start 130.4761 86.8162)
		(end 131.5761 87.9162)
		(width 0.2032)
		(layer "F.Cu")
		(net "FPGA_MAC_PPS_DIFF_IN0")
	)
	(segment
		(start 132.8937 86.5986)
		(end 134.1261 86.5986)
		(width 0.2032)
		(layer "F.Cu")
		(net "FPGA_MAC_PPS_DIFF_IN0")
	)
	(segment
		(start 131.5761 87.9162)
		(end 132.8937 86.5986)
		(width 0.2032)
		(layer "F.Cu")
		(net "FPGA_MAC_PPS_DIFF_IN0")
	)
	(segment
		(start 128.4261 87.5162)
		(end 129.1261 86.8162)
		(width 0.2032)
		(layer "F.Cu")
		(net "FPGA_MAC_PPS_DIFF_IN0")
	)
	(segment
		(start 129.1261 86.8162)
		(end 130.4761 86.8162)
		(width 0.2032)
		(layer "F.Cu")
		(net "FPGA_MAC_PPS_DIFF_IN0")
	)
	(segment
		(start 128.4261 87.8912)
		(end 128.4261 87.5162)
		(width 0.2032)
		(layer "F.Cu")
		(net "FPGA_MAC_PPS_DIFF_IN0")
	)
	(segment
		(start 203.7261 80.5162)
		(end 207.8261 76.4162)
		(width 0.2032)
		(layer "F.Cu")
		(net "DIP_SW_UART_SEL")
	)
	(segment
		(start 167.1761 83.2162)
		(end 169.5661 83.2162)
		(width 0.2032)
		(layer "F.Cu")
		(net "DIP_SW_UART_SEL")
	)
	(segment
		(start 218.7261 80.5162)
		(end 218.7261 80.1162)
		(width 0.2032)
		(layer "F.Cu")
		(net "DIP_SW_UART_SEL")
	)
	(segment
		(start 170.1261 83.7062)
		(end 170.1261 83.3162)
		(width 0.2032)
		(layer "F.Cu")
		(net "DIP_SW_UART_SEL")
	)
	(segment
		(start 173.8261 80.5162)
		(end 203.7261 80.5162)
		(width 0.2032)
		(layer "F.Cu")
		(net "DIP_SW_UART_SEL")
	)
	(segment
		(start 170.74012 82.70218)
		(end 171.64012 82.70218)
		(width 0.2032)
		(layer "F.Cu")
		(net "DIP_SW_UART_SEL")
	)
	(segment
		(start 170.1261 83.3162)
		(end 170.74012 82.70218)
		(width 0.2032)
		(layer "F.Cu")
		(net "DIP_SW_UART_SEL")
	)
	(segment
		(start 218.6261 77.2162)
		(end 219.4261 78.0162)
		(width 0.2032)
		(layer "F.Cu")
		(net "DIP_SW_UART_SEL")
	)
	(segment
		(start 209.9261 76.4162)
		(end 211.0761 77.5662)
		(width 0.2032)
		(layer "F.Cu")
		(net "DIP_SW_UART_SEL")
	)
	(segment
		(start 171.64012 82.70218)
		(end 173.8261 80.5162)
		(width 0.2032)
		(layer "F.Cu")
		(net "DIP_SW_UART_SEL")
	)
	(segment
		(start 210.4261 81.0162)
		(end 210.8761 80.5662)
		(width 0.2032)
		(layer "F.Cu")
		(net "DIP_SW_UART_SEL")
	)
	(segment
		(start 210.8761 80.5662)
		(end 210.8761 79.6162)
		(width 0.2032)
		(layer "F.Cu")
		(net "DIP_SW_UART_SEL")
	)
	(segment
		(start 170.0911 83.7412)
		(end 170.1261 83.7062)
		(width 0.2032)
		(layer "F.Cu")
		(net "DIP_SW_UART_SEL")
	)
	(segment
		(start 218.7261 80.1162)
		(end 219.2261 79.6162)
		(width 0.2032)
		(layer "F.Cu")
		(net "DIP_SW_UART_SEL")
	)
	(segment
		(start 167.19755 84.53188)
		(end 167.19755 83.23765)
		(width 0.2032)
		(layer "F.Cu")
		(net "DIP_SW_UART_SEL")
	)
	(segment
		(start 211.0761 78.0162)
		(end 211.0761 77.5662)
		(width 0.2032)
		(layer "F.Cu")
		(net "DIP_SW_UART_SEL")
	)
	(segment
		(start 207.8261 76.4162)
		(end 209.9261 76.4162)
		(width 0.2032)
		(layer "F.Cu")
		(net "DIP_SW_UART_SEL")
	)
	(segment
		(start 218.6261 77.2162)
		(end 218.6261 77.2162)
		(width 0.2032)
		(layer "F.Cu")
		(net "DIP_SW_UART_SEL")
	)
	(segment
		(start 167.1761 83.2162)
		(end 167.19755 83.23765)
		(width 0.2032)
		(layer "F.Cu")
		(net "DIP_SW_UART_SEL")
	)
	(segment
		(start 169.5661 83.2162)
		(end 170.0911 83.7412)
		(width 0.2032)
		(layer "F.Cu")
		(net "DIP_SW_UART_SEL")
	)
	(via
		(at 210.4261 81.0162)
		(size 0.4064)
		(drill 0.2032)
		(layers "F.Cu" "B.Cu")
		(net "DIP_SW_UART_SEL")
	)
	(via
		(at 218.6261 77.2162)
		(size 0.4064)
		(drill 0.2032)
		(layers "F.Cu" "B.Cu")
		(net "DIP_SW_UART_SEL")
	)
	(via
		(at 218.7261 80.5162)
		(size 0.4064)
		(drill 0.2032)
		(layers "F.Cu" "B.Cu")
		(net "DIP_SW_UART_SEL")
	)
	(via
		(at 209.9261 76.4162)
		(size 0.4064)
		(drill 0.2032)
		(layers "F.Cu" "B.Cu")
		(net "DIP_SW_UART_SEL")
	)
	(segment
		(start 218.6261 77.2162)
		(end 218.7261 77.3162)
		(width 0.2032)
		(layer "B.Cu")
		(net "DIP_SW_UART_SEL")
	)
	(segment
		(start 217.7261 81.5162)
		(end 218.7261 80.5162)
		(width 0.2032)
		(layer "B.Cu")
		(net "DIP_SW_UART_SEL")
	)
	(segment
		(start 210.4261 81.0162)
		(end 210.9261 81.5162)
		(width 0.2032)
		(layer "B.Cu")
		(net "DIP_SW_UART_SEL")
	)
	(segment
		(start 210.9261 81.5162)
		(end 217.7261 81.5162)
		(width 0.2032)
		(layer "B.Cu")
		(net "DIP_SW_UART_SEL")
	)
	(segment
		(start 210.4261 81.0162)
		(end 210.4261 76.9162)
		(width 0.2032)
		(layer "B.Cu")
		(net "DIP_SW_UART_SEL")
	)
	(segment
		(start 209.9261 76.4162)
		(end 210.4261 76.9162)
		(width 0.2032)
		(layer "B.Cu")
		(net "DIP_SW_UART_SEL")
	)
	(segment
		(start 218.7261 80.5162)
		(end 218.7261 77.3162)
		(width 0.2032)
		(layer "B.Cu")
		(net "DIP_SW_UART_SEL")
	)
	(segment
		(start 173.8261 81.4162)
		(end 174.0511 81.6412)
		(width 0.2032)
		(layer "F.Cu")
		(net "DIP_SW_PPS_SEL")
	)
	(segment
		(start 174.0511 83.3162)
		(end 174.0511 81.6412)
		(width 0.2032)
		(layer "F.Cu")
		(net "DIP_SW_PPS_SEL")
	)
	(segment
		(start 174.0511 84.7869)
		(end 174.0511 83.3162)
		(width 0.2032)
		(layer "F.Cu")
		(net "DIP_SW_PPS_SEL")
	)
	(segment
		(start 127.0261 86.5662)
		(end 127.24795 86.5662)
		(width 0.2032)
		(layer "F.Cu")
		(net "DIP_SW_PPS_SEL")
	)
	(segment
		(start 124.60939 87.18291)
		(end 125.4261 86.3662)
		(width 0.2032)
		(layer "F.Cu")
		(net "DIP_SW_PPS_SEL")
	)
	(segment
		(start 124.40356 87.18291)
		(end 124.60939 87.18291)
		(width 0.2032)
		(layer "F.Cu")
		(net "DIP_SW_PPS_SEL")
	)
	(segment
		(start 174.0261 84.81191)
		(end 174.0511 84.7869)
		(width 0.2032)
		(layer "F.Cu")
		(net "DIP_SW_PPS_SEL")
	)
	(segment
		(start 127.24795 86.5662)
		(end 127.73756 87.05581)
		(width 0.2032)
		(layer "F.Cu")
		(net "DIP_SW_PPS_SEL")
	)
	(segment
		(start 173.6261 83.7412)
		(end 174.0511 83.3162)
		(width 0.2032)
		(layer "F.Cu")
		(net "DIP_SW_PPS_SEL")
	)
	(segment
		(start 171.3611 83.7412)
		(end 173.6261 83.7412)
		(width 0.2032)
		(layer "F.Cu")
		(net "DIP_SW_PPS_SEL")
	)
	(via
		(at 127.73756 87.05581)
		(size 0.4064)
		(drill 0.2032)
		(layers "F.Cu" "B.Cu")
		(net "DIP_SW_PPS_SEL")
	)
	(via
		(at 173.8261 81.4162)
		(size 0.4064)
		(drill 0.2032)
		(layers "F.Cu" "B.Cu")
		(net "DIP_SW_PPS_SEL")
	)
	(via
		(at 124.40356 87.18291)
		(size 0.4064)
		(drill 0.2032)
		(layers "F.Cu" "B.Cu")
		(net "DIP_SW_PPS_SEL")
	)
	(segment
		(start 145.5261 85.3162)
		(end 145.5261 83.1162)
		(width 0.2032)
		(layer "In2.Cu")
		(net "DIP_SW_PPS_SEL")
	)
	(segment
		(start 161.1261 88.2162)
		(end 163.63889 85.70341)
		(width 0.2032)
		(layer "In2.Cu")
		(net "DIP_SW_PPS_SEL")
	)
	(segment
		(start 124.53066 87.05581)
		(end 127.73756 87.05581)
		(width 0.2032)
		(layer "In2.Cu")
		(net "DIP_SW_PPS_SEL")
	)
	(segment
		(start 128.6261 86.0162)
		(end 132.0261 82.6162)
		(width 0.2032)
		(layer "In2.Cu")
		(net "DIP_SW_PPS_SEL")
	)
	(segment
		(start 145.5261 85.3162)
		(end 148.4261 88.2162)
		(width 0.2032)
		(layer "In2.Cu")
		(net "DIP_SW_PPS_SEL")
	)
	(segment
		(start 164.7261 82.9162)
		(end 171.0261 82.9162)
		(width 0.2032)
		(layer "In2.Cu")
		(net "DIP_SW_PPS_SEL")
	)
	(segment
		(start 163.63889 85.70341)
		(end 163.63889 84.90341)
		(width 0.2032)
		(layer "In2.Cu")
		(net "DIP_SW_PPS_SEL")
	)
	(segment
		(start 164.7261 83.8162)
		(end 164.7261 82.9162)
		(width 0.2032)
		(layer "In2.Cu")
		(net "DIP_SW_PPS_SEL")
	)
	(segment
		(start 128.6261 86.3662)
		(end 128.6261 86.0162)
		(width 0.2032)
		(layer "In2.Cu")
		(net "DIP_SW_PPS_SEL")
	)
	(segment
		(start 127.73756 87.05581)
		(end 127.93649 87.05581)
		(width 0.2032)
		(layer "In2.Cu")
		(net "DIP_SW_PPS_SEL")
	)
	(segment
		(start 127.93649 87.05581)
		(end 128.6261 86.3662)
		(width 0.2032)
		(layer "In2.Cu")
		(net "DIP_SW_PPS_SEL")
	)
	(segment
		(start 132.0261 82.6162)
		(end 145.0261 82.6162)
		(width 0.2032)
		(layer "In2.Cu")
		(net "DIP_SW_PPS_SEL")
	)
	(segment
		(start 145.0261 82.6162)
		(end 145.5261 83.1162)
		(width 0.2032)
		(layer "In2.Cu")
		(net "DIP_SW_PPS_SEL")
	)
	(segment
		(start 163.63889 84.90341)
		(end 164.7261 83.8162)
		(width 0.2032)
		(layer "In2.Cu")
		(net "DIP_SW_PPS_SEL")
	)
	(segment
		(start 124.40356 87.18291)
		(end 124.53066 87.05581)
		(width 0.2032)
		(layer "In2.Cu")
		(net "DIP_SW_PPS_SEL")
	)
	(segment
		(start 171.0261 82.9162)
		(end 172.5261 81.4162)
		(width 0.2032)
		(layer "In2.Cu")
		(net "DIP_SW_PPS_SEL")
	)
	(segment
		(start 148.4261 88.2162)
		(end 161.1261 88.2162)
		(width 0.2032)
		(layer "In2.Cu")
		(net "DIP_SW_PPS_SEL")
	)
	(segment
		(start 172.5261 81.4162)
		(end 173.8261 81.4162)
		(width 0.2032)
		(layer "In2.Cu")
		(net "DIP_SW_PPS_SEL")
	)
	(segment
		(start 206.20466 111.4162)
		(end 206.60466 111.0162)
		(width 0.254)
		(layer "F.Cu")
		(net "P5V_VDD")
	)
	(segment
		(start 206.60466 111.0162)
		(end 207.32611 111.0162)
		(width 0.254)
		(layer "F.Cu")
		(net "P5V_VDD")
	)
	(segment
		(start 207.32611 111.0162)
		(end 207.38725 110.95506)
		(width 0.254)
		(layer "F.Cu")
		(net "P5V_VDD")
	)
	(segment
		(start 207.38725 110.95506)
		(end 208.7644 110.95506)
		(width 0.254)
		(layer "F.Cu")
		(net "P5V_VDD")
	)
	(segment
		(start 205.4261 105.3162)
		(end 206.8511 105.3162)
		(width 0.254)
		(layer "F.Cu")
		(net "P5V_SENSE")
	)
	(segment
		(start 206.9261 105.2162)
		(end 207.7261 104.4162)
		(width 0.254)
		(layer "F.Cu")
		(net "P5V_SENSE")
	)
	(segment
		(start 225.3261 114.3162)
		(end 225.3261 111.3162)
		(width 0.254)
		(layer "F.Cu")
		(net "P5V_SENSE")
	)
	(segment
		(start 225.2261 111.2162)
		(end 225.3261 111.3162)
		(width 0.254)
		(layer "F.Cu")
		(net "P5V_SENSE")
	)
	(segment
		(start 225.3261 114.3162)
		(end 226.0311 115.0212)
		(width 0.254)
		(layer "F.Cu")
		(net "P5V_SENSE")
	)
	(segment
		(start 226.0311 115.0212)
		(end 230.4261 115.0212)
		(width 0.254)
		(layer "F.Cu")
		(net "P5V_SENSE")
	)
	(segment
		(start 206.9261 105.3912)
		(end 206.9261 105.2162)
		(width 0.254)
		(layer "F.Cu")
		(net "P5V_SENSE")
	)
	(segment
		(start 206.8511 105.3162)
		(end 206.9261 105.3912)
		(width 0.254)
		(layer "F.Cu")
		(net "P5V_SENSE")
	)
	(via
		(at 224.4261 110.0162)
		(size 0.4064)
		(drill 0.2032)
		(layers "F.Cu" "B.Cu")
		(net "P5V_SENSE")
	)
	(via
		(at 207.7261 104.4162)
		(size 0.4064)
		(drill 0.2032)
		(layers "F.Cu" "B.Cu")
		(net "P5V_SENSE")
	)
	(segment
		(start 224.05391 109.64401)
		(end 224.4261 110.0162)
		(width 0.254)
		(layer "B.Cu")
		(net "P5V_SENSE")
	)
	(segment
		(start 208.4261 103.7162)
		(end 215.4261 103.7162)
		(width 0.254)
		(layer "B.Cu")
		(net "P5V_SENSE")
	)
	(segment
		(start 216.6261 105.98193)
		(end 216.6261 104.9162)
		(width 0.254)
		(layer "B.Cu")
		(net "P5V_SENSE")
	)
	(segment
		(start 215.4261 103.7162)
		(end 216.6261 104.9162)
		(width 0.254)
		(layer "B.Cu")
		(net "P5V_SENSE")
	)
	(segment
		(start 216.6261 105.98193)
		(end 220.28817 109.64401)
		(width 0.254)
		(layer "B.Cu")
		(net "P5V_SENSE")
	)
	(segment
		(start 207.7261 104.4162)
		(end 208.4261 103.7162)
		(width 0.254)
		(layer "B.Cu")
		(net "P5V_SENSE")
	)
	(segment
		(start 220.28817 109.64401)
		(end 224.05391 109.64401)
		(width 0.254)
		(layer "B.Cu")
		(net "P5V_SENSE")
	)
	(segment
		(start 206.62611 112.7162)
		(end 207.32611 112.0162)
		(width 0.254)
		(layer "F.Cu")
		(net "P5V_PVDD")
	)
	(segment
		(start 208.1261 112.8162)
		(end 208.5261 112.8162)
		(width 0.254)
		(layer "F.Cu")
		(net "P5V_PVDD")
	)
	(segment
		(start 207.32611 112.0162)
		(end 208.1261 112.8162)
		(width 0.254)
		(layer "F.Cu")
		(net "P5V_PVDD")
	)
	(segment
		(start 204.15953 112.7162)
		(end 206.62611 112.7162)
		(width 0.254)
		(layer "F.Cu")
		(net "P5V_PVDD")
	)
	(segment
		(start 224.3811 115.1712)
		(end 224.3811 114.5162)
		(width 0.254)
		(layer "F.Cu")
		(net "P5V_PVDD")
	)
	(segment
		(start 208.5261 112.8162)
		(end 208.9261 112.8162)
		(width 0.254)
		(layer "F.Cu")
		(net "P5V_PVDD")
	)
	(segment
		(start 224.3811 115.1712)
		(end 224.9261 115.7162)
		(width 0.254)
		(layer "F.Cu")
		(net "P5V_PVDD")
	)
	(segment
		(start 208.9261 112.8162)
		(end 209.3894 112.3529)
		(width 0.254)
		(layer "F.Cu")
		(net "P5V_PVDD")
	)
	(segment
		(start 203.7261 112.28278)
		(end 204.15953 112.7162)
		(width 0.254)
		(layer "F.Cu")
		(net "P5V_PVDD")
	)
	(segment
		(start 209.3894 112.3529)
		(end 209.3894 111.73006)
		(width 0.254)
		(layer "F.Cu")
		(net "P5V_PVDD")
	)
	(via
		(at 208.5261 112.8162)
		(size 0.4064)
		(drill 0.2032)
		(layers "F.Cu" "B.Cu")
		(net "P5V_PVDD")
	)
	(via
		(at 224.9261 115.7162)
		(size 0.4064)
		(drill 0.2032)
		(layers "F.Cu" "B.Cu")
		(net "P5V_PVDD")
	)
	(segment
		(start 223.4261 114.2162)
		(end 224.9261 115.7162)
		(width 0.254)
		(layer "In2.Cu")
		(net "P5V_PVDD")
	)
	(segment
		(start 209.3261 114.2162)
		(end 223.4261 114.2162)
		(width 0.254)
		(layer "In2.Cu")
		(net "P5V_PVDD")
	)
	(segment
		(start 208.5261 113.4162)
		(end 208.5261 112.8162)
		(width 0.254)
		(layer "In2.Cu")
		(net "P5V_PVDD")
	)
	(segment
		(start 208.5261 113.4162)
		(end 209.3261 114.2162)
		(width 0.254)
		(layer "In2.Cu")
		(net "P5V_PVDD")
	)
	(segment
		(start 208.1261 108.1162)
		(end 208.36496 108.35506)
		(width 0.254)
		(layer "F.Cu")
		(net "P5V_FB")
	)
	(segment
		(start 203.8011 106.0162)
		(end 203.8011 105.03432)
		(width 0.254)
		(layer "F.Cu")
		(net "P5V_FB")
	)
	(segment
		(start 204.1011 106.3162)
		(end 205.4261 106.3162)
		(width 0.254)
		(layer "F.Cu")
		(net "P5V_FB")
	)
	(segment
		(start 208.36496 108.35506)
		(end 208.7644 108.35506)
		(width 0.254)
		(layer "F.Cu")
		(net "P5V_FB")
	)
	(segment
		(start 208.1261 108.1162)
		(end 208.1261 107.4162)
		(width 0.254)
		(layer "F.Cu")
		(net "P5V_FB")
	)
	(segment
		(start 206.9261 106.2412)
		(end 206.9511 106.2412)
		(width 0.254)
		(layer "F.Cu")
		(net "P5V_FB")
	)
	(segment
		(start 203.8011 106.0162)
		(end 204.1011 106.3162)
		(width 0.254)
		(layer "F.Cu")
		(net "P5V_FB")
	)
	(segment
		(start 202.64789 103.88111)
		(end 203.8011 105.03432)
		(width 0.254)
		(layer "F.Cu")
		(net "P5V_FB")
	)
	(segment
		(start 206.9511 106.2412)
		(end 208.1261 107.4162)
		(width 0.254)
		(layer "F.Cu")
		(net "P5V_FB")
	)
	(segment
		(start 213.1761 116.7662)
		(end 215.3261 116.7662)
		(width 0.254)
		(layer "F.Cu")
		(net "P5V_FB")
	)
	(segment
		(start 213.1261 116.7162)
		(end 213.1761 116.7662)
		(width 0.254)
		(layer "F.Cu")
		(net "P5V_FB")
	)
	(segment
		(start 205.4261 106.2412)
		(end 206.9261 106.2412)
		(width 0.254)
		(layer "F.Cu")
		(net "P5V_FB")
	)
	(via
		(at 202.64789 103.88111)
		(size 0.4064)
		(drill 0.2032)
		(layers "F.Cu" "B.Cu")
		(net "P5V_FB")
	)
	(via
		(at 213.1261 116.7162)
		(size 0.4064)
		(drill 0.2032)
		(layers "F.Cu" "B.Cu")
		(net "P5V_FB")
	)
	(segment
		(start 202.64789 103.88111)
		(end 202.99101 103.88111)
		(width 0.254)
		(layer "In2.Cu")
		(net "P5V_FB")
	)
	(segment
		(start 206.1261 113.9162)
		(end 208.9261 116.7162)
		(width 0.254)
		(layer "In2.Cu")
		(net "P5V_FB")
	)
	(segment
		(start 208.9261 116.7162)
		(end 213.1261 116.7162)
		(width 0.254)
		(layer "In2.Cu")
		(net "P5V_FB")
	)
	(segment
		(start 202.99101 103.88111)
		(end 206.1261 107.0162)
		(width 0.254)
		(layer "In2.Cu")
		(net "P5V_FB")
	)
	(segment
		(start 206.1261 113.9162)
		(end 206.1261 107.0162)
		(width 0.254)
		(layer "In2.Cu")
		(net "P5V_FB")
	)
	(segment
		(start 203.30466 129.2162)
		(end 203.7261 129.2162)
		(width 0.508)
		(layer "F.Cu")
		(net "P3V3_VDD")
	)
	(segment
		(start 203.7261 129.2162)
		(end 205.0261 127.9162)
		(width 0.508)
		(layer "F.Cu")
		(net "P3V3_VDD")
	)
	(segment
		(start 205.0261 126.1162)
		(end 205.3011 125.8412)
		(width 0.508)
		(layer "F.Cu")
		(net "P3V3_VDD")
	)
	(segment
		(start 205.3011 125.8412)
		(end 205.9261 125.8412)
		(width 0.508)
		(layer "F.Cu")
		(net "P3V3_VDD")
	)
	(segment
		(start 205.0261 127.9162)
		(end 205.0261 126.1162)
		(width 0.508)
		(layer "F.Cu")
		(net "P3V3_VDD")
	)
	(segment
		(start 203.5011 120.5662)
		(end 203.5761 120.6412)
		(width 0.2032)
		(layer "F.Cu")
		(net "P3V3_SENSE")
	)
	(segment
		(start 202.2761 120.5662)
		(end 203.5011 120.5662)
		(width 0.2032)
		(layer "F.Cu")
		(net "P3V3_SENSE")
	)
	(segment
		(start 204.49186 120.6412)
		(end 204.50955 120.65889)
		(width 0.2032)
		(layer "F.Cu")
		(net "P3V3_SENSE")
	)
	(segment
		(start 224.1261 131.9162)
		(end 225.4311 133.2212)
		(width 0.2032)
		(layer "F.Cu")
		(net "P3V3_SENSE")
	)
	(segment
		(start 225.4311 133.2212)
		(end 228.4261 133.2212)
		(width 0.2032)
		(layer "F.Cu")
		(net "P3V3_SENSE")
	)
	(segment
		(start 224.1261 128.4162)
		(end 224.6261 127.9162)
		(width 0.2032)
		(layer "F.Cu")
		(net "P3V3_SENSE")
	)
	(segment
		(start 224.1261 131.9162)
		(end 224.1261 128.4162)
		(width 0.2032)
		(layer "F.Cu")
		(net "P3V3_SENSE")
	)
	(segment
		(start 224.6261 126.8162)
		(end 224.7261 126.7162)
		(width 0.2032)
		(layer "F.Cu")
		(net "P3V3_SENSE")
	)
	(segment
		(start 203.5761 120.6412)
		(end 204.49186 120.6412)
		(width 0.2032)
		(layer "F.Cu")
		(net "P3V3_SENSE")
	)
	(segment
		(start 224.6261 127.9162)
		(end 224.6261 126.8162)
		(width 0.2032)
		(layer "F.Cu")
		(net "P3V3_SENSE")
	)
	(via
		(at 204.50955 120.65889)
		(size 0.4064)
		(drill 0.2032)
		(layers "F.Cu" "B.Cu")
		(net "P3V3_SENSE")
	)
	(via
		(at 223.29254 125.72852)
		(size 0.4064)
		(drill 0.2032)
		(layers "F.Cu" "B.Cu")
		(net "P3V3_SENSE")
	)
	(segment
		(start 222.78022 125.2162)
		(end 223.29254 125.72852)
		(width 0.2032)
		(layer "B.Cu")
		(net "P3V3_SENSE")
	)
	(segment
		(start 220.0261 125.2162)
		(end 222.78022 125.2162)
		(width 0.2032)
		(layer "B.Cu")
		(net "P3V3_SENSE")
	)
	(segment
		(start 205.1261 119.4162)
		(end 208.4261 119.4162)
		(width 0.2032)
		(layer "B.Cu")
		(net "P3V3_SENSE")
	)
	(segment
		(start 210.3261 117.5162)
		(end 212.3261 117.5162)
		(width 0.2032)
		(layer "B.Cu")
		(net "P3V3_SENSE")
	)
	(segment
		(start 212.3261 117.5162)
		(end 220.0261 125.2162)
		(width 0.2032)
		(layer "B.Cu")
		(net "P3V3_SENSE")
	)
	(segment
		(start 208.4261 119.4162)
		(end 210.3261 117.5162)
		(width 0.2032)
		(layer "B.Cu")
		(net "P3V3_SENSE")
	)
	(segment
		(start 204.50955 120.65889)
		(end 204.50955 120.03275)
		(width 0.2032)
		(layer "B.Cu")
		(net "P3V3_SENSE")
	)
	(segment
		(start 204.50955 120.03275)
		(end 205.1261 119.4162)
		(width 0.2032)
		(layer "B.Cu")
		(net "P3V3_SENSE")
	)
	(segment
		(start 205.8261 129.4162)
		(end 205.9261 129.5162)
		(width 0.254)
		(layer "F.Cu")
		(net "P3V3_PVDD")
	)
	(segment
		(start 206.0261 127.9162)
		(end 206.5511 127.3912)
		(width 0.508)
		(layer "F.Cu")
		(net "P3V3_PVDD")
	)
	(segment
		(start 205.9261 129.5162)
		(end 206.7261 129.5162)
		(width 0.254)
		(layer "F.Cu")
		(net "P3V3_PVDD")
	)
	(segment
		(start 222.4261 130.3162)
		(end 222.5261 130.4162)
		(width 0.254)
		(layer "F.Cu")
		(net "P3V3_PVDD")
	)
	(segment
		(start 206.0261 129.2162)
		(end 206.0261 127.9162)
		(width 0.508)
		(layer "F.Cu")
		(net "P3V3_PVDD")
	)
	(segment
		(start 206.5511 127.3912)
		(end 206.5511 126.6162)
		(width 0.508)
		(layer "F.Cu")
		(net "P3V3_PVDD")
	)
	(segment
		(start 221.5811 130.3162)
		(end 222.4261 130.3162)
		(width 0.254)
		(layer "F.Cu")
		(net "P3V3_PVDD")
	)
	(segment
		(start 205.8261 129.4162)
		(end 206.0261 129.2162)
		(width 0.508)
		(layer "F.Cu")
		(net "P3V3_PVDD")
	)
	(via
		(at 222.5261 130.4162)
		(size 0.4064)
		(drill 0.2032)
		(layers "F.Cu" "B.Cu")
		(net "P3V3_PVDD")
	)
	(via
		(at 206.7261 129.5162)
		(size 0.4064)
		(drill 0.2032)
		(layers "F.Cu" "B.Cu")
		(net "P3V3_PVDD")
	)
	(segment
		(start 206.7261 129.5162)
		(end 208.1261 130.9162)
		(width 0.254)
		(layer "B.Cu")
		(net "P3V3_PVDD")
	)
	(segment
		(start 208.1261 130.9162)
		(end 213.1261 130.9162)
		(width 0.254)
		(layer "B.Cu")
		(net "P3V3_PVDD")
	)
	(segment
		(start 213.6261 130.4162)
		(end 222.5261 130.4162)
		(width 0.254)
		(layer "B.Cu")
		(net "P3V3_PVDD")
	)
	(segment
		(start 213.1261 130.9162)
		(end 213.6261 130.4162)
		(width 0.254)
		(layer "B.Cu")
		(net "P3V3_PVDD")
	)
	(segment
		(start 202.2761 121.5662)
		(end 202.3511 121.4912)
		(width 0.2032)
		(layer "F.Cu")
		(net "P3V3_FB")
	)
	(segment
		(start 207.7761 128.08597)
		(end 207.79117 128.0709)
		(width 0.254)
		(layer "F.Cu")
		(net "P3V3_FB")
	)
	(segment
		(start 203.3511 122.6662)
		(end 203.3511 121.7162)
		(width 0.2032)
		(layer "F.Cu")
		(net "P3V3_FB")
	)
	(segment
		(start 204.6011 121.4912)
		(end 204.6261 121.5162)
		(width 0.2032)
		(layer "F.Cu")
		(net "P3V3_FB")
	)
	(segment
		(start 207.7761 129.2162)
		(end 207.7761 128.08597)
		(width 0.254)
		(layer "F.Cu")
		(net "P3V3_FB")
	)
	(segment
		(start 202.3511 121.4912)
		(end 203.5761 121.4912)
		(width 0.2032)
		(layer "F.Cu")
		(net "P3V3_FB")
	)
	(segment
		(start 203.5761 121.4912)
		(end 204.6011 121.4912)
		(width 0.2032)
		(layer "F.Cu")
		(net "P3V3_FB")
	)
	(segment
		(start 203.3511 121.7162)
		(end 203.5761 121.4912)
		(width 0.2032)
		(layer "F.Cu")
		(net "P3V3_FB")
	)
	(segment
		(start 203.9261 123.2412)
		(end 205.9261 123.2412)
		(width 0.2032)
		(layer "F.Cu")
		(net "P3V3_FB")
	)
	(segment
		(start 203.3511 122.6662)
		(end 203.9261 123.2412)
		(width 0.2032)
		(layer "F.Cu")
		(net "P3V3_FB")
	)
	(via
		(at 207.79117 128.0709)
		(size 0.4064)
		(drill 0.2032)
		(layers "F.Cu" "B.Cu")
		(net "P3V3_FB")
	)
	(via
		(at 204.6261 121.5162)
		(size 0.4064)
		(drill 0.2032)
		(layers "F.Cu" "B.Cu")
		(net "P3V3_FB")
	)
	(segment
		(start 204.6261 125.8162)
		(end 206.8808 128.0709)
		(width 0.254)
		(layer "B.Cu")
		(net "P3V3_FB")
	)
	(segment
		(start 206.8808 128.0709)
		(end 207.79117 128.0709)
		(width 0.254)
		(layer "B.Cu")
		(net "P3V3_FB")
	)
	(segment
		(start 204.6261 125.8162)
		(end 204.6261 121.5162)
		(width 0.254)
		(layer "B.Cu")
		(net "P3V3_FB")
	)
	(segment
		(start 236.0261 133.2212)
		(end 236.0261 132.9162)
		(width 0.254)
		(layer "F.Cu")
		(net "NetR80_1")
	)
	(segment
		(start 233.8261 133.2212)
		(end 236.0261 133.2212)
		(width 0.254)
		(layer "F.Cu")
		(net "NetR80_1")
	)
	(segment
		(start 233.8261 131.9512)
		(end 236.0261 131.9512)
		(width 0.254)
		(layer "F.Cu")
		(net "NetR79_1")
	)
	(segment
		(start 236.0261 131.9512)
		(end 236.0261 131.8162)
		(width 0.254)
		(layer "F.Cu")
		(net "NetR79_1")
	)
	(segment
		(start 207.8511 121.3912)
		(end 208.5261 120.7162)
		(width 0.2032)
		(layer "F.Cu")
		(net "NetR69_1")
	)
	(segment
		(start 217.5261 129.6162)
		(end 218.3261 129.6162)
		(width 0.254)
		(layer "F.Cu")
		(net "NetR69_1")
	)
	(segment
		(start 218.3261 129.6162)
		(end 218.7261 129.2162)
		(width 0.254)
		(layer "F.Cu")
		(net "NetR69_1")
	)
	(segment
		(start 207.8511 121.8162)
		(end 207.8511 121.3912)
		(width 0.2032)
		(layer "F.Cu")
		(net "NetR69_1")
	)
	(via
		(at 218.7261 129.2162)
		(size 0.4064)
		(drill 0.2032)
		(layers "F.Cu" "B.Cu")
		(net "NetR69_1")
	)
	(via
		(at 208.5261 120.7162)
		(size 0.4064)
		(drill 0.2032)
		(layers "F.Cu" "B.Cu")
		(net "NetR69_1")
	)
	(segment
		(start 214.1261 127.9162)
		(end 217.4261 127.9162)
		(width 0.2032)
		(layer "B.Cu")
		(net "NetR69_1")
	)
	(segment
		(start 217.4261 127.9162)
		(end 218.7261 129.2162)
		(width 0.2032)
		(layer "B.Cu")
		(net "NetR69_1")
	)
	(segment
		(start 208.5261 122.3162)
		(end 214.1261 127.9162)
		(width 0.2032)
		(layer "B.Cu")
		(net "NetR69_1")
	)
	(segment
		(start 208.5261 122.3162)
		(end 208.5261 120.7162)
		(width 0.2032)
		(layer "B.Cu")
		(net "NetR69_1")
	)
	(segment
		(start 203.3261 123.9162)
		(end 205.9011 123.9162)
		(width 0.2032)
		(layer "F.Cu")
		(net "NetR68_2")
	)
	(segment
		(start 205.9011 123.9162)
		(end 205.9261 123.8912)
		(width 0.2032)
		(layer "F.Cu")
		(net "NetR68_2")
	)
	(segment
		(start 204.3261 124.9162)
		(end 204.7011 124.5412)
		(width 0.2032)
		(layer "F.Cu")
		(net "NetR67_2")
	)
	(segment
		(start 203.3261 124.9162)
		(end 204.3261 124.9162)
		(width 0.2032)
		(layer "F.Cu")
		(net "NetR67_2")
	)
	(segment
		(start 204.7011 124.5412)
		(end 205.9261 124.5412)
		(width 0.2032)
		(layer "F.Cu")
		(net "NetR67_2")
	)
	(segment
		(start 235.8261 115.4162)
		(end 235.8261 115.0212)
		(width 0.254)
		(layer "F.Cu")
		(net "NetR66_1")
	)
	(segment
		(start 234.6261 116.6162)
		(end 235.8261 115.4162)
		(width 0.254)
		(layer "F.Cu")
		(net "NetR66_1")
	)
	(segment
		(start 232.7261 116.6162)
		(end 235.5911 113.7512)
		(width 0.254)
		(layer "F.Cu")
		(net "NetR65_1")
	)
	(segment
		(start 235.5911 113.7512)
		(end 235.8261 113.7512)
		(width 0.254)
		(layer "F.Cu")
		(net "NetR65_1")
	)
	(segment
		(start 205.3261 82.9162)
		(end 206.0261 82.9162)
		(width 0.2032)
		(layer "F.Cu")
		(net "NetR64_1")
	)
	(segment
		(start 205.0311 84.5162)
		(end 205.0311 83.2112)
		(width 0.2032)
		(layer "F.Cu")
		(net "NetR64_1")
	)
	(segment
		(start 205.0311 83.2112)
		(end 205.3261 82.9162)
		(width 0.2032)
		(layer "F.Cu")
		(net "NetR64_1")
	)
	(segment
		(start 203.7261 82.8162)
		(end 203.7611 82.8162)
		(width 0.2032)
		(layer "F.Cu")
		(net "NetR62_1")
	)
	(segment
		(start 203.7611 84.5162)
		(end 203.7611 82.8162)
		(width 0.2032)
		(layer "F.Cu")
		(net "NetR62_1")
	)
	(segment
		(start 218.13844 116.0162)
		(end 219.3261 116.0162)
		(width 0.254)
		(layer "F.Cu")
		(net "NetR4_1")
	)
	(segment
		(start 218.12941 116.00717)
		(end 218.13844 116.0162)
		(width 0.254)
		(layer "F.Cu")
		(net "NetR4_1")
	)
	(segment
		(start 210.6894 105.7529)
		(end 210.8261 105.6162)
		(width 0.254)
		(layer "F.Cu")
		(net "NetR4_1")
	)
	(segment
		(start 217.7261 116.41049)
		(end 218.12941 116.00717)
		(width 0.254)
		(layer "F.Cu")
		(net "NetR4_1")
	)
	(segment
		(start 210.6894 106.93006)
		(end 210.6894 105.7529)
		(width 0.254)
		(layer "F.Cu")
		(net "NetR4_1")
	)
	(segment
		(start 217.7261 116.6162)
		(end 217.7261 116.41049)
		(width 0.254)
		(layer "F.Cu")
		(net "NetR4_1")
	)
	(via
		(at 217.7261 116.6162)
		(size 0.4064)
		(drill 0.2032)
		(layers "F.Cu" "B.Cu")
		(net "NetR4_1")
	)
	(via
		(at 210.8261 105.6162)
		(size 0.4064)
		(drill 0.2032)
		(layers "F.Cu" "B.Cu")
		(net "NetR4_1")
	)
	(segment
		(start 210.8261 108.4162)
		(end 210.8261 105.6162)
		(width 0.254)
		(layer "In2.Cu")
		(net "NetR4_1")
	)
	(segment
		(start 207.7261 114.0162)
		(end 207.7261 111.5162)
		(width 0.254)
		(layer "In2.Cu")
		(net "NetR4_1")
	)
	(segment
		(start 209.4261 115.7162)
		(end 216.8261 115.7162)
		(width 0.254)
		(layer "In2.Cu")
		(net "NetR4_1")
	)
	(segment
		(start 207.7261 111.5162)
		(end 210.8261 108.4162)
		(width 0.254)
		(layer "In2.Cu")
		(net "NetR4_1")
	)
	(segment
		(start 216.8261 115.7162)
		(end 217.7261 116.6162)
		(width 0.254)
		(layer "In2.Cu")
		(net "NetR4_1")
	)
	(segment
		(start 207.7261 114.0162)
		(end 209.4261 115.7162)
		(width 0.254)
		(layer "In2.Cu")
		(net "NetR4_1")
	)
	(segment
		(start 207.2261 108.0162)
		(end 208.21495 109.00506)
		(width 0.254)
		(layer "F.Cu")
		(net "NetR3_2")
	)
	(segment
		(start 208.21495 109.00506)
		(end 208.7644 109.00506)
		(width 0.254)
		(layer "F.Cu")
		(net "NetR3_2")
	)
	(segment
		(start 207.2261 108.0162)
		(end 207.2261 107.6162)
		(width 0.254)
		(layer "F.Cu")
		(net "NetR3_2")
	)
	(segment
		(start 206.9261 107.3162)
		(end 207.2261 107.6162)
		(width 0.254)
		(layer "F.Cu")
		(net "NetR3_2")
	)
	(segment
		(start 206.5261 107.3162)
		(end 206.9261 107.3162)
		(width 0.254)
		(layer "F.Cu")
		(net "NetR3_2")
	)
	(segment
		(start 207.96496 109.65506)
		(end 208.7644 109.65506)
		(width 0.254)
		(layer "F.Cu")
		(net "NetR2_2")
	)
	(segment
		(start 206.5261 108.2162)
		(end 207.96496 109.65506)
		(width 0.254)
		(layer "F.Cu")
		(net "NetR2_2")
	)
	(segment
		(start 208.5011 126.6162)
		(end 208.5011 126.0562)
		(width 0.254)
		(layer "F.Cu")
		(net "NetL2_1")
	)
	(segment
		(start 212.5261 126.8412)
		(end 214.0261 126.8412)
		(width 0.381)
		(layer "F.Cu")
		(net "NetL2_1")
	)
	(segment
		(start 211.8011 128.7162)
		(end 211.8011 127.6662)
		(width 0.381)
		(layer "F.Cu")
		(net "NetL2_1")
	)
	(segment
		(start 211.7511 127.6162)
		(end 211.8011 127.6662)
		(width 0.381)
		(layer "F.Cu")
		(net "NetL2_1")
	)
	(segment
		(start 211.7511 127.6162)
		(end 212.5261 126.8412)
		(width 0.381)
		(layer "F.Cu")
		(net "NetL2_1")
	)
	(segment
		(start 208.5011 126.0562)
		(end 209.8411 124.7162)
		(width 0.254)
		(layer "F.Cu")
		(net "NetL2_1")
	)
	(segment
		(start 211.33939 111.73006)
		(end 211.33939 111.17005)
		(width 0.254)
		(layer "F.Cu")
		(net "NetL1_1")
	)
	(segment
		(start 211.33939 111.17005)
		(end 212.67939 109.83006)
		(width 0.254)
		(layer "F.Cu")
		(net "NetL1_1")
	)
	(segment
		(start 216.1261 113.4912)
		(end 216.1261 113.0162)
		(width 0.254)
		(layer "F.Cu")
		(net "NetL1_1")
	)
	(segment
		(start 216.1261 113.4912)
		(end 216.7511 114.1162)
		(width 0.254)
		(layer "F.Cu")
		(net "NetL1_1")
	)
	(segment
		(start 234.7761 135.3162)
		(end 236.92395 135.3162)
		(width 0.2032)
		(layer "F.Cu")
		(net "NetD20_1")
	)
	(segment
		(start 209.8261 128.6662)
		(end 209.8511 128.6662)
		(width 0.254)
		(layer "F.Cu")
		(net "NetC74_1")
	)
	(segment
		(start 209.8511 128.6662)
		(end 210.9011 127.6162)
		(width 0.254)
		(layer "F.Cu")
		(net "NetC74_1")
	)
	(segment
		(start 209.2761 129.2162)
		(end 209.8261 128.6662)
		(width 0.254)
		(layer "F.Cu")
		(net "NetC74_1")
	)
	(segment
		(start 213.4261 128.73764)
		(end 214.0261 128.13764)
		(width 0.254)
		(layer "F.Cu")
		(net "NetC72_1")
	)
	(segment
		(start 214.0261 128.13764)
		(end 214.0261 127.5912)
		(width 0.254)
		(layer "F.Cu")
		(net "NetC72_1")
	)
	(segment
		(start 203.3261 127.5162)
		(end 203.3261 126.35066)
		(width 0.2032)
		(layer "F.Cu")
		(net "NetC71_1")
	)
	(segment
		(start 204.8511 125.1912)
		(end 205.9261 125.1912)
		(width 0.2032)
		(layer "F.Cu")
		(net "NetC71_1")
	)
	(segment
		(start 203.19164 126.2162)
		(end 203.3261 126.35066)
		(width 0.2032)
		(layer "F.Cu")
		(net "NetC71_1")
	)
	(segment
		(start 203.19164 126.2162)
		(end 203.8261 126.2162)
		(width 0.2032)
		(layer "F.Cu")
		(net "NetC71_1")
	)
	(segment
		(start 203.8261 126.2162)
		(end 204.8511 125.1912)
		(width 0.2032)
		(layer "F.Cu")
		(net "NetC71_1")
	)
	(segment
		(start 210.8261 128.7412)
		(end 210.8511 128.7162)
		(width 0.254)
		(layer "F.Cu")
		(net "NetC68_2")
	)
	(segment
		(start 210.8261 129.5162)
		(end 210.8261 128.7412)
		(width 0.254)
		(layer "F.Cu")
		(net "NetC68_2")
	)
	(segment
		(start 210.8261 129.5162)
		(end 211.1761 129.8662)
		(width 0.254)
		(layer "F.Cu")
		(net "NetC68_2")
	)
	(segment
		(start 211.1761 129.8662)
		(end 211.5261 130.2162)
		(width 0.254)
		(layer "F.Cu")
		(net "NetC68_2")
	)
	(segment
		(start 206.5511 121.8162)
		(end 206.5511 120.9412)
		(width 0.2032)
		(layer "F.Cu")
		(net "NetC68_2")
	)
	(segment
		(start 211.5261 130.2162)
		(end 214.8761 130.2162)
		(width 0.254)
		(layer "F.Cu")
		(net "NetC68_2")
	)
	(segment
		(start 206.2261 120.6162)
		(end 206.5511 120.9412)
		(width 0.2032)
		(layer "F.Cu")
		(net "NetC68_2")
	)
	(via
		(at 206.2261 120.6162)
		(size 0.4064)
		(drill 0.2032)
		(layers "F.Cu" "B.Cu")
		(net "NetC68_2")
	)
	(via
		(at 211.1761 129.8662)
		(size 0.4064)
		(drill 0.2032)
		(layers "F.Cu" "B.Cu")
		(net "NetC68_2")
	)
	(segment
		(start 206.2261 123.4162)
		(end 206.2261 120.6162)
		(width 0.2032)
		(layer "B.Cu")
		(net "NetC68_2")
	)
	(segment
		(start 209.2261 125.7162)
		(end 211.2261 127.7162)
		(width 0.2032)
		(layer "B.Cu")
		(net "NetC68_2")
	)
	(segment
		(start 211.1761 129.8662)
		(end 211.2261 129.8162)
		(width 0.2032)
		(layer "B.Cu")
		(net "NetC68_2")
	)
	(segment
		(start 206.2261 123.4162)
		(end 208.5261 125.7162)
		(width 0.2032)
		(layer "B.Cu")
		(net "NetC68_2")
	)
	(segment
		(start 211.2261 129.8162)
		(end 211.2261 127.7162)
		(width 0.2032)
		(layer "B.Cu")
		(net "NetC68_2")
	)
	(segment
		(start 208.5261 125.7162)
		(end 209.2261 125.7162)
		(width 0.2032)
		(layer "B.Cu")
		(net "NetC68_2")
	)
	(segment
		(start 216.3761 130.2162)
		(end 216.7761 130.6162)
		(width 0.254)
		(layer "F.Cu")
		(net "NetC68_1")
	)
	(segment
		(start 219.1711 130.6162)
		(end 219.4711 130.3162)
		(width 0.254)
		(layer "F.Cu")
		(net "NetC68_1")
	)
	(segment
		(start 216.7761 130.6162)
		(end 217.5261 130.6162)
		(width 0.254)
		(layer "F.Cu")
		(net "NetC68_1")
	)
	(segment
		(start 217.5261 130.6162)
		(end 219.1711 130.6162)
		(width 0.254)
		(layer "F.Cu")
		(net "NetC68_1")
	)
	(segment
		(start 215.3261 115.2662)
		(end 215.3261 113.9412)
		(width 0.254)
		(layer "F.Cu")
		(net "NetC9_1")
	)
	(segment
		(start 213.70466 115.4162)
		(end 214.1261 114.99476)
		(width 0.254)
		(layer "F.Cu")
		(net "NetC7_1")
	)
	(segment
		(start 214.1261 114.99476)
		(end 214.1261 113.8912)
		(width 0.254)
		(layer "F.Cu")
		(net "NetC7_1")
	)
	(segment
		(start 206.0261 109.98174)
		(end 206.16056 110.1162)
		(width 0.254)
		(layer "F.Cu")
		(net "NetC6_1")
	)
	(segment
		(start 204.21663 109.98174)
		(end 206.0261 109.98174)
		(width 0.254)
		(layer "F.Cu")
		(net "NetC6_1")
	)
	(segment
		(start 204.0261 109.7912)
		(end 204.21663 109.98174)
		(width 0.254)
		(layer "F.Cu")
		(net "NetC6_1")
	)
	(segment
		(start 207.6261 110.1162)
		(end 207.81496 110.30506)
		(width 0.254)
		(layer "F.Cu")
		(net "NetC6_1")
	)
	(segment
		(start 206.16056 110.1162)
		(end 207.6261 110.1162)
		(width 0.254)
		(layer "F.Cu")
		(net "NetC6_1")
	)
	(segment
		(start 207.81496 110.30506)
		(end 208.7644 110.30506)
		(width 0.254)
		(layer "F.Cu")
		(net "NetC6_1")
	)
	(segment
		(start 205.0311 91.5212)
		(end 206.0261 92.5162)
		(width 0.254)
		(layer "F.Cu")
		(net "+12V_SENS")
	)
	(segment
		(start 206.0261 92.5162)
		(end 208.8011 92.5162)
		(width 0.254)
		(layer "F.Cu")
		(net "+12V_SENS")
	)
	(segment
		(start 205.0311 91.5212)
		(end 205.0311 89.9162)
		(width 0.254)
		(layer "F.Cu")
		(net "+12V_SENS")
	)
	(segment
		(start 208.8011 92.5162)
		(end 209.6261 93.3412)
		(width 0.254)
		(layer "F.Cu")
		(net "+12V_SENS")
	)
	(segment
		(start 191.2563 83.7464)
		(end 191.3261 83.8162)
		(width 0.2032)
		(layer "F.Cu")
		(net "NetR58_2")
	)
	(segment
		(start 188.5761 84.1662)
		(end 188.9959 83.7464)
		(width 0.2032)
		(layer "F.Cu")
		(net "NetR58_2")
	)
	(segment
		(start 188.5761 84.6537)
		(end 188.5761 84.1662)
		(width 0.2032)
		(layer "F.Cu")
		(net "NetR58_2")
	)
	(segment
		(start 188.9959 83.7464)
		(end 191.2563 83.7464)
		(width 0.2032)
		(layer "F.Cu")
		(net "NetR58_2")
	)
	(segment
		(start 189.0761 84.2662)
		(end 189.2261 84.1162)
		(width 0.2032)
		(layer "F.Cu")
		(net "NetR57_2")
	)
	(segment
		(start 190.9261 84.3162)
		(end 191.8261 84.3162)
		(width 0.2032)
		(layer "F.Cu")
		(net "NetR57_2")
	)
	(segment
		(start 189.0761 84.6537)
		(end 189.0761 84.2662)
		(width 0.2032)
		(layer "F.Cu")
		(net "NetR57_2")
	)
	(segment
		(start 189.2261 84.1162)
		(end 190.7261 84.1162)
		(width 0.2032)
		(layer "F.Cu")
		(net "NetR57_2")
	)
	(segment
		(start 191.8261 84.3162)
		(end 192.3261 83.8162)
		(width 0.2032)
		(layer "F.Cu")
		(net "NetR57_2")
	)
	(segment
		(start 190.7261 84.1162)
		(end 190.9261 84.3162)
		(width 0.2032)
		(layer "F.Cu")
		(net "NetR57_2")
	)
	(segment
		(start 187.5761 84.6537)
		(end 187.5761 82.8662)
		(width 0.2032)
		(layer "F.Cu")
		(net "NetR55_2")
	)
	(segment
		(start 187.5761 82.8662)
		(end 187.6261 82.8162)
		(width 0.2032)
		(layer "F.Cu")
		(net "NetR55_2")
	)
	(segment
		(start 183.4261 85.7162)
		(end 184.0261 85.7162)
		(width 0.2032)
		(layer "F.Cu")
		(net "NetR53_1")
	)
	(segment
		(start 184.0261 85.7162)
		(end 184.2761 85.9662)
		(width 0.2032)
		(layer "F.Cu")
		(net "NetR53_1")
	)
	(segment
		(start 183.4261 84.8162)
		(end 183.4261 84.8162)
		(width 0.2032)
		(layer "F.Cu")
		(net "NetR53_1")
	)
	(segment
		(start 184.2761 85.9662)
		(end 185.0136 85.9662)
		(width 0.2032)
		(layer "F.Cu")
		(net "NetR53_1")
	)
	(segment
		(start 183.4261 85.7162)
		(end 183.4261 85.7162)
		(width 0.2032)
		(layer "F.Cu")
		(net "NetR53_1")
	)
	(segment
		(start 183.4261 85.7162)
		(end 183.4261 84.8162)
		(width 0.2032)
		(layer "F.Cu")
		(net "NetR53_1")
	)
	(segment
		(start 185.5261 83.3162)
		(end 186.70315 83.3162)
		(width 0.2032)
		(layer "F.Cu")
		(net "NetR52_1")
	)
	(segment
		(start 186.70315 83.737)
		(end 186.70315 83.3162)
		(width 0.2032)
		(layer "F.Cu")
		(net "NetR52_1")
	)
	(segment
		(start 186.70315 83.737)
		(end 187.0761 84.10995)
		(width 0.2032)
		(layer "F.Cu")
		(net "NetR52_1")
	)
	(segment
		(start 187.0761 84.6537)
		(end 187.0761 84.10995)
		(width 0.2032)
		(layer "F.Cu")
		(net "NetR52_1")
	)
	(segment
		(start 185.0261 82.8162)
		(end 185.5261 83.3162)
		(width 0.2032)
		(layer "F.Cu")
		(net "NetR52_1")
	)
	(segment
		(start 186.7261 83.2162)
		(end 186.7261 82.8162)
		(width 0.2032)
		(layer "F.Cu")
		(net "NetR52_1")
	)
	(segment
		(start 190.3761 85.9662)
		(end 190.8261 85.5162)
		(width 0.2032)
		(layer "F.Cu")
		(net "NetR51_2")
	)
	(segment
		(start 189.6386 85.9662)
		(end 190.3761 85.9662)
		(width 0.2032)
		(layer "F.Cu")
		(net "NetR51_2")
	)
	(segment
		(start 188.0761 84.6537)
		(end 188.0761 83.7662)
		(width 0.2032)
		(layer "F.Cu")
		(net "NetC65_1")
	)
	(segment
		(start 188.4261 83.4162)
		(end 189.04754 83.4162)
		(width 0.2032)
		(layer "F.Cu")
		(net "NetC65_1")
	)
	(segment
		(start 188.0761 83.7662)
		(end 188.4261 83.4162)
		(width 0.2032)
		(layer "F.Cu")
		(net "NetC65_1")
	)
	(segment
		(start 189.04754 83.4162)
		(end 189.44754 83.0162)
		(width 0.2032)
		(layer "F.Cu")
		(net "NetC65_1")
	)
	(segment
		(start 188.0761 89.9062)
		(end 188.0761 87.7787)
		(width 0.2032)
		(layer "F.Cu")
		(net "BNO_XOUT32")
	)
	(segment
		(start 188.0761 89.9062)
		(end 189.1861 91.0162)
		(width 0.2032)
		(layer "F.Cu")
		(net "BNO_XOUT32")
	)
	(segment
		(start 193.4261 91.0162)
		(end 195.9261 93.5162)
		(width 0.2032)
		(layer "F.Cu")
		(net "BNO_XOUT32_C")
	)
	(segment
		(start 180.6959 103.786)
		(end 192.3563 103.786)
		(width 0.2032)
		(layer "F.Cu")
		(net "BNO_XOUT32_C")
	)
	(segment
		(start 190.0661 91.0162)
		(end 193.4261 91.0162)
		(width 0.2032)
		(layer "F.Cu")
		(net "BNO_XOUT32_C")
	)
	(segment
		(start 195.9261 100.2162)
		(end 195.9261 93.5162)
		(width 0.2032)
		(layer "F.Cu")
		(net "BNO_XOUT32_C")
	)
	(segment
		(start 177.2261 100.3162)
		(end 177.2261 99.53926)
		(width 0.2032)
		(layer "F.Cu")
		(net "BNO_XOUT32_C")
	)
	(segment
		(start 177.2261 100.3162)
		(end 180.6959 103.786)
		(width 0.2032)
		(layer "F.Cu")
		(net "BNO_XOUT32_C")
	)
	(segment
		(start 177.21009 99.52325)
		(end 177.21009 99.40019)
		(width 0.2032)
		(layer "F.Cu")
		(net "BNO_XOUT32_C")
	)
	(segment
		(start 192.3563 103.786)
		(end 195.9261 100.2162)
		(width 0.2032)
		(layer "F.Cu")
		(net "BNO_XOUT32_C")
	)
	(segment
		(start 177.21009 99.52325)
		(end 177.2261 99.53926)
		(width 0.2032)
		(layer "F.Cu")
		(net "BNO_XOUT32_C")
	)
	(segment
		(start 176.82832 99.01842)
		(end 177.21009 99.40019)
		(width 0.2032)
		(layer "F.Cu")
		(net "BNO_XOUT32_C")
	)
	(segment
		(start 176.82832 99.01842)
		(end 176.82832 97.90213)
		(width 0.2032)
		(layer "F.Cu")
		(net "BNO_XOUT32_C")
	)
	(segment
		(start 188.5761 89.4062)
		(end 188.5761 87.7787)
		(width 0.2032)
		(layer "F.Cu")
		(net "BNO_XIN32")
	)
	(segment
		(start 188.5761 89.4062)
		(end 189.1861 90.0162)
		(width 0.2032)
		(layer "F.Cu")
		(net "BNO_XIN32")
	)
	(segment
		(start 176.3261 99.1162)
		(end 176.5261 99.3162)
		(width 0.2032)
		(layer "F.Cu")
		(net "BNO_XIN32_C")
	)
	(segment
		(start 190.0661 90.0162)
		(end 193.3261 90.0162)
		(width 0.2032)
		(layer "F.Cu")
		(net "BNO_XIN32_C")
	)
	(segment
		(start 192.9261 104.1162)
		(end 196.5261 100.5162)
		(width 0.2032)
		(layer "F.Cu")
		(net "BNO_XIN32_C")
	)
	(segment
		(start 193.3261 90.0162)
		(end 196.5261 93.2162)
		(width 0.2032)
		(layer "F.Cu")
		(net "BNO_XIN32_C")
	)
	(segment
		(start 196.5261 100.5162)
		(end 196.5261 93.2162)
		(width 0.2032)
		(layer "F.Cu")
		(net "BNO_XIN32_C")
	)
	(segment
		(start 176.5261 100.7162)
		(end 179.9261 104.1162)
		(width 0.2032)
		(layer "F.Cu")
		(net "BNO_XIN32_C")
	)
	(segment
		(start 179.9261 104.1162)
		(end 192.9261 104.1162)
		(width 0.2032)
		(layer "F.Cu")
		(net "BNO_XIN32_C")
	)
	(segment
		(start 176.3261 97.90449)
		(end 176.32845 97.90213)
		(width 0.2032)
		(layer "F.Cu")
		(net "BNO_XIN32_C")
	)
	(segment
		(start 176.5261 100.7162)
		(end 176.5261 99.3162)
		(width 0.2032)
		(layer "F.Cu")
		(net "BNO_XIN32_C")
	)
	(segment
		(start 176.3261 99.1162)
		(end 176.3261 97.90449)
		(width 0.2032)
		(layer "F.Cu")
		(net "BNO_XIN32_C")
	)
	(segment
		(start 190.9261 101.7162)
		(end 195.4261 97.2162)
		(width 0.2032)
		(layer "F.Cu")
		(net "BNO_INT")
	)
	(segment
		(start 190.3261 103.4162)
		(end 190.9261 102.8162)
		(width 0.2032)
		(layer "F.Cu")
		(net "BNO_INT")
	)
	(segment
		(start 187.3233 91.0134)
		(end 188.5261 92.2162)
		(width 0.2032)
		(layer "F.Cu")
		(net "BNO_INT")
	)
	(segment
		(start 178.3261 100.2162)
		(end 178.3261 97.90448)
		(width 0.2032)
		(layer "F.Cu")
		(net "BNO_INT")
	)
	(segment
		(start 181.9261 86.5162)
		(end 181.9261 84.2162)
		(width 0.2032)
		(layer "F.Cu")
		(net "BNO_INT")
	)
	(segment
		(start 187.2261 103.1162)
		(end 187.5261 103.4162)
		(width 0.2032)
		(layer "F.Cu")
		(net "BNO_INT")
	)
	(segment
		(start 184.0261 89.3162)
		(end 185.7233 91.0134)
		(width 0.2032)
		(layer "F.Cu")
		(net "BNO_INT")
	)
	(segment
		(start 192.7261 92.2162)
		(end 195.4261 94.9162)
		(width 0.2032)
		(layer "F.Cu")
		(net "BNO_INT")
	)
	(segment
		(start 185.7233 91.0134)
		(end 187.3233 91.0134)
		(width 0.2032)
		(layer "F.Cu")
		(net "BNO_INT")
	)
	(segment
		(start 181.2261 103.1162)
		(end 187.2261 103.1162)
		(width 0.2032)
		(layer "F.Cu")
		(net "BNO_INT")
	)
	(segment
		(start 184.6261 83.4162)
		(end 185.5761 84.3662)
		(width 0.2032)
		(layer "F.Cu")
		(net "BNO_INT")
	)
	(segment
		(start 181.9261 86.5162)
		(end 183.1261 87.7162)
		(width 0.2032)
		(layer "F.Cu")
		(net "BNO_INT")
	)
	(segment
		(start 182.7261 83.4162)
		(end 184.6261 83.4162)
		(width 0.2032)
		(layer "F.Cu")
		(net "BNO_INT")
	)
	(segment
		(start 188.5261 92.2162)
		(end 192.7261 92.2162)
		(width 0.2032)
		(layer "F.Cu")
		(net "BNO_INT")
	)
	(segment
		(start 185.5761 84.6537)
		(end 185.5761 84.3662)
		(width 0.2032)
		(layer "F.Cu")
		(net "BNO_INT")
	)
	(segment
		(start 195.4261 97.2162)
		(end 195.4261 94.9162)
		(width 0.2032)
		(layer "F.Cu")
		(net "BNO_INT")
	)
	(segment
		(start 178.3261 97.90448)
		(end 178.32845 97.90213)
		(width 0.2032)
		(layer "F.Cu")
		(net "BNO_INT")
	)
	(segment
		(start 181.9261 84.2162)
		(end 182.7261 83.4162)
		(width 0.2032)
		(layer "F.Cu")
		(net "BNO_INT")
	)
	(segment
		(start 190.9261 102.8162)
		(end 190.9261 101.7162)
		(width 0.2032)
		(layer "F.Cu")
		(net "BNO_INT")
	)
	(segment
		(start 184.0261 89.3162)
		(end 184.0261 89.2162)
		(width 0.2032)
		(layer "F.Cu")
		(net "BNO_INT")
	)
	(segment
		(start 178.3261 100.2162)
		(end 181.2261 103.1162)
		(width 0.2032)
		(layer "F.Cu")
		(net "BNO_INT")
	)
	(segment
		(start 187.5261 103.4162)
		(end 190.3261 103.4162)
		(width 0.2032)
		(layer "F.Cu")
		(net "BNO_INT")
	)
	(segment
		(start 183.1261 88.3162)
		(end 183.1261 87.7162)
		(width 0.2032)
		(layer "F.Cu")
		(net "BNO_INT")
	)
	(segment
		(start 183.1261 88.3162)
		(end 184.0261 89.2162)
		(width 0.2032)
		(layer "F.Cu")
		(net "BNO_INT")
	)
	(segment
		(start 189.15305 102.3162)
		(end 189.79411 102.95726)
		(width 0.2032)
		(layer "F.Cu")
		(net "GPS2_PIN15")
	)
	(segment
		(start 229.75226 72.6786)
		(end 230.27163 73.19797)
		(width 0.2032)
		(layer "F.Cu")
		(net "GPS2_PIN15")
	)
	(segment
		(start 178.82832 100.01842)
		(end 181.1261 102.3162)
		(width 0.2032)
		(layer "F.Cu")
		(net "GPS2_PIN15")
	)
	(segment
		(start 228.0711 72.6786)
		(end 229.75226 72.6786)
		(width 0.2032)
		(layer "F.Cu")
		(net "GPS2_PIN15")
	)
	(segment
		(start 181.1261 102.3162)
		(end 189.15305 102.3162)
		(width 0.2032)
		(layer "F.Cu")
		(net "GPS2_PIN15")
	)
	(segment
		(start 178.82832 100.01842)
		(end 178.82832 97.90213)
		(width 0.2032)
		(layer "F.Cu")
		(net "GPS2_PIN15")
	)
	(via
		(at 230.27163 73.19797)
		(size 0.4064)
		(drill 0.2032)
		(layers "F.Cu" "B.Cu")
		(net "GPS2_PIN15")
	)
	(via
		(at 189.79411 102.95726)
		(size 0.4064)
		(drill 0.2032)
		(layers "F.Cu" "B.Cu")
		(net "GPS2_PIN15")
	)
	(segment
		(start 206.9269 88.3154)
		(end 211.5261 83.7162)
		(width 0.2032)
		(layer "In2.Cu")
		(net "GPS2_PIN15")
	)
	(segment
		(start 199.0261 102.9162)
		(end 204.8261 97.1162)
		(width 0.2032)
		(layer "In2.Cu")
		(net "GPS2_PIN15")
	)
	(segment
		(start 225.14432 73.19797)
		(end 230.27163 73.19797)
		(width 0.2032)
		(layer "In2.Cu")
		(net "GPS2_PIN15")
	)
	(segment
		(start 206.91784 88.3154)
		(end 206.9269 88.3154)
		(width 0.2032)
		(layer "In2.Cu")
		(net "GPS2_PIN15")
	)
	(segment
		(start 206.6649 88.5774)
		(end 206.6649 88.56834)
		(width 0.2032)
		(layer "In2.Cu")
		(net "GPS2_PIN15")
	)
	(segment
		(start 206.6649 88.56834)
		(end 206.91784 88.3154)
		(width 0.2032)
		(layer "In2.Cu")
		(net "GPS2_PIN15")
	)
	(segment
		(start 189.79411 102.95726)
		(end 189.83517 102.9162)
		(width 0.2032)
		(layer "In2.Cu")
		(net "GPS2_PIN15")
	)
	(segment
		(start 214.6261 83.7162)
		(end 225.14432 73.19797)
		(width 0.2032)
		(layer "In2.Cu")
		(net "GPS2_PIN15")
	)
	(segment
		(start 204.8261 97.1162)
		(end 204.8261 90.4162)
		(width 0.2032)
		(layer "In2.Cu")
		(net "GPS2_PIN15")
	)
	(segment
		(start 189.83517 102.9162)
		(end 199.0261 102.9162)
		(width 0.2032)
		(layer "In2.Cu")
		(net "GPS2_PIN15")
	)
	(segment
		(start 211.5261 83.7162)
		(end 214.6261 83.7162)
		(width 0.2032)
		(layer "In2.Cu")
		(net "GPS2_PIN15")
	)
	(segment
		(start 204.8261 90.4162)
		(end 206.6649 88.5774)
		(width 0.2032)
		(layer "In2.Cu")
		(net "GPS2_PIN15")
	)
	(segment
		(start 182.1261 91.1162)
		(end 183.3261 91.1162)
		(width 0.2032)
		(layer "F.Cu")
		(net "GPS2_PIN14")
	)
	(segment
		(start 186.3261 94.1162)
		(end 191.6261 94.1162)
		(width 0.2032)
		(layer "F.Cu")
		(net "GPS2_PIN14")
	)
	(segment
		(start 221.82372 70.6786)
		(end 223.6261 70.6786)
		(width 0.2032)
		(layer "F.Cu")
		(net "GPS2_PIN14")
	)
	(segment
		(start 181.82831 91.41399)
		(end 182.1261 91.1162)
		(width 0.2032)
		(layer "F.Cu")
		(net "GPS2_PIN14")
	)
	(segment
		(start 183.3261 91.1162)
		(end 186.3261 94.1162)
		(width 0.2032)
		(layer "F.Cu")
		(net "GPS2_PIN14")
	)
	(segment
		(start 193.97799 96.46809)
		(end 194.11451 96.46809)
		(width 0.2032)
		(layer "F.Cu")
		(net "GPS2_PIN14")
	)
	(segment
		(start 221.49782 71.00451)
		(end 221.82372 70.6786)
		(width 0.2032)
		(layer "F.Cu")
		(net "GPS2_PIN14")
	)
	(segment
		(start 181.82831 93.85236)
		(end 181.82831 91.41399)
		(width 0.2032)
		(layer "F.Cu")
		(net "GPS2_PIN14")
	)
	(segment
		(start 191.6261 94.1162)
		(end 193.97799 96.46809)
		(width 0.2032)
		(layer "F.Cu")
		(net "GPS2_PIN14")
	)
	(via
		(at 194.11451 96.46809)
		(size 0.4064)
		(drill 0.2032)
		(layers "F.Cu" "B.Cu")
		(net "GPS2_PIN14")
	)
	(via
		(at 221.49782 71.00451)
		(size 0.4064)
		(drill 0.2032)
		(layers "F.Cu" "B.Cu")
		(net "GPS2_PIN14")
	)
	(segment
		(start 194.11451 96.90461)
		(end 195.3261 98.1162)
		(width 0.2032)
		(layer "In2.Cu")
		(net "GPS2_PIN14")
	)
	(segment
		(start 209.5261 82.3162)
		(end 212.5261 82.3162)
		(width 0.2032)
		(layer "In2.Cu")
		(net "GPS2_PIN14")
	)
	(segment
		(start 200.2261 98.1162)
		(end 202.8261 95.5162)
		(width 0.2032)
		(layer "In2.Cu")
		(net "GPS2_PIN14")
	)
	(segment
		(start 195.3261 98.1162)
		(end 200.2261 98.1162)
		(width 0.2032)
		(layer "In2.Cu")
		(net "GPS2_PIN14")
	)
	(segment
		(start 202.8261 95.5162)
		(end 202.8261 89.0162)
		(width 0.2032)
		(layer "In2.Cu")
		(net "GPS2_PIN14")
	)
	(segment
		(start 212.5261 82.3162)
		(end 220.64639 74.19591)
		(width 0.2032)
		(layer "In2.Cu")
		(net "GPS2_PIN14")
	)
	(segment
		(start 202.8261 89.0162)
		(end 209.5261 82.3162)
		(width 0.2032)
		(layer "In2.Cu")
		(net "GPS2_PIN14")
	)
	(segment
		(start 220.64639 72.69588)
		(end 221.49782 71.84445)
		(width 0.2032)
		(layer "In2.Cu")
		(net "GPS2_PIN14")
	)
	(segment
		(start 220.64639 74.19591)
		(end 220.64639 72.69588)
		(width 0.2032)
		(layer "In2.Cu")
		(net "GPS2_PIN14")
	)
	(segment
		(start 221.49782 71.84445)
		(end 221.49782 71.00451)
		(width 0.2032)
		(layer "In2.Cu")
		(net "GPS2_PIN14")
	)
	(segment
		(start 194.11451 96.90461)
		(end 194.11451 96.46809)
		(width 0.2032)
		(layer "In2.Cu")
		(net "GPS2_PIN14")
	)
	(segment
		(start 180.82831 100.61842)
		(end 181.7261 101.5162)
		(width 0.2032)
		(layer "F.Cu")
		(net "GPS2_PIN13")
	)
	(segment
		(start 229.5441 70.6786)
		(end 230.11718 71.25168)
		(width 0.2032)
		(layer "F.Cu")
		(net "GPS2_PIN13")
	)
	(segment
		(start 189.5261 101.5162)
		(end 189.8261 101.8162)
		(width 0.2032)
		(layer "F.Cu")
		(net "GPS2_PIN13")
	)
	(segment
		(start 228.0711 70.6786)
		(end 229.5441 70.6786)
		(width 0.2032)
		(layer "F.Cu")
		(net "GPS2_PIN13")
	)
	(segment
		(start 181.7261 101.5162)
		(end 189.5261 101.5162)
		(width 0.2032)
		(layer "F.Cu")
		(net "GPS2_PIN13")
	)
	(segment
		(start 180.82831 100.61842)
		(end 180.82831 97.90213)
		(width 0.2032)
		(layer "F.Cu")
		(net "GPS2_PIN13")
	)
	(via
		(at 189.8261 101.8162)
		(size 0.4064)
		(drill 0.2032)
		(layers "F.Cu" "B.Cu")
		(net "GPS2_PIN13")
	)
	(via
		(at 230.11718 71.25168)
		(size 0.4064)
		(drill 0.2032)
		(layers "F.Cu" "B.Cu")
		(net "GPS2_PIN13")
	)
	(segment
		(start 229.49062 71.25168)
		(end 230.11718 71.25168)
		(width 0.2032)
		(layer "In2.Cu")
		(net "GPS2_PIN13")
	)
	(segment
		(start 210.7261 83.3162)
		(end 214.4261 83.3162)
		(width 0.2032)
		(layer "In2.Cu")
		(net "GPS2_PIN13")
	)
	(segment
		(start 204.1261 89.9162)
		(end 210.7261 83.3162)
		(width 0.2032)
		(layer "In2.Cu")
		(net "GPS2_PIN13")
	)
	(segment
		(start 204.1261 97.0162)
		(end 204.1261 89.9162)
		(width 0.2032)
		(layer "In2.Cu")
		(net "GPS2_PIN13")
	)
	(segment
		(start 214.4261 83.3162)
		(end 225.0261 72.7162)
		(width 0.2032)
		(layer "In2.Cu")
		(net "GPS2_PIN13")
	)
	(segment
		(start 225.0261 72.7162)
		(end 228.0261 72.7162)
		(width 0.2032)
		(layer "In2.Cu")
		(net "GPS2_PIN13")
	)
	(segment
		(start 199.4261 101.7162)
		(end 204.1261 97.0162)
		(width 0.2032)
		(layer "In2.Cu")
		(net "GPS2_PIN13")
	)
	(segment
		(start 189.8261 101.8162)
		(end 189.9261 101.7162)
		(width 0.2032)
		(layer "In2.Cu")
		(net "GPS2_PIN13")
	)
	(segment
		(start 189.9261 101.7162)
		(end 199.4261 101.7162)
		(width 0.2032)
		(layer "In2.Cu")
		(net "GPS2_PIN13")
	)
	(segment
		(start 228.0261 72.7162)
		(end 229.49062 71.25168)
		(width 0.2032)
		(layer "In2.Cu")
		(net "GPS2_PIN13")
	)
	(segment
		(start 221.86369 68.67861)
		(end 223.6261 68.67861)
		(width 0.2032)
		(layer "F.Cu")
		(net "GPS2_PIN12")
	)
	(segment
		(start 192.63671 93.5162)
		(end 194.78373 95.66322)
		(width 0.2032)
		(layer "F.Cu")
		(net "GPS2_PIN12")
	)
	(segment
		(start 181.32844 92.81386)
		(end 181.49811 92.64419)
		(width 0.2032)
		(layer "F.Cu")
		(net "GPS2_PIN12")
	)
	(segment
		(start 221.4261 69.1162)
		(end 221.86369 68.67861)
		(width 0.2032)
		(layer "F.Cu")
		(net "GPS2_PIN12")
	)
	(segment
		(start 186.7261 93.5162)
		(end 192.63671 93.5162)
		(width 0.2032)
		(layer "F.Cu")
		(net "GPS2_PIN12")
	)
	(segment
		(start 181.32844 93.85236)
		(end 181.32844 92.81386)
		(width 0.2032)
		(layer "F.Cu")
		(net "GPS2_PIN12")
	)
	(segment
		(start 183.9261 90.7162)
		(end 186.7261 93.5162)
		(width 0.2032)
		(layer "F.Cu")
		(net "GPS2_PIN12")
	)
	(segment
		(start 181.49811 92.64419)
		(end 181.49811 91.04418)
		(width 0.2032)
		(layer "F.Cu")
		(net "GPS2_PIN12")
	)
	(segment
		(start 181.49811 91.04418)
		(end 181.8261 90.7162)
		(width 0.2032)
		(layer "F.Cu")
		(net "GPS2_PIN12")
	)
	(segment
		(start 181.8261 90.7162)
		(end 183.9261 90.7162)
		(width 0.2032)
		(layer "F.Cu")
		(net "GPS2_PIN12")
	)
	(via
		(at 194.78373 95.66322)
		(size 0.4064)
		(drill 0.2032)
		(layers "F.Cu" "B.Cu")
		(net "GPS2_PIN12")
	)
	(via
		(at 221.4261 69.1162)
		(size 0.4064)
		(drill 0.2032)
		(layers "F.Cu" "B.Cu")
		(net "GPS2_PIN12")
	)
	(segment
		(start 194.78373 95.87382)
		(end 195.7261 96.8162)
		(width 0.2032)
		(layer "In2.Cu")
		(net "GPS2_PIN12")
	)
	(segment
		(start 194.78373 95.87382)
		(end 194.78373 95.66322)
		(width 0.2032)
		(layer "In2.Cu")
		(net "GPS2_PIN12")
	)
	(segment
		(start 195.7261 96.8162)
		(end 199.8261 96.8162)
		(width 0.2032)
		(layer "In2.Cu")
		(net "GPS2_PIN12")
	)
	(segment
		(start 208.7261 81.8162)
		(end 221.4261 69.1162)
		(width 0.2032)
		(layer "In2.Cu")
		(net "GPS2_PIN12")
	)
	(segment
		(start 208.7261 82.3162)
		(end 208.7261 81.8162)
		(width 0.2032)
		(layer "In2.Cu")
		(net "GPS2_PIN12")
	)
	(segment
		(start 200.9261 95.7162)
		(end 200.9261 90.1162)
		(width 0.2032)
		(layer "In2.Cu")
		(net "GPS2_PIN12")
	)
	(segment
		(start 199.8261 96.8162)
		(end 200.9261 95.7162)
		(width 0.2032)
		(layer "In2.Cu")
		(net "GPS2_PIN12")
	)
	(segment
		(start 200.9261 90.1162)
		(end 208.7261 82.3162)
		(width 0.2032)
		(layer "In2.Cu")
		(net "GPS2_PIN12")
	)
	(segment
		(start 181.32844 100.21854)
		(end 181.8261 100.7162)
		(width 0.2032)
		(layer "F.Cu")
		(net "GPS2_PIN11")
	)
	(segment
		(start 229.44406 68.67861)
		(end 230.28709 69.52164)
		(width 0.2032)
		(layer "F.Cu")
		(net "GPS2_PIN11")
	)
	(segment
		(start 228.0711 68.67861)
		(end 229.44406 68.67861)
		(width 0.2032)
		(layer "F.Cu")
		(net "GPS2_PIN11")
	)
	(segment
		(start 181.8261 100.7162)
		(end 189.90003 100.7162)
		(width 0.2032)
		(layer "F.Cu")
		(net "GPS2_PIN11")
	)
	(segment
		(start 181.32844 100.21854)
		(end 181.32844 97.90213)
		(width 0.2032)
		(layer "F.Cu")
		(net "GPS2_PIN11")
	)
	(segment
		(start 189.90003 100.7162)
		(end 189.9002 100.71637)
		(width 0.2032)
		(layer "F.Cu")
		(net "GPS2_PIN11")
	)
	(via
		(at 230.28709 69.52164)
		(size 0.4064)
		(drill 0.2032)
		(layers "F.Cu" "B.Cu")
		(net "GPS2_PIN11")
	)
	(via
		(at 189.9002 100.71637)
		(size 0.4064)
		(drill 0.2032)
		(layers "F.Cu" "B.Cu")
		(net "GPS2_PIN11")
	)
	(segment
		(start 224.67426 70.86804)
		(end 225.24649 70.29581)
		(width 0.2032)
		(layer "In2.Cu")
		(net "GPS2_PIN11")
	)
	(segment
		(start 226.84649 70.29581)
		(end 227.62066 69.52164)
		(width 0.2032)
		(layer "In2.Cu")
		(net "GPS2_PIN11")
	)
	(segment
		(start 225.24649 70.29581)
		(end 226.84649 70.29581)
		(width 0.2032)
		(layer "In2.Cu")
		(net "GPS2_PIN11")
	)
	(segment
		(start 214.3261 82.8162)
		(end 224.67426 72.46804)
		(width 0.2032)
		(layer "In2.Cu")
		(net "GPS2_PIN11")
	)
	(segment
		(start 203.2261 96.9162)
		(end 203.2261 89.6162)
		(width 0.2032)
		(layer "In2.Cu")
		(net "GPS2_PIN11")
	)
	(segment
		(start 224.67426 72.46804)
		(end 224.67426 70.86804)
		(width 0.2032)
		(layer "In2.Cu")
		(net "GPS2_PIN11")
	)
	(segment
		(start 210.0261 82.8162)
		(end 214.3261 82.8162)
		(width 0.2032)
		(layer "In2.Cu")
		(net "GPS2_PIN11")
	)
	(segment
		(start 199.4261 100.7162)
		(end 203.2261 96.9162)
		(width 0.2032)
		(layer "In2.Cu")
		(net "GPS2_PIN11")
	)
	(segment
		(start 189.9002 100.71637)
		(end 189.90037 100.7162)
		(width 0.2032)
		(layer "In2.Cu")
		(net "GPS2_PIN11")
	)
	(segment
		(start 189.90037 100.7162)
		(end 199.4261 100.7162)
		(width 0.2032)
		(layer "In2.Cu")
		(net "GPS2_PIN11")
	)
	(segment
		(start 203.2261 89.6162)
		(end 210.0261 82.8162)
		(width 0.2032)
		(layer "In2.Cu")
		(net "GPS2_PIN11")
	)
	(segment
		(start 227.62066 69.52164)
		(end 230.28709 69.52164)
		(width 0.2032)
		(layer "In2.Cu")
		(net "GPS2_PIN11")
	)
	(segment
		(start 79.4261 59.3162)
		(end 79.9261 58.8162)
		(width 0.2032)
		(layer "F.Cu")
		(net "GPS1_PIN15")
	)
	(segment
		(start 144.3261 76.0162)
		(end 147.4261 79.1162)
		(width 0.2032)
		(layer "F.Cu")
		(net "GPS1_PIN15")
	)
	(segment
		(start 157.5261 100.0162)
		(end 162.7261 100.0162)
		(width 0.2032)
		(layer "F.Cu")
		(net "GPS1_PIN15")
	)
	(segment
		(start 79.5385 59.8286)
		(end 81.9311 59.8286)
		(width 0.2032)
		(layer "F.Cu")
		(net "GPS1_PIN15")
	)
	(segment
		(start 162.7261 100.0162)
		(end 162.82835 99.91395)
		(width 0.2032)
		(layer "F.Cu")
		(net "GPS1_PIN15")
	)
	(segment
		(start 79.9261 58.8162)
		(end 96.0261 58.8162)
		(width 0.2032)
		(layer "F.Cu")
		(net "GPS1_PIN15")
	)
	(segment
		(start 96.0261 58.8162)
		(end 113.2261 76.0162)
		(width 0.2032)
		(layer "F.Cu")
		(net "GPS1_PIN15")
	)
	(segment
		(start 79.4261 59.7162)
		(end 79.4261 59.3162)
		(width 0.2032)
		(layer "F.Cu")
		(net "GPS1_PIN15")
	)
	(segment
		(start 79.4261 59.7162)
		(end 79.5385 59.8286)
		(width 0.2032)
		(layer "F.Cu")
		(net "GPS1_PIN15")
	)
	(segment
		(start 147.4261 92.4162)
		(end 147.4261 79.1162)
		(width 0.2032)
		(layer "F.Cu")
		(net "GPS1_PIN15")
	)
	(segment
		(start 154.5261 97.5162)
		(end 155.0261 97.5162)
		(width 0.2032)
		(layer "F.Cu")
		(net "GPS1_PIN15")
	)
	(segment
		(start 162.82835 99.91395)
		(end 162.82835 97.90213)
		(width 0.2032)
		(layer "F.Cu")
		(net "GPS1_PIN15")
	)
	(segment
		(start 147.4261 92.4162)
		(end 147.7261 92.7162)
		(width 0.2032)
		(layer "F.Cu")
		(net "GPS1_PIN15")
	)
	(segment
		(start 113.2261 76.0162)
		(end 144.3261 76.0162)
		(width 0.2032)
		(layer "F.Cu")
		(net "GPS1_PIN15")
	)
	(segment
		(start 149.7261 92.7162)
		(end 154.5261 97.5162)
		(width 0.2032)
		(layer "F.Cu")
		(net "GPS1_PIN15")
	)
	(segment
		(start 147.7261 92.7162)
		(end 149.7261 92.7162)
		(width 0.2032)
		(layer "F.Cu")
		(net "GPS1_PIN15")
	)
	(segment
		(start 155.0261 97.5162)
		(end 157.5261 100.0162)
		(width 0.2032)
		(layer "F.Cu")
		(net "GPS1_PIN15")
	)
	(segment
		(start 144.5261 82.7162)
		(end 146.3261 84.5162)
		(width 0.2032)
		(layer "F.Cu")
		(net "GPS1_PIN14")
	)
	(segment
		(start 95.9261 60.1162)
		(end 113.2261 77.4162)
		(width 0.2032)
		(layer "F.Cu")
		(net "GPS1_PIN14")
	)
	(segment
		(start 89.4137 61.8286)
		(end 91.1261 60.1162)
		(width 0.2032)
		(layer "F.Cu")
		(net "GPS1_PIN14")
	)
	(segment
		(start 91.1261 60.1162)
		(end 95.9261 60.1162)
		(width 0.2032)
		(layer "F.Cu")
		(net "GPS1_PIN14")
	)
	(segment
		(start 135.6261 77.4162)
		(end 140.9261 82.7162)
		(width 0.2032)
		(layer "F.Cu")
		(net "GPS1_PIN14")
	)
	(segment
		(start 146.3261 96.0162)
		(end 150.9261 100.6162)
		(width 0.2032)
		(layer "F.Cu")
		(net "GPS1_PIN14")
	)
	(segment
		(start 163.32848 100.51382)
		(end 163.32848 97.90213)
		(width 0.2032)
		(layer "F.Cu")
		(net "GPS1_PIN14")
	)
	(segment
		(start 163.2261 100.6162)
		(end 163.32848 100.51382)
		(width 0.2032)
		(layer "F.Cu")
		(net "GPS1_PIN14")
	)
	(segment
		(start 86.3761 61.8286)
		(end 89.4137 61.8286)
		(width 0.2032)
		(layer "F.Cu")
		(net "GPS1_PIN14")
	)
	(segment
		(start 150.9261 100.6162)
		(end 163.2261 100.6162)
		(width 0.2032)
		(layer "F.Cu")
		(net "GPS1_PIN14")
	)
	(segment
		(start 113.2261 77.4162)
		(end 135.6261 77.4162)
		(width 0.2032)
		(layer "F.Cu")
		(net "GPS1_PIN14")
	)
	(segment
		(start 146.3261 96.0162)
		(end 146.3261 84.5162)
		(width 0.2032)
		(layer "F.Cu")
		(net "GPS1_PIN14")
	)
	(segment
		(start 140.9261 82.7162)
		(end 144.5261 82.7162)
		(width 0.2032)
		(layer "F.Cu")
		(net "GPS1_PIN14")
	)
	(segment
		(start 78.8261 61.4162)
		(end 79.2385 61.8286)
		(width 0.2032)
		(layer "F.Cu")
		(net "GPS1_PIN13")
	)
	(segment
		(start 162.1261 92.3162)
		(end 162.5261 92.3162)
		(width 0.2032)
		(layer "F.Cu")
		(net "GPS1_PIN13")
	)
	(segment
		(start 148.4261 91.6162)
		(end 148.4261 78.9162)
		(width 0.2032)
		(layer "F.Cu")
		(net "GPS1_PIN13")
	)
	(segment
		(start 78.8261 58.8162)
		(end 79.5261 58.1162)
		(width 0.2032)
		(layer "F.Cu")
		(net "GPS1_PIN13")
	)
	(segment
		(start 148.4261 91.6162)
		(end 149.5261 91.6162)
		(width 0.2032)
		(layer "F.Cu")
		(net "GPS1_PIN13")
	)
	(segment
		(start 79.5261 58.1162)
		(end 97.5261 58.1162)
		(width 0.2032)
		(layer "F.Cu")
		(net "GPS1_PIN13")
	)
	(segment
		(start 152.5261 94.6162)
		(end 159.8261 94.6162)
		(width 0.2032)
		(layer "F.Cu")
		(net "GPS1_PIN13")
	)
	(segment
		(start 144.9261 75.4162)
		(end 148.4261 78.9162)
		(width 0.2032)
		(layer "F.Cu")
		(net "GPS1_PIN13")
	)
	(segment
		(start 159.8261 94.6162)
		(end 162.1261 92.3162)
		(width 0.2032)
		(layer "F.Cu")
		(net "GPS1_PIN13")
	)
	(segment
		(start 114.8261 75.4162)
		(end 144.9261 75.4162)
		(width 0.2032)
		(layer "F.Cu")
		(net "GPS1_PIN13")
	)
	(segment
		(start 162.82835 93.85236)
		(end 162.82835 92.61845)
		(width 0.2032)
		(layer "F.Cu")
		(net "GPS1_PIN13")
	)
	(segment
		(start 162.5261 92.3162)
		(end 162.82835 92.61845)
		(width 0.2032)
		(layer "F.Cu")
		(net "GPS1_PIN13")
	)
	(segment
		(start 78.8261 61.4162)
		(end 78.8261 58.8162)
		(width 0.2032)
		(layer "F.Cu")
		(net "GPS1_PIN13")
	)
	(segment
		(start 79.2385 61.8286)
		(end 81.9311 61.8286)
		(width 0.2032)
		(layer "F.Cu")
		(net "GPS1_PIN13")
	)
	(segment
		(start 97.5261 58.1162)
		(end 114.8261 75.4162)
		(width 0.2032)
		(layer "F.Cu")
		(net "GPS1_PIN13")
	)
	(segment
		(start 149.5261 91.6162)
		(end 152.5261 94.6162)
		(width 0.2032)
		(layer "F.Cu")
		(net "GPS1_PIN13")
	)
	(segment
		(start 144.3261 83.2162)
		(end 145.8261 84.7162)
		(width 0.2032)
		(layer "F.Cu")
		(net "GPS1_PIN12")
	)
	(segment
		(start 145.8261 96.6162)
		(end 145.8261 84.7162)
		(width 0.2032)
		(layer "F.Cu")
		(net "GPS1_PIN12")
	)
	(segment
		(start 89.31371 63.82859)
		(end 91.5261 61.6162)
		(width 0.2032)
		(layer "F.Cu")
		(net "GPS1_PIN12")
	)
	(segment
		(start 91.5261 61.6162)
		(end 96.2261 61.6162)
		(width 0.2032)
		(layer "F.Cu")
		(net "GPS1_PIN12")
	)
	(segment
		(start 135.5261 78.1162)
		(end 140.6261 83.2162)
		(width 0.2032)
		(layer "F.Cu")
		(net "GPS1_PIN12")
	)
	(segment
		(start 150.4261 101.2162)
		(end 163.3261 101.2162)
		(width 0.2032)
		(layer "F.Cu")
		(net "GPS1_PIN12")
	)
	(segment
		(start 163.82835 100.71395)
		(end 163.82835 97.90213)
		(width 0.2032)
		(layer "F.Cu")
		(net "GPS1_PIN12")
	)
	(segment
		(start 163.3261 101.2162)
		(end 163.82835 100.71395)
		(width 0.2032)
		(layer "F.Cu")
		(net "GPS1_PIN12")
	)
	(segment
		(start 86.3761 63.82859)
		(end 89.31371 63.82859)
		(width 0.2032)
		(layer "F.Cu")
		(net "GPS1_PIN12")
	)
	(segment
		(start 145.8261 96.6162)
		(end 150.4261 101.2162)
		(width 0.2032)
		(layer "F.Cu")
		(net "GPS1_PIN12")
	)
	(segment
		(start 140.6261 83.2162)
		(end 144.3261 83.2162)
		(width 0.2032)
		(layer "F.Cu")
		(net "GPS1_PIN12")
	)
	(segment
		(start 96.2261 61.6162)
		(end 112.7261 78.1162)
		(width 0.2032)
		(layer "F.Cu")
		(net "GPS1_PIN12")
	)
	(segment
		(start 112.7261 78.1162)
		(end 135.5261 78.1162)
		(width 0.2032)
		(layer "F.Cu")
		(net "GPS1_PIN12")
	)
	(segment
		(start 162.9261 91.5162)
		(end 163.32848 91.91858)
		(width 0.2032)
		(layer "F.Cu")
		(net "GPS1_PIN11")
	)
	(segment
		(start 78.1261 63.4162)
		(end 78.1261 58.7162)
		(width 0.2032)
		(layer "F.Cu")
		(net "GPS1_PIN11")
	)
	(segment
		(start 152.6261 93.6162)
		(end 159.8261 93.6162)
		(width 0.2032)
		(layer "F.Cu")
		(net "GPS1_PIN11")
	)
	(segment
		(start 78.1261 63.4162)
		(end 78.55801 63.84811)
		(width 0.2032)
		(layer "F.Cu")
		(net "GPS1_PIN11")
	)
	(segment
		(start 149.1261 90.1162)
		(end 152.6261 93.6162)
		(width 0.2032)
		(layer "F.Cu")
		(net "GPS1_PIN11")
	)
	(segment
		(start 78.55801 63.84811)
		(end 81.91159 63.84811)
		(width 0.2032)
		(layer "F.Cu")
		(net "GPS1_PIN11")
	)
	(segment
		(start 163.32848 93.85236)
		(end 163.32848 91.91858)
		(width 0.2032)
		(layer "F.Cu")
		(net "GPS1_PIN11")
	)
	(segment
		(start 78.1261 58.7162)
		(end 79.4261 57.4162)
		(width 0.2032)
		(layer "F.Cu")
		(net "GPS1_PIN11")
	)
	(segment
		(start 159.8261 93.6162)
		(end 161.9261 91.5162)
		(width 0.2032)
		(layer "F.Cu")
		(net "GPS1_PIN11")
	)
	(segment
		(start 115.4261 74.2162)
		(end 145.7261 74.2162)
		(width 0.2032)
		(layer "F.Cu")
		(net "GPS1_PIN11")
	)
	(segment
		(start 79.4261 57.4162)
		(end 98.6261 57.4162)
		(width 0.2032)
		(layer "F.Cu")
		(net "GPS1_PIN11")
	)
	(segment
		(start 81.91159 63.84811)
		(end 81.9311 63.82859)
		(width 0.2032)
		(layer "F.Cu")
		(net "GPS1_PIN11")
	)
	(segment
		(start 98.6261 57.4162)
		(end 115.4261 74.2162)
		(width 0.2032)
		(layer "F.Cu")
		(net "GPS1_PIN11")
	)
	(segment
		(start 145.7261 74.2162)
		(end 149.1261 77.6162)
		(width 0.2032)
		(layer "F.Cu")
		(net "GPS1_PIN11")
	)
	(segment
		(start 149.1261 90.1162)
		(end 149.1261 77.6162)
		(width 0.2032)
		(layer "F.Cu")
		(net "GPS1_PIN11")
	)
	(segment
		(start 161.9261 91.5162)
		(end 162.9261 91.5162)
		(width 0.2032)
		(layer "F.Cu")
		(net "GPS1_PIN11")
	)
	(segment
		(start 170.82833 99.81843)
		(end 170.82833 97.90213)
		(width 0.2032)
		(layer "F.Cu")
		(net "NetJ35_33")
	)
	(segment
		(start 171.4261 101.8162)
		(end 171.4261 100.4162)
		(width 0.2032)
		(layer "F.Cu")
		(net "NetJ35_33")
	)
	(segment
		(start 170.82833 99.81843)
		(end 171.4261 100.4162)
		(width 0.2032)
		(layer "F.Cu")
		(net "NetJ35_33")
	)
	(segment
		(start 99.0661 87.2762)
		(end 99.0661 85.6162)
		(width 0.2032)
		(layer "F.Cu")
		(net "NetP1_5")
	)
	(segment
		(start 98.7261 87.6162)
		(end 99.0661 87.2762)
		(width 0.2032)
		(layer "F.Cu")
		(net "NetP1_5")
	)
	(via
		(at 152.7261 84.8162)
		(size 0.4064)
		(drill 0.2032)
		(layers "F.Cu" "B.Cu")
		(tenting
			(front yes)
			(back yes)
		)
		(net "MAC_VCC")
	)
	(via
		(at 152.7261 84.0162)
		(size 0.4064)
		(drill 0.2032)
		(layers "F.Cu" "B.Cu")
		(tenting
			(front yes)
			(back yes)
		)
		(net "MAC_VCC")
	)
	(via
		(at 153.2261 84.0162)
		(size 0.4064)
		(drill 0.2032)
		(layers "F.Cu" "B.Cu")
		(tenting
			(front yes)
			(back yes)
		)
		(net "MAC_VCC")
	)
	(via
		(at 152.2261 84.8162)
		(size 0.4064)
		(drill 0.2032)
		(layers "F.Cu" "B.Cu")
		(tenting
			(front yes)
			(back yes)
		)
		(net "MAC_VCC")
	)
	(via
		(at 152.2261 84.0162)
		(size 0.4064)
		(drill 0.2032)
		(layers "F.Cu" "B.Cu")
		(tenting
			(front yes)
			(back yes)
		)
		(net "MAC_VCC")
	)
	(via
		(at 153.2261 84.8162)
		(size 0.4064)
		(drill 0.2032)
		(layers "F.Cu" "B.Cu")
		(tenting
			(front yes)
			(back yes)
		)
		(net "MAC_VCC")
	)
	(segment
		(start 125.5261 83.3162)
		(end 125.6261 83.3162)
		(width 0.2032)
		(layer "F.Cu")
		(net "MAC_PPS_OUT")
	)
	(segment
		(start 124.7511 84.0912)
		(end 125.0225 83.8198)
		(width 0.2032)
		(layer "F.Cu")
		(net "MAC_PPS_OUT")
	)
	(segment
		(start 125.0225 83.79651)
		(end 125.15641 83.6626)
		(width 0.2032)
		(layer "F.Cu")
		(net "MAC_PPS_OUT")
	)
	(segment
		(start 125.15641 83.6626)
		(end 125.1797 83.6626)
		(width 0.2032)
		(layer "F.Cu")
		(net "MAC_PPS_OUT")
	)
	(segment
		(start 125.0225 83.8198)
		(end 125.0225 83.79651)
		(width 0.2032)
		(layer "F.Cu")
		(net "MAC_PPS_OUT")
	)
	(segment
		(start 124.6761 84.0412)
		(end 124.7511 84.1162)
		(width 0.2032)
		(layer "F.Cu")
		(net "MAC_PPS_OUT")
	)
	(segment
		(start 125.1797 83.6626)
		(end 125.5261 83.3162)
		(width 0.2032)
		(layer "F.Cu")
		(net "MAC_PPS_OUT")
	)
	(segment
		(start 122.8261 84.0412)
		(end 124.6761 84.0412)
		(width 0.2032)
		(layer "F.Cu")
		(net "MAC_PPS_OUT")
	)
	(segment
		(start 124.7511 84.1162)
		(end 124.7511 84.0912)
		(width 0.2032)
		(layer "F.Cu")
		(net "MAC_PPS_OUT")
	)
	(via
		(at 125.6261 83.3162)
		(size 0.4064)
		(drill 0.2032)
		(layers "F.Cu" "B.Cu")
		(net "MAC_PPS_OUT")
	)
	(segment
		(start 123.4261 135.9122)
		(end 123.4261 86.2162)
		(width 0.2032)
		(layer "B.Cu")
		(net "MAC_PPS_OUT")
	)
	(segment
		(start 125.6261 84.9162)
		(end 125.6261 83.3162)
		(width 0.2032)
		(layer "B.Cu")
		(net "MAC_PPS_OUT")
	)
	(segment
		(start 124.5261 86.0162)
		(end 125.6261 84.9162)
		(width 0.2032)
		(layer "B.Cu")
		(net "MAC_PPS_OUT")
	)
	(segment
		(start 123.4261 135.9122)
		(end 125.7301 138.2162)
		(width 0.2032)
		(layer "B.Cu")
		(net "MAC_PPS_OUT")
	)
	(segment
		(start 123.6261 86.0162)
		(end 124.5261 86.0162)
		(width 0.2032)
		(layer "B.Cu")
		(net "MAC_PPS_OUT")
	)
	(segment
		(start 123.4261 86.2162)
		(end 123.6261 86.0162)
		(width 0.2032)
		(layer "B.Cu")
		(net "MAC_PPS_OUT")
	)
	(segment
		(start 128.3779 83.56436)
		(end 128.4011 83.58756)
		(width 0.254)
		(layer "F.Cu")
		(net "MAC_PPS_IN")
	)
	(segment
		(start 128.2511 83.43756)
		(end 128.2511 81.7162)
		(width 0.254)
		(layer "F.Cu")
		(net "MAC_PPS_IN")
	)
	(segment
		(start 128.4011 84.4162)
		(end 128.4011 83.58756)
		(width 0.254)
		(layer "F.Cu")
		(net "MAC_PPS_IN")
	)
	(segment
		(start 128.2511 83.43756)
		(end 128.3779 83.56436)
		(width 0.254)
		(layer "F.Cu")
		(net "MAC_PPS_IN")
	)
	(via
		(at 128.3779 83.56436)
		(size 0.4064)
		(drill 0.2032)
		(layers "F.Cu" "B.Cu")
		(net "MAC_PPS_IN")
	)
	(segment
		(start 123.9261 87.6162)
		(end 124.3261 88.0162)
		(width 0.254)
		(layer "B.Cu")
		(net "MAC_PPS_IN")
	)
	(segment
		(start 125.6261 86.5162)
		(end 128.3779 83.76439)
		(width 0.254)
		(layer "B.Cu")
		(net "MAC_PPS_IN")
	)
	(segment
		(start 128.3779 83.76439)
		(end 128.3779 83.56436)
		(width 0.254)
		(layer "B.Cu")
		(net "MAC_PPS_IN")
	)
	(segment
		(start 124.3261 133.7642)
		(end 128.7781 138.2162)
		(width 0.254)
		(layer "B.Cu")
		(net "MAC_PPS_IN")
	)
	(segment
		(start 123.9261 86.5162)
		(end 125.6261 86.5162)
		(width 0.254)
		(layer "B.Cu")
		(net "MAC_PPS_IN")
	)
	(segment
		(start 123.9261 87.6162)
		(end 123.9261 86.5162)
		(width 0.254)
		(layer "B.Cu")
		(net "MAC_PPS_IN")
	)
	(segment
		(start 124.3261 133.7642)
		(end 124.3261 88.0162)
		(width 0.254)
		(layer "B.Cu")
		(net "MAC_PPS_IN")
	)
	(segment
		(start 69.8761 54.9412)
		(end 69.8761 52.8662)
		(width 0.2032)
		(layer "F.Cu")
		(net "NetD3_1")
	)
	(segment
		(start 84.1261 89.6162)
		(end 84.8761 88.8662)
		(width 0.254)
		(layer "F.Cu")
		(net "NetR41_2")
	)
	(segment
		(start 84.8761 88.6162)
		(end 85.8761 87.6162)
		(width 0.254)
		(layer "F.Cu")
		(net "NetR41_2")
	)
	(segment
		(start 84.8761 88.6162)
		(end 84.8761 88.6162)
		(width 0.254)
		(layer "F.Cu")
		(net "NetR41_2")
	)
	(segment
		(start 84.8761 88.8662)
		(end 84.8761 88.6162)
		(width 0.254)
		(layer "F.Cu")
		(net "NetR41_2")
	)
	(segment
		(start 85.8761 87.6162)
		(end 87.0511 87.6162)
		(width 0.254)
		(layer "F.Cu")
		(net "NetR41_2")
	)
	(segment
		(start 79.6261 135.6162)
		(end 79.8761 135.8662)
		(width 0.2032)
		(layer "F.Cu")
		(net "NetR34_1")
	)
	(segment
		(start 79.8761 135.8662)
		(end 80.5511 135.8662)
		(width 0.2032)
		(layer "F.Cu")
		(net "NetR34_1")
	)
	(segment
		(start 78.2761 135.6162)
		(end 79.6261 135.6162)
		(width 0.2032)
		(layer "F.Cu")
		(net "NetR34_1")
	)
	(segment
		(start 79.6261 135.6162)
		(end 79.8761 135.3662)
		(width 0.2032)
		(layer "F.Cu")
		(net "NetR34_1")
	)
	(segment
		(start 79.8761 135.3662)
		(end 80.5511 135.3662)
		(width 0.2032)
		(layer "F.Cu")
		(net "NetR34_1")
	)
	(segment
		(start 80.1261 108.3662)
		(end 80.8011 108.3662)
		(width 0.2032)
		(layer "F.Cu")
		(net "NetR33_1")
	)
	(segment
		(start 79.8761 108.6162)
		(end 80.1261 108.8662)
		(width 0.2032)
		(layer "F.Cu")
		(net "NetR33_1")
	)
	(segment
		(start 78.5761 108.6162)
		(end 79.8761 108.6162)
		(width 0.2032)
		(layer "F.Cu")
		(net "NetR33_1")
	)
	(segment
		(start 79.8761 108.6162)
		(end 80.1261 108.3662)
		(width 0.2032)
		(layer "F.Cu")
		(net "NetR33_1")
	)
	(segment
		(start 80.1261 108.8662)
		(end 80.8011 108.8662)
		(width 0.2032)
		(layer "F.Cu")
		(net "NetR33_1")
	)
	(segment
		(start 80.0713 122.1162)
		(end 80.8011 122.1162)
		(width 0.2032)
		(layer "F.Cu")
		(net "NetR28_1")
	)
	(segment
		(start 80.0713 121.6162)
		(end 80.8011 121.6162)
		(width 0.2032)
		(layer "F.Cu")
		(net "NetR28_1")
	)
	(segment
		(start 79.8213 121.8662)
		(end 80.0713 121.6162)
		(width 0.2032)
		(layer "F.Cu")
		(net "NetR28_1")
	)
	(segment
		(start 78.5761 121.8662)
		(end 79.8213 121.8662)
		(width 0.2032)
		(layer "F.Cu")
		(net "NetR28_1")
	)
	(segment
		(start 79.8213 121.8662)
		(end 80.0713 122.1162)
		(width 0.2032)
		(layer "F.Cu")
		(net "NetR28_1")
	)
	(segment
		(start 58.4261 140.3912)
		(end 58.4511 140.4162)
		(width 0.2032)
		(layer "F.Cu")
		(net "NetD18_4")
	)
	(segment
		(start 88.8641 84.7792)
		(end 88.8761 84.7912)
		(width 0.2032)
		(layer "F.Cu")
		(net "NetD18_4")
	)
	(segment
		(start 57.1261 140.3662)
		(end 57.1511 140.3912)
		(width 0.2032)
		(layer "F.Cu")
		(net "NetD18_4")
	)
	(segment
		(start 88.8641 84.7792)
		(end 88.8641 83.6282)
		(width 0.2032)
		(layer "F.Cu")
		(net "NetD18_4")
	)
	(segment
		(start 57.1511 140.3912)
		(end 58.4261 140.3912)
		(width 0.2032)
		(layer "F.Cu")
		(net "NetD18_4")
	)
	(segment
		(start 88.8521 83.6162)
		(end 88.8641 83.6282)
		(width 0.2032)
		(layer "F.Cu")
		(net "NetD18_4")
	)
	(via
		(at 88.8521 83.6162)
		(size 0.4064)
		(drill 0.2032)
		(layers "F.Cu" "B.Cu")
		(tenting
			(front yes)
			(back yes)
		)
		(net "NetD18_4")
	)
	(via
		(at 57.1261 140.3662)
		(size 0.4064)
		(drill 0.2032)
		(layers "F.Cu" "B.Cu")
		(tenting
			(front yes)
			(back yes)
		)
		(net "NetD18_4")
	)
	(segment
		(start 88.8681 82.84117)
		(end 89.68267 82.0266)
		(width 0.2032)
		(layer "B.Cu")
		(net "NetD18_4")
	)
	(segment
		(start 66.6261 140.3662)
		(end 70.7157 136.2766)
		(width 0.2032)
		(layer "B.Cu")
		(net "NetD18_4")
	)
	(segment
		(start 96.4657 90.59266)
		(end 96.4657 86.38974)
		(width 0.2032)
		(layer "B.Cu")
		(net "NetD18_4")
	)
	(segment
		(start 88.8521 83.6162)
		(end 88.8681 83.6002)
		(width 0.2032)
		(layer "B.Cu")
		(net "NetD18_4")
	)
	(segment
		(start 70.7157 136.2766)
		(end 70.7157 107.47934)
		(width 0.2032)
		(layer "B.Cu")
		(net "NetD18_4")
	)
	(segment
		(start 90.85256 96.2058)
		(end 96.4657 90.59266)
		(width 0.2032)
		(layer "B.Cu")
		(net "NetD18_4")
	)
	(segment
		(start 81.98924 96.2058)
		(end 90.85256 96.2058)
		(width 0.2032)
		(layer "B.Cu")
		(net "NetD18_4")
	)
	(segment
		(start 89.68267 82.0266)
		(end 92.10256 82.0266)
		(width 0.2032)
		(layer "B.Cu")
		(net "NetD18_4")
	)
	(segment
		(start 57.1261 140.3662)
		(end 66.6261 140.3662)
		(width 0.2032)
		(layer "B.Cu")
		(net "NetD18_4")
	)
	(segment
		(start 88.8681 83.6002)
		(end 88.8681 82.84117)
		(width 0.2032)
		(layer "B.Cu")
		(net "NetD18_4")
	)
	(segment
		(start 92.10256 82.0266)
		(end 96.4657 86.38974)
		(width 0.2032)
		(layer "B.Cu")
		(net "NetD18_4")
	)
	(segment
		(start 70.7157 107.47934)
		(end 81.98924 96.2058)
		(width 0.2032)
		(layer "B.Cu")
		(net "NetD18_4")
	)
	(segment
		(start 88.3441 83.82662)
		(end 88.3441 83.1322)
		(width 0.2032)
		(layer "F.Cu")
		(net "NetD18_3")
	)
	(segment
		(start 88.3441 83.82662)
		(end 88.3761 83.85862)
		(width 0.2032)
		(layer "F.Cu")
		(net "NetD18_3")
	)
	(segment
		(start 88.3761 84.7912)
		(end 88.3761 83.85862)
		(width 0.2032)
		(layer "F.Cu")
		(net "NetD18_3")
	)
	(segment
		(start 88.3441 83.1322)
		(end 88.3601 83.1162)
		(width 0.2032)
		(layer "F.Cu")
		(net "NetD18_3")
	)
	(segment
		(start 57.1261 141.3662)
		(end 58.1261 141.3662)
		(width 0.2032)
		(layer "F.Cu")
		(net "NetD18_3")
	)
	(via
		(at 57.1261 141.3662)
		(size 0.4064)
		(drill 0.2032)
		(layers "F.Cu" "B.Cu")
		(tenting
			(front yes)
			(back yes)
		)
		(net "NetD18_3")
	)
	(via
		(at 88.3601 83.1162)
		(size 0.4064)
		(drill 0.2032)
		(layers "F.Cu" "B.Cu")
		(tenting
			(front yes)
			(back yes)
		)
		(net "NetD18_3")
	)
	(segment
		(start 90.98933 96.536)
		(end 96.7959 90.72943)
		(width 0.2032)
		(layer "B.Cu")
		(net "NetD18_3")
	)
	(segment
		(start 71.0459 136.41337)
		(end 71.0459 107.61611)
		(width 0.2032)
		(layer "B.Cu")
		(net "NetD18_3")
	)
	(segment
		(start 88.39898 82.84332)
		(end 89.5459 81.6964)
		(width 0.2032)
		(layer "B.Cu")
		(net "NetD18_3")
	)
	(segment
		(start 82.12601 96.536)
		(end 90.98933 96.536)
		(width 0.2032)
		(layer "B.Cu")
		(net "NetD18_3")
	)
	(segment
		(start 66.09307 141.3662)
		(end 71.0459 136.41337)
		(width 0.2032)
		(layer "B.Cu")
		(net "NetD18_3")
	)
	(segment
		(start 71.0459 107.61611)
		(end 82.12601 96.536)
		(width 0.2032)
		(layer "B.Cu")
		(net "NetD18_3")
	)
	(segment
		(start 92.23933 81.6964)
		(end 96.7959 86.25297)
		(width 0.2032)
		(layer "B.Cu")
		(net "NetD18_3")
	)
	(segment
		(start 57.1261 141.3662)
		(end 66.09307 141.3662)
		(width 0.2032)
		(layer "B.Cu")
		(net "NetD18_3")
	)
	(segment
		(start 88.3601 83.1162)
		(end 88.39898 83.07732)
		(width 0.2032)
		(layer "B.Cu")
		(net "NetD18_3")
	)
	(segment
		(start 88.39898 83.07732)
		(end 88.39898 82.84332)
		(width 0.2032)
		(layer "B.Cu")
		(net "NetD18_3")
	)
	(segment
		(start 96.7959 90.72943)
		(end 96.7959 86.25297)
		(width 0.2032)
		(layer "B.Cu")
		(net "NetD18_3")
	)
	(segment
		(start 89.5459 81.6964)
		(end 92.23933 81.6964)
		(width 0.2032)
		(layer "B.Cu")
		(net "NetD18_3")
	)
	(segment
		(start 87.8561 84.7712)
		(end 87.8761 84.7912)
		(width 0.2032)
		(layer "F.Cu")
		(net "NetD18_2")
	)
	(segment
		(start 58.01498 142.15508)
		(end 58.1261 142.2662)
		(width 0.2032)
		(layer "F.Cu")
		(net "NetD18_2")
	)
	(segment
		(start 57.1261 142.1162)
		(end 57.16498 142.15508)
		(width 0.2032)
		(layer "F.Cu")
		(net "NetD18_2")
	)
	(segment
		(start 57.16498 142.15508)
		(end 58.01498 142.15508)
		(width 0.2032)
		(layer "F.Cu")
		(net "NetD18_2")
	)
	(segment
		(start 87.8561 84.7712)
		(end 87.8561 83.6362)
		(width 0.2032)
		(layer "F.Cu")
		(net "NetD18_2")
	)
	(segment
		(start 87.8361 83.6162)
		(end 87.8561 83.6362)
		(width 0.2032)
		(layer "F.Cu")
		(net "NetD18_2")
	)
	(via
		(at 57.1261 142.1162)
		(size 0.4064)
		(drill 0.2032)
		(layers "F.Cu" "B.Cu")
		(tenting
			(front yes)
			(back yes)
		)
		(net "NetD18_2")
	)
	(via
		(at 87.8361 83.6162)
		(size 0.4064)
		(drill 0.2032)
		(layers "F.Cu" "B.Cu")
		(tenting
			(front yes)
			(back yes)
		)
		(net "NetD18_2")
	)
	(segment
		(start 92.3761 81.3662)
		(end 97.1261 86.1162)
		(width 0.2032)
		(layer "B.Cu")
		(net "NetD18_2")
	)
	(segment
		(start 89.3761 81.3662)
		(end 92.3761 81.3662)
		(width 0.2032)
		(layer "B.Cu")
		(net "NetD18_2")
	)
	(segment
		(start 71.3761 107.75289)
		(end 82.26278 96.8662)
		(width 0.2032)
		(layer "B.Cu")
		(net "NetD18_2")
	)
	(segment
		(start 71.3761 136.55014)
		(end 71.3761 107.75289)
		(width 0.2032)
		(layer "B.Cu")
		(net "NetD18_2")
	)
	(segment
		(start 87.8361 83.6162)
		(end 87.8361 82.9062)
		(width 0.2032)
		(layer "B.Cu")
		(net "NetD18_2")
	)
	(segment
		(start 87.8361 82.9062)
		(end 89.3761 81.3662)
		(width 0.2032)
		(layer "B.Cu")
		(net "NetD18_2")
	)
	(segment
		(start 82.26278 96.8662)
		(end 91.1261 96.8662)
		(width 0.2032)
		(layer "B.Cu")
		(net "NetD18_2")
	)
	(segment
		(start 97.1261 90.8662)
		(end 97.1261 86.1162)
		(width 0.2032)
		(layer "B.Cu")
		(net "NetD18_2")
	)
	(segment
		(start 57.1261 142.1162)
		(end 65.81004 142.1162)
		(width 0.2032)
		(layer "B.Cu")
		(net "NetD18_2")
	)
	(segment
		(start 65.81004 142.1162)
		(end 71.3761 136.55014)
		(width 0.2032)
		(layer "B.Cu")
		(net "NetD18_2")
	)
	(segment
		(start 91.1261 96.8662)
		(end 97.1261 90.8662)
		(width 0.2032)
		(layer "B.Cu")
		(net "NetD18_2")
	)
	(segment
		(start 90.8961 83.6442)
		(end 90.9161 83.6242)
		(width 0.2032)
		(layer "F.Cu")
		(net "NetD17_4")
	)
	(segment
		(start 90.8761 84.7912)
		(end 90.8961 84.7712)
		(width 0.2032)
		(layer "F.Cu")
		(net "NetD17_4")
	)
	(segment
		(start 58.33998 126.90508)
		(end 58.4511 127.0162)
		(width 0.2032)
		(layer "F.Cu")
		(net "NetD17_4")
	)
	(segment
		(start 57.16498 126.90508)
		(end 58.33998 126.90508)
		(width 0.2032)
		(layer "F.Cu")
		(net "NetD17_4")
	)
	(segment
		(start 90.8961 84.7712)
		(end 90.8961 83.6442)
		(width 0.2032)
		(layer "F.Cu")
		(net "NetD17_4")
	)
	(segment
		(start 57.1261 126.8662)
		(end 57.16498 126.90508)
		(width 0.2032)
		(layer "F.Cu")
		(net "NetD17_4")
	)
	(via
		(at 57.1261 126.8662)
		(size 0.4064)
		(drill 0.2032)
		(layers "F.Cu" "B.Cu")
		(tenting
			(front yes)
			(back yes)
		)
		(net "NetD17_4")
	)
	(via
		(at 90.9161 83.6242)
		(size 0.4064)
		(drill 0.2032)
		(layers "F.Cu" "B.Cu")
		(tenting
			(front yes)
			(back yes)
		)
		(net "NetD17_4")
	)
	(segment
		(start 67.3761 126.8662)
		(end 69.7251 124.5172)
		(width 0.2032)
		(layer "B.Cu")
		(net "NetD17_4")
	)
	(segment
		(start 90.9241 83.6162)
		(end 92.29125 83.6162)
		(width 0.2032)
		(layer "B.Cu")
		(net "NetD17_4")
	)
	(segment
		(start 69.7251 107.06903)
		(end 81.57893 95.2152)
		(width 0.2032)
		(layer "B.Cu")
		(net "NetD17_4")
	)
	(segment
		(start 92.29125 83.6162)
		(end 95.4751 86.80005)
		(width 0.2032)
		(layer "B.Cu")
		(net "NetD17_4")
	)
	(segment
		(start 69.7251 124.5172)
		(end 69.7251 107.06903)
		(width 0.2032)
		(layer "B.Cu")
		(net "NetD17_4")
	)
	(segment
		(start 57.1261 126.8662)
		(end 67.3761 126.8662)
		(width 0.2032)
		(layer "B.Cu")
		(net "NetD17_4")
	)
	(segment
		(start 81.57893 95.2152)
		(end 90.44224 95.2152)
		(width 0.2032)
		(layer "B.Cu")
		(net "NetD17_4")
	)
	(segment
		(start 90.44224 95.2152)
		(end 95.4751 90.18234)
		(width 0.2032)
		(layer "B.Cu")
		(net "NetD17_4")
	)
	(segment
		(start 95.4751 90.18234)
		(end 95.4751 86.80005)
		(width 0.2032)
		(layer "B.Cu")
		(net "NetD17_4")
	)
	(segment
		(start 90.9161 83.6242)
		(end 90.9241 83.6162)
		(width 0.2032)
		(layer "B.Cu")
		(net "NetD17_4")
	)
	(segment
		(start 90.3761 84.7912)
		(end 90.3921 84.7752)
		(width 0.2032)
		(layer "F.Cu")
		(net "NetD17_3")
	)
	(segment
		(start 57.16498 127.90508)
		(end 58.06498 127.90508)
		(width 0.2032)
		(layer "F.Cu")
		(net "NetD17_3")
	)
	(segment
		(start 90.3921 84.7752)
		(end 90.3921 83.1162)
		(width 0.2032)
		(layer "F.Cu")
		(net "NetD17_3")
	)
	(segment
		(start 58.06498 127.90508)
		(end 58.1261 127.9662)
		(width 0.2032)
		(layer "F.Cu")
		(net "NetD17_3")
	)
	(segment
		(start 57.1261 127.8662)
		(end 57.16498 127.90508)
		(width 0.2032)
		(layer "F.Cu")
		(net "NetD17_3")
	)
	(via
		(at 90.3921 83.1162)
		(size 0.4064)
		(drill 0.2032)
		(layers "F.Cu" "B.Cu")
		(tenting
			(front yes)
			(back yes)
		)
		(net "NetD17_3")
	)
	(via
		(at 57.1261 127.8662)
		(size 0.4064)
		(drill 0.2032)
		(layers "F.Cu" "B.Cu")
		(tenting
			(front yes)
			(back yes)
		)
		(net "NetD17_3")
	)
	(segment
		(start 70.0553 124.65397)
		(end 70.0553 107.2058)
		(width 0.2032)
		(layer "B.Cu")
		(net "NetD17_3")
	)
	(segment
		(start 66.84307 127.8662)
		(end 70.0553 124.65397)
		(width 0.2032)
		(layer "B.Cu")
		(net "NetD17_3")
	)
	(segment
		(start 90.57901 95.5454)
		(end 95.8053 90.31911)
		(width 0.2032)
		(layer "B.Cu")
		(net "NetD17_3")
	)
	(segment
		(start 81.7157 95.5454)
		(end 90.57901 95.5454)
		(width 0.2032)
		(layer "B.Cu")
		(net "NetD17_3")
	)
	(segment
		(start 95.8053 90.31911)
		(end 95.8053 86.66328)
		(width 0.2032)
		(layer "B.Cu")
		(net "NetD17_3")
	)
	(segment
		(start 57.1261 127.8662)
		(end 66.84307 127.8662)
		(width 0.2032)
		(layer "B.Cu")
		(net "NetD17_3")
	)
	(segment
		(start 70.0553 107.2058)
		(end 81.7157 95.5454)
		(width 0.2032)
		(layer "B.Cu")
		(net "NetD17_3")
	)
	(segment
		(start 92.25822 83.1162)
		(end 95.8053 86.66328)
		(width 0.2032)
		(layer "B.Cu")
		(net "NetD17_3")
	)
	(segment
		(start 90.3921 83.1162)
		(end 92.25822 83.1162)
		(width 0.2032)
		(layer "B.Cu")
		(net "NetD17_3")
	)
	(segment
		(start 89.8761 84.7912)
		(end 89.8801 84.7872)
		(width 0.2032)
		(layer "F.Cu")
		(net "NetD17_2")
	)
	(segment
		(start 89.8801 84.7872)
		(end 89.8801 83.6202)
		(width 0.2032)
		(layer "F.Cu")
		(net "NetD17_2")
	)
	(segment
		(start 89.8801 83.6202)
		(end 89.8841 83.6162)
		(width 0.2032)
		(layer "F.Cu")
		(net "NetD17_2")
	)
	(segment
		(start 57.1261 128.8662)
		(end 58.1261 128.8662)
		(width 0.2032)
		(layer "F.Cu")
		(net "NetD17_2")
	)
	(via
		(at 57.1261 128.8662)
		(size 0.4064)
		(drill 0.2032)
		(layers "F.Cu" "B.Cu")
		(tenting
			(front yes)
			(back yes)
		)
		(net "NetD17_2")
	)
	(via
		(at 89.8841 83.6162)
		(size 0.4064)
		(drill 0.2032)
		(layers "F.Cu" "B.Cu")
		(tenting
			(front yes)
			(back yes)
		)
		(net "NetD17_2")
	)
	(segment
		(start 89.8841 82.8582)
		(end 90.3761 82.3662)
		(width 0.2032)
		(layer "B.Cu")
		(net "NetD17_2")
	)
	(segment
		(start 90.71578 95.8756)
		(end 96.1355 90.45588)
		(width 0.2032)
		(layer "B.Cu")
		(net "NetD17_2")
	)
	(segment
		(start 91.97519 82.3662)
		(end 96.1355 86.52651)
		(width 0.2032)
		(layer "B.Cu")
		(net "NetD17_2")
	)
	(segment
		(start 66.31004 128.8662)
		(end 70.3855 124.79074)
		(width 0.2032)
		(layer "B.Cu")
		(net "NetD17_2")
	)
	(segment
		(start 89.8841 83.6162)
		(end 89.8841 82.8582)
		(width 0.2032)
		(layer "B.Cu")
		(net "NetD17_2")
	)
	(segment
		(start 57.1261 128.8662)
		(end 66.31004 128.8662)
		(width 0.2032)
		(layer "B.Cu")
		(net "NetD17_2")
	)
	(segment
		(start 90.3761 82.3662)
		(end 91.97519 82.3662)
		(width 0.2032)
		(layer "B.Cu")
		(net "NetD17_2")
	)
	(segment
		(start 96.1355 90.45588)
		(end 96.1355 86.52651)
		(width 0.2032)
		(layer "B.Cu")
		(net "NetD17_2")
	)
	(segment
		(start 70.3855 124.79074)
		(end 70.3855 107.34257)
		(width 0.2032)
		(layer "B.Cu")
		(net "NetD17_2")
	)
	(segment
		(start 81.85247 95.8756)
		(end 90.71578 95.8756)
		(width 0.2032)
		(layer "B.Cu")
		(net "NetD17_2")
	)
	(segment
		(start 70.3855 107.34257)
		(end 81.85247 95.8756)
		(width 0.2032)
		(layer "B.Cu")
		(net "NetD17_2")
	)
	(segment
		(start 91.70503 86.62012)
		(end 92.87218 86.62012)
		(width 0.2032)
		(layer "F.Cu")
		(net "NetD16_4")
	)
	(segment
		(start 92.87218 86.62012)
		(end 92.8761 86.62405)
		(width 0.2032)
		(layer "F.Cu")
		(net "NetD16_4")
	)
	(segment
		(start 57.1261 113.3662)
		(end 57.1511 113.3912)
		(width 0.2032)
		(layer "F.Cu")
		(net "NetD16_4")
	)
	(segment
		(start 57.1511 113.3912)
		(end 58.4261 113.3912)
		(width 0.2032)
		(layer "F.Cu")
		(net "NetD16_4")
	)
	(segment
		(start 58.4261 113.3912)
		(end 58.4511 113.4162)
		(width 0.2032)
		(layer "F.Cu")
		(net "NetD16_4")
	)
	(segment
		(start 91.7011 86.6162)
		(end 91.70503 86.62012)
		(width 0.2032)
		(layer "F.Cu")
		(net "NetD16_4")
	)
	(via
		(at 92.8761 86.62405)
		(size 0.4064)
		(drill 0.2032)
		(layers "F.Cu" "B.Cu")
		(tenting
			(front yes)
			(back yes)
		)
		(net "NetD16_4")
	)
	(via
		(at 57.1261 113.3662)
		(size 0.4064)
		(drill 0.2032)
		(layers "F.Cu" "B.Cu")
		(tenting
			(front yes)
			(back yes)
		)
		(net "NetD16_4")
	)
	(segment
		(start 66.94216 113.3662)
		(end 68.7345 111.57386)
		(width 0.2032)
		(layer "B.Cu")
		(net "NetD16_4")
	)
	(segment
		(start 68.7345 106.65872)
		(end 81.16861 94.2246)
		(width 0.2032)
		(layer "B.Cu")
		(net "NetD16_4")
	)
	(segment
		(start 68.7345 111.57386)
		(end 68.7345 106.65872)
		(width 0.2032)
		(layer "B.Cu")
		(net "NetD16_4")
	)
	(segment
		(start 93.88395 86.62405)
		(end 94.4845 87.2246)
		(width 0.2032)
		(layer "B.Cu")
		(net "NetD16_4")
	)
	(segment
		(start 57.1261 113.3662)
		(end 66.94216 113.3662)
		(width 0.2032)
		(layer "B.Cu")
		(net "NetD16_4")
	)
	(segment
		(start 94.4845 89.77203)
		(end 94.4845 87.2246)
		(width 0.2032)
		(layer "B.Cu")
		(net "NetD16_4")
	)
	(segment
		(start 92.8761 86.62405)
		(end 93.88395 86.62405)
		(width 0.2032)
		(layer "B.Cu")
		(net "NetD16_4")
	)
	(segment
		(start 81.16861 94.2246)
		(end 90.03193 94.2246)
		(width 0.2032)
		(layer "B.Cu")
		(net "NetD16_4")
	)
	(segment
		(start 90.03193 94.2246)
		(end 94.4845 89.77203)
		(width 0.2032)
		(layer "B.Cu")
		(net "NetD16_4")
	)
	(segment
		(start 57.1261 114.3662)
		(end 58.1261 114.3662)
		(width 0.2032)
		(layer "F.Cu")
		(net "NetD16_3")
	)
	(segment
		(start 91.70126 86.11605)
		(end 93.3761 86.11605)
		(width 0.2032)
		(layer "F.Cu")
		(net "NetD16_3")
	)
	(segment
		(start 91.7011 86.1162)
		(end 91.70126 86.11605)
		(width 0.2032)
		(layer "F.Cu")
		(net "NetD16_3")
	)
	(via
		(at 93.3761 86.11605)
		(size 0.4064)
		(drill 0.2032)
		(layers "F.Cu" "B.Cu")
		(tenting
			(front yes)
			(back yes)
		)
		(net "NetD16_3")
	)
	(via
		(at 57.1261 114.3662)
		(size 0.4064)
		(drill 0.2032)
		(layers "F.Cu" "B.Cu")
		(tenting
			(front yes)
			(back yes)
		)
		(net "NetD16_3")
	)
	(segment
		(start 57.1261 114.3662)
		(end 66.40913 114.3662)
		(width 0.2032)
		(layer "B.Cu")
		(net "NetD16_3")
	)
	(segment
		(start 93.8841 86.143)
		(end 94.8147 87.0736)
		(width 0.2032)
		(layer "B.Cu")
		(net "NetD16_3")
	)
	(segment
		(start 81.30538 94.5548)
		(end 90.1687 94.5548)
		(width 0.2032)
		(layer "B.Cu")
		(net "NetD16_3")
	)
	(segment
		(start 66.40913 114.3662)
		(end 69.0647 111.71063)
		(width 0.2032)
		(layer "B.Cu")
		(net "NetD16_3")
	)
	(segment
		(start 69.0647 106.79549)
		(end 81.30538 94.5548)
		(width 0.2032)
		(layer "B.Cu")
		(net "NetD16_3")
	)
	(segment
		(start 93.3761 86.11605)
		(end 93.40305 86.143)
		(width 0.2032)
		(layer "B.Cu")
		(net "NetD16_3")
	)
	(segment
		(start 69.0647 111.71063)
		(end 69.0647 106.79549)
		(width 0.2032)
		(layer "B.Cu")
		(net "NetD16_3")
	)
	(segment
		(start 93.40305 86.143)
		(end 93.8841 86.143)
		(width 0.2032)
		(layer "B.Cu")
		(net "NetD16_3")
	)
	(segment
		(start 94.8147 89.9088)
		(end 94.8147 87.0736)
		(width 0.2032)
		(layer "B.Cu")
		(net "NetD16_3")
	)
	(segment
		(start 90.1687 94.5548)
		(end 94.8147 89.9088)
		(width 0.2032)
		(layer "B.Cu")
		(net "NetD16_3")
	)
	(segment
		(start 57.16498 115.32732)
		(end 58.06498 115.32732)
		(width 0.2032)
		(layer "F.Cu")
		(net "NetD16_2")
	)
	(segment
		(start 91.7011 85.6162)
		(end 91.7211 85.5962)
		(width 0.2032)
		(layer "F.Cu")
		(net "NetD16_2")
	)
	(segment
		(start 57.1261 115.3662)
		(end 57.16498 115.32732)
		(width 0.2032)
		(layer "F.Cu")
		(net "NetD16_2")
	)
	(segment
		(start 92.8561 85.5962)
		(end 92.8761 85.5762)
		(width 0.2032)
		(layer "F.Cu")
		(net "NetD16_2")
	)
	(segment
		(start 58.06498 115.32732)
		(end 58.1261 115.2662)
		(width 0.2032)
		(layer "F.Cu")
		(net "NetD16_2")
	)
	(segment
		(start 91.7211 85.5962)
		(end 92.8561 85.5962)
		(width 0.2032)
		(layer "F.Cu")
		(net "NetD16_2")
	)
	(via
		(at 57.1261 115.3662)
		(size 0.4064)
		(drill 0.2032)
		(layers "F.Cu" "B.Cu")
		(tenting
			(front yes)
			(back yes)
		)
		(net "NetD16_2")
	)
	(via
		(at 92.8761 85.5762)
		(size 0.4064)
		(drill 0.2032)
		(layers "F.Cu" "B.Cu")
		(tenting
			(front yes)
			(back yes)
		)
		(net "NetD16_2")
	)
	(segment
		(start 81.44216 94.885)
		(end 90.30547 94.885)
		(width 0.2032)
		(layer "B.Cu")
		(net "NetD16_2")
	)
	(segment
		(start 95.1449 90.04557)
		(end 95.1449 86.93682)
		(width 0.2032)
		(layer "B.Cu")
		(net "NetD16_2")
	)
	(segment
		(start 69.3949 106.93226)
		(end 81.44216 94.885)
		(width 0.2032)
		(layer "B.Cu")
		(net "NetD16_2")
	)
	(segment
		(start 65.8761 115.3662)
		(end 69.3949 111.8474)
		(width 0.2032)
		(layer "B.Cu")
		(net "NetD16_2")
	)
	(segment
		(start 93.78428 85.5762)
		(end 95.1449 86.93682)
		(width 0.2032)
		(layer "B.Cu")
		(net "NetD16_2")
	)
	(segment
		(start 90.30547 94.885)
		(end 95.1449 90.04557)
		(width 0.2032)
		(layer "B.Cu")
		(net "NetD16_2")
	)
	(segment
		(start 69.3949 111.8474)
		(end 69.3949 106.93226)
		(width 0.2032)
		(layer "B.Cu")
		(net "NetD16_2")
	)
	(segment
		(start 92.8761 85.5762)
		(end 93.78428 85.5762)
		(width 0.2032)
		(layer "B.Cu")
		(net "NetD16_2")
	)
	(segment
		(start 57.1261 115.3662)
		(end 65.8761 115.3662)
		(width 0.2032)
		(layer "B.Cu")
		(net "NetD16_2")
	)
	(segment
		(start 57.1261 100.1162)
		(end 57.16498 100.07732)
		(width 0.2032)
		(layer "F.Cu")
		(net "NetD15_4")
	)
	(segment
		(start 92.8561 88.6362)
		(end 92.8761 88.6562)
		(width 0.2032)
		(layer "F.Cu")
		(net "NetD15_4")
	)
	(segment
		(start 57.16498 100.07732)
		(end 58.38998 100.07732)
		(width 0.2032)
		(layer "F.Cu")
		(net "NetD15_4")
	)
	(segment
		(start 58.38998 100.07732)
		(end 58.4511 100.0162)
		(width 0.2032)
		(layer "F.Cu")
		(net "NetD15_4")
	)
	(segment
		(start 91.7211 88.6362)
		(end 92.8561 88.6362)
		(width 0.2032)
		(layer "F.Cu")
		(net "NetD15_4")
	)
	(segment
		(start 91.7011 88.6162)
		(end 91.7211 88.6362)
		(width 0.2032)
		(layer "F.Cu")
		(net "NetD15_4")
	)
	(via
		(at 57.1261 100.1162)
		(size 0.4064)
		(drill 0.2032)
		(layers "F.Cu" "B.Cu")
		(tenting
			(front yes)
			(back yes)
		)
		(net "NetD15_4")
	)
	(via
		(at 92.8761 88.6562)
		(size 0.4064)
		(drill 0.2032)
		(layers "F.Cu" "B.Cu")
		(tenting
			(front yes)
			(back yes)
		)
		(net "NetD15_4")
	)
	(segment
		(start 80.7583 93.234)
		(end 89.62161 93.234)
		(width 0.2032)
		(layer "B.Cu")
		(net "NetD15_4")
	)
	(segment
		(start 89.62161 93.234)
		(end 92.8761 89.97952)
		(width 0.2032)
		(layer "B.Cu")
		(net "NetD15_4")
	)
	(segment
		(start 57.1261 100.1162)
		(end 73.8761 100.1162)
		(width 0.2032)
		(layer "B.Cu")
		(net "NetD15_4")
	)
	(segment
		(start 92.8761 89.97952)
		(end 92.8761 88.6562)
		(width 0.2032)
		(layer "B.Cu")
		(net "NetD15_4")
	)
	(segment
		(start 73.8761 100.1162)
		(end 80.7583 93.234)
		(width 0.2032)
		(layer "B.Cu")
		(net "NetD15_4")
	)
	(segment
		(start 57.1261 101.1162)
		(end 57.16498 101.07732)
		(width 0.2032)
		(layer "F.Cu")
		(net "NetD15_3")
	)
	(segment
		(start 91.7011 88.1162)
		(end 92.63383 88.1162)
		(width 0.2032)
		(layer "F.Cu")
		(net "NetD15_3")
	)
	(segment
		(start 92.66568 88.14805)
		(end 93.3761 88.14805)
		(width 0.2032)
		(layer "F.Cu")
		(net "NetD15_3")
	)
	(segment
		(start 57.16498 101.07732)
		(end 58.01498 101.07732)
		(width 0.2032)
		(layer "F.Cu")
		(net "NetD15_3")
	)
	(segment
		(start 58.01498 101.07732)
		(end 58.1261 100.9662)
		(width 0.2032)
		(layer "F.Cu")
		(net "NetD15_3")
	)
	(segment
		(start 92.63383 88.1162)
		(end 92.66568 88.14805)
		(width 0.2032)
		(layer "F.Cu")
		(net "NetD15_3")
	)
	(via
		(at 57.1261 101.1162)
		(size 0.4064)
		(drill 0.2032)
		(layers "F.Cu" "B.Cu")
		(tenting
			(front yes)
			(back yes)
		)
		(net "NetD15_3")
	)
	(via
		(at 93.3761 88.14805)
		(size 0.4064)
		(drill 0.2032)
		(layers "F.Cu" "B.Cu")
		(tenting
			(front yes)
			(back yes)
		)
		(net "NetD15_3")
	)
	(segment
		(start 57.1261 101.1162)
		(end 73.34307 101.1162)
		(width 0.2032)
		(layer "B.Cu")
		(net "NetD15_3")
	)
	(segment
		(start 93.3761 88.14805)
		(end 93.8241 88.59605)
		(width 0.2032)
		(layer "B.Cu")
		(net "NetD15_3")
	)
	(segment
		(start 93.8241 89.49849)
		(end 93.8241 88.59605)
		(width 0.2032)
		(layer "B.Cu")
		(net "NetD15_3")
	)
	(segment
		(start 80.89507 93.5642)
		(end 89.75839 93.5642)
		(width 0.2032)
		(layer "B.Cu")
		(net "NetD15_3")
	)
	(segment
		(start 73.34307 101.1162)
		(end 80.89507 93.5642)
		(width 0.2032)
		(layer "B.Cu")
		(net "NetD15_3")
	)
	(segment
		(start 89.75839 93.5642)
		(end 93.8241 89.49849)
		(width 0.2032)
		(layer "B.Cu")
		(net "NetD15_3")
	)
	(segment
		(start 91.71303 87.62812)
		(end 92.86418 87.62812)
		(width 0.2032)
		(layer "F.Cu")
		(net "NetD15_2")
	)
	(segment
		(start 91.7011 87.6162)
		(end 91.71303 87.62812)
		(width 0.2032)
		(layer "F.Cu")
		(net "NetD15_2")
	)
	(segment
		(start 57.1261 101.8662)
		(end 58.1261 101.8662)
		(width 0.2032)
		(layer "F.Cu")
		(net "NetD15_2")
	)
	(segment
		(start 92.86418 87.62812)
		(end 92.8761 87.64005)
		(width 0.2032)
		(layer "F.Cu")
		(net "NetD15_2")
	)
	(via
		(at 57.1261 101.8662)
		(size 0.4064)
		(drill 0.2032)
		(layers "F.Cu" "B.Cu")
		(tenting
			(front yes)
			(back yes)
		)
		(net "NetD15_2")
	)
	(via
		(at 92.8761 87.64005)
		(size 0.4064)
		(drill 0.2032)
		(layers "F.Cu" "B.Cu")
		(tenting
			(front yes)
			(back yes)
		)
		(net "NetD15_2")
	)
	(segment
		(start 93.64995 87.64005)
		(end 94.1543 88.1444)
		(width 0.2032)
		(layer "B.Cu")
		(net "NetD15_2")
	)
	(segment
		(start 57.1261 101.8662)
		(end 73.06004 101.8662)
		(width 0.2032)
		(layer "B.Cu")
		(net "NetD15_2")
	)
	(segment
		(start 94.1543 89.63526)
		(end 94.1543 88.1444)
		(width 0.2032)
		(layer "B.Cu")
		(net "NetD15_2")
	)
	(segment
		(start 81.03184 93.8944)
		(end 89.89516 93.8944)
		(width 0.2032)
		(layer "B.Cu")
		(net "NetD15_2")
	)
	(segment
		(start 73.06004 101.8662)
		(end 81.03184 93.8944)
		(width 0.2032)
		(layer "B.Cu")
		(net "NetD15_2")
	)
	(segment
		(start 89.89516 93.8944)
		(end 94.1543 89.63526)
		(width 0.2032)
		(layer "B.Cu")
		(net "NetD15_2")
	)
	(segment
		(start 92.8761 87.64005)
		(end 93.64995 87.64005)
		(width 0.2032)
		(layer "B.Cu")
		(net "NetD15_2")
	)
	(segment
		(start 57.16498 81.15508)
		(end 58.33998 81.15508)
		(width 0.2032)
		(layer "F.Cu")
		(net "NetD14_4")
	)
	(segment
		(start 89.8881 90.6924)
		(end 89.9001 90.7044)
		(width 0.2032)
		(layer "F.Cu")
		(net "NetD14_4")
	)
	(segment
		(start 57.1261 81.1162)
		(end 57.16498 81.15508)
		(width 0.2032)
		(layer "F.Cu")
		(net "NetD14_4")
	)
	(segment
		(start 89.8761 89.4412)
		(end 89.8881 89.4532)
		(width 0.2032)
		(layer "F.Cu")
		(net "NetD14_4")
	)
	(segment
		(start 89.8881 90.6924)
		(end 89.8881 89.4532)
		(width 0.2032)
		(layer "F.Cu")
		(net "NetD14_4")
	)
	(segment
		(start 58.33998 81.15508)
		(end 58.4511 81.2662)
		(width 0.2032)
		(layer "F.Cu")
		(net "NetD14_4")
	)
	(via
		(at 57.1261 81.1162)
		(size 0.4064)
		(drill 0.2032)
		(layers "F.Cu" "B.Cu")
		(tenting
			(front yes)
			(back yes)
		)
		(net "NetD14_4")
	)
	(via
		(at 89.9001 90.7044)
		(size 0.4064)
		(drill 0.2032)
		(layers "F.Cu" "B.Cu")
		(tenting
			(front yes)
			(back yes)
		)
		(net "NetD14_4")
	)
	(segment
		(start 89.9001 91.5546)
		(end 89.9001 90.7044)
		(width 0.2032)
		(layer "B.Cu")
		(net "NetD14_4")
	)
	(segment
		(start 83.18725 92.2434)
		(end 89.2113 92.2434)
		(width 0.2032)
		(layer "B.Cu")
		(net "NetD14_4")
	)
	(segment
		(start 57.1261 81.1162)
		(end 72.06004 81.1162)
		(width 0.2032)
		(layer "B.Cu")
		(net "NetD14_4")
	)
	(segment
		(start 72.06004 81.1162)
		(end 83.18725 92.2434)
		(width 0.2032)
		(layer "B.Cu")
		(net "NetD14_4")
	)
	(segment
		(start 89.2113 92.2434)
		(end 89.9001 91.5546)
		(width 0.2032)
		(layer "B.Cu")
		(net "NetD14_4")
	)
	(segment
		(start 58.06498 82.15508)
		(end 58.1261 82.2162)
		(width 0.2032)
		(layer "F.Cu")
		(net "NetD14_3")
	)
	(segment
		(start 57.1261 82.1162)
		(end 57.16498 82.15508)
		(width 0.2032)
		(layer "F.Cu")
		(net "NetD14_3")
	)
	(segment
		(start 90.3761 90.37378)
		(end 90.4081 90.40578)
		(width 0.2032)
		(layer "F.Cu")
		(net "NetD14_3")
	)
	(segment
		(start 57.16498 82.15508)
		(end 58.06498 82.15508)
		(width 0.2032)
		(layer "F.Cu")
		(net "NetD14_3")
	)
	(segment
		(start 90.3761 90.37378)
		(end 90.3761 89.4412)
		(width 0.2032)
		(layer "F.Cu")
		(net "NetD14_3")
	)
	(segment
		(start 90.4081 91.1162)
		(end 90.4081 90.40578)
		(width 0.2032)
		(layer "F.Cu")
		(net "NetD14_3")
	)
	(via
		(at 90.4081 91.1162)
		(size 0.4064)
		(drill 0.2032)
		(layers "F.Cu" "B.Cu")
		(tenting
			(front yes)
			(back yes)
		)
		(net "NetD14_3")
	)
	(via
		(at 57.1261 82.1162)
		(size 0.4064)
		(drill 0.2032)
		(layers "F.Cu" "B.Cu")
		(tenting
			(front yes)
			(back yes)
		)
		(net "NetD14_3")
	)
	(segment
		(start 90.36922 91.15508)
		(end 90.4081 91.1162)
		(width 0.2032)
		(layer "B.Cu")
		(net "NetD14_3")
	)
	(segment
		(start 57.1261 82.1162)
		(end 72.59307 82.1162)
		(width 0.2032)
		(layer "B.Cu")
		(net "NetD14_3")
	)
	(segment
		(start 90.36922 91.55245)
		(end 90.36922 91.15508)
		(width 0.2032)
		(layer "B.Cu")
		(net "NetD14_3")
	)
	(segment
		(start 89.34807 92.5736)
		(end 90.36922 91.55245)
		(width 0.2032)
		(layer "B.Cu")
		(net "NetD14_3")
	)
	(segment
		(start 83.05047 92.5736)
		(end 89.34807 92.5736)
		(width 0.2032)
		(layer "B.Cu")
		(net "NetD14_3")
	)
	(segment
		(start 72.59307 82.1162)
		(end 83.05047 92.5736)
		(width 0.2032)
		(layer "B.Cu")
		(net "NetD14_3")
	)
	(segment
		(start 90.8961 90.6844)
		(end 90.9161 90.7044)
		(width 0.2032)
		(layer "F.Cu")
		(net "NetD14_2")
	)
	(segment
		(start 57.1261 83.1162)
		(end 58.1261 83.1162)
		(width 0.2032)
		(layer "F.Cu")
		(net "NetD14_2")
	)
	(segment
		(start 90.8961 90.6844)
		(end 90.8961 89.4612)
		(width 0.2032)
		(layer "F.Cu")
		(net "NetD14_2")
	)
	(segment
		(start 90.8761 89.4412)
		(end 90.8961 89.4612)
		(width 0.2032)
		(layer "F.Cu")
		(net "NetD14_2")
	)
	(via
		(at 57.1261 83.1162)
		(size 0.4064)
		(drill 0.2032)
		(layers "F.Cu" "B.Cu")
		(tenting
			(front yes)
			(back yes)
		)
		(net "NetD14_2")
	)
	(via
		(at 90.9161 90.7044)
		(size 0.4064)
		(drill 0.2032)
		(layers "F.Cu" "B.Cu")
		(tenting
			(front yes)
			(back yes)
		)
		(net "NetD14_2")
	)
	(segment
		(start 82.9137 92.9038)
		(end 89.48484 92.9038)
		(width 0.2032)
		(layer "B.Cu")
		(net "NetD14_2")
	)
	(segment
		(start 89.48484 92.9038)
		(end 90.9161 91.47254)
		(width 0.2032)
		(layer "B.Cu")
		(net "NetD14_2")
	)
	(segment
		(start 57.1261 83.1162)
		(end 73.1261 83.1162)
		(width 0.2032)
		(layer "B.Cu")
		(net "NetD14_2")
	)
	(segment
		(start 90.9161 91.47254)
		(end 90.9161 90.7044)
		(width 0.2032)
		(layer "B.Cu")
		(net "NetD14_2")
	)
	(segment
		(start 73.1261 83.1162)
		(end 82.9137 92.9038)
		(width 0.2032)
		(layer "B.Cu")
		(net "NetD14_2")
	)
	(segment
		(start 58.38998 70.32732)
		(end 58.4511 70.2662)
		(width 0.2032)
		(layer "F.Cu")
		(net "NetD13_4")
	)
	(segment
		(start 57.16498 70.32732)
		(end 58.38998 70.32732)
		(width 0.2032)
		(layer "F.Cu")
		(net "NetD13_4")
	)
	(segment
		(start 57.1261 70.3662)
		(end 57.16498 70.32732)
		(width 0.2032)
		(layer "F.Cu")
		(net "NetD13_4")
	)
	(segment
		(start 87.8721 90.7004)
		(end 87.8721 89.4452)
		(width 0.2032)
		(layer "F.Cu")
		(net "NetD13_4")
	)
	(segment
		(start 87.8721 89.4452)
		(end 87.8761 89.4412)
		(width 0.2032)
		(layer "F.Cu")
		(net "NetD13_4")
	)
	(segment
		(start 87.8681 90.7044)
		(end 87.8721 90.7004)
		(width 0.2032)
		(layer "F.Cu")
		(net "NetD13_4")
	)
	(via
		(at 57.1261 70.3662)
		(size 0.4064)
		(drill 0.2032)
		(layers "F.Cu" "B.Cu")
		(tenting
			(front yes)
			(back yes)
		)
		(net "NetD13_4")
	)
	(via
		(at 87.8681 90.7044)
		(size 0.4064)
		(drill 0.2032)
		(layers "F.Cu" "B.Cu")
		(tenting
			(front yes)
			(back yes)
		)
		(net "NetD13_4")
	)
	(segment
		(start 57.1261 70.3662)
		(end 62.71096 70.3662)
		(width 0.2032)
		(layer "B.Cu")
		(net "NetD13_4")
	)
	(segment
		(start 62.71096 70.3662)
		(end 83.59756 91.2528)
		(width 0.2032)
		(layer "B.Cu")
		(net "NetD13_4")
	)
	(segment
		(start 87.3197 91.2528)
		(end 87.8681 90.7044)
		(width 0.2032)
		(layer "B.Cu")
		(net "NetD13_4")
	)
	(segment
		(start 83.59756 91.2528)
		(end 87.3197 91.2528)
		(width 0.2032)
		(layer "B.Cu")
		(net "NetD13_4")
	)
	(segment
		(start 57.16498 71.15508)
		(end 58.06498 71.15508)
		(width 0.2032)
		(layer "F.Cu")
		(net "NetD13_3")
	)
	(segment
		(start 88.3761 91.1162)
		(end 88.3761 89.4412)
		(width 0.2032)
		(layer "F.Cu")
		(net "NetD13_3")
	)
	(segment
		(start 58.06498 71.15508)
		(end 58.1261 71.2162)
		(width 0.2032)
		(layer "F.Cu")
		(net "NetD13_3")
	)
	(segment
		(start 57.1261 71.1162)
		(end 57.16498 71.15508)
		(width 0.2032)
		(layer "F.Cu")
		(net "NetD13_3")
	)
	(via
		(at 88.3761 91.1162)
		(size 0.4064)
		(drill 0.2032)
		(layers "F.Cu" "B.Cu")
		(tenting
			(front yes)
			(back yes)
		)
		(net "NetD13_3")
	)
	(via
		(at 57.1261 71.1162)
		(size 0.4064)
		(drill 0.2032)
		(layers "F.Cu" "B.Cu")
		(tenting
			(front yes)
			(back yes)
		)
		(net "NetD13_3")
	)
	(segment
		(start 83.46079 91.583)
		(end 87.9093 91.583)
		(width 0.2032)
		(layer "B.Cu")
		(net "NetD13_3")
	)
	(segment
		(start 57.1261 71.1162)
		(end 62.99399 71.1162)
		(width 0.2032)
		(layer "B.Cu")
		(net "NetD13_3")
	)
	(segment
		(start 62.99399 71.1162)
		(end 83.46079 91.583)
		(width 0.2032)
		(layer "B.Cu")
		(net "NetD13_3")
	)
	(segment
		(start 87.9093 91.583)
		(end 88.3761 91.1162)
		(width 0.2032)
		(layer "B.Cu")
		(net "NetD13_3")
	)
	(segment
		(start 88.8801 90.7004)
		(end 88.8801 89.4452)
		(width 0.2032)
		(layer "F.Cu")
		(net "NetD13_2")
	)
	(segment
		(start 57.1261 72.1162)
		(end 58.1261 72.1162)
		(width 0.2032)
		(layer "F.Cu")
		(net "NetD13_2")
	)
	(segment
		(start 88.8761 89.4412)
		(end 88.8801 89.4452)
		(width 0.2032)
		(layer "F.Cu")
		(net "NetD13_2")
	)
	(segment
		(start 88.8801 90.7004)
		(end 88.8841 90.7044)
		(width 0.2032)
		(layer "F.Cu")
		(net "NetD13_2")
	)
	(via
		(at 88.8841 90.7044)
		(size 0.4064)
		(drill 0.2032)
		(layers "F.Cu" "B.Cu")
		(tenting
			(front yes)
			(back yes)
		)
		(net "NetD13_2")
	)
	(via
		(at 57.1261 72.1162)
		(size 0.4064)
		(drill 0.2032)
		(layers "F.Cu" "B.Cu")
		(tenting
			(front yes)
			(back yes)
		)
		(net "NetD13_2")
	)
	(segment
		(start 88.8841 91.32662)
		(end 88.8841 90.7044)
		(width 0.2032)
		(layer "B.Cu")
		(net "NetD13_2")
	)
	(segment
		(start 88.29752 91.9132)
		(end 88.8841 91.32662)
		(width 0.2032)
		(layer "B.Cu")
		(net "NetD13_2")
	)
	(segment
		(start 83.32402 91.9132)
		(end 88.29752 91.9132)
		(width 0.2032)
		(layer "B.Cu")
		(net "NetD13_2")
	)
	(segment
		(start 57.1261 72.1162)
		(end 63.52702 72.1162)
		(width 0.2032)
		(layer "B.Cu")
		(net "NetD13_2")
	)
	(segment
		(start 63.52702 72.1162)
		(end 83.32402 91.9132)
		(width 0.2032)
		(layer "B.Cu")
		(net "NetD13_2")
	)
	(segment
		(start 146.28233 115.31242)
		(end 147.69091 115.31242)
		(width 0.2032)
		(layer "F.Cu")
		(net "EXT_GPIO_10")
	)
	(segment
		(start 145.3841 115.3662)
		(end 146.22856 115.3662)
		(width 0.2032)
		(layer "F.Cu")
		(net "EXT_GPIO_10")
	)
	(segment
		(start 146.22856 115.3662)
		(end 146.28233 115.31242)
		(width 0.2032)
		(layer "F.Cu")
		(net "EXT_GPIO_10")
	)
	(via
		(at 145.3841 115.3662)
		(size 0.4064)
		(drill 0.2032)
		(layers "F.Cu" "B.Cu")
		(tenting
			(front yes)
			(back yes)
		)
		(net "EXT_GPIO_10")
	)
	(segment
		(start 205.3667 112.50772)
		(end 205.3667 58.88982)
		(width 0.2032)
		(layer "B.Cu")
		(net "EXT_GPIO_10")
	)
	(segment
		(start 205.1261 58.64923)
		(end 205.3667 58.88982)
		(width 0.2032)
		(layer "B.Cu")
		(net "EXT_GPIO_10")
	)
	(segment
		(start 146.77702 115.3662)
		(end 148.94682 117.536)
		(width 0.2032)
		(layer "B.Cu")
		(net "EXT_GPIO_10")
	)
	(segment
		(start 148.94682 117.536)
		(end 200.33842 117.536)
		(width 0.2032)
		(layer "B.Cu")
		(net "EXT_GPIO_10")
	)
	(segment
		(start 205.1261 58.64923)
		(end 205.1261 53.59766)
		(width 0.2032)
		(layer "B.Cu")
		(net "EXT_GPIO_10")
	)
	(segment
		(start 200.33842 117.536)
		(end 205.3667 112.50772)
		(width 0.2032)
		(layer "B.Cu")
		(net "EXT_GPIO_10")
	)
	(segment
		(start 145.3841 115.3662)
		(end 146.77702 115.3662)
		(width 0.2032)
		(layer "B.Cu")
		(net "EXT_GPIO_10")
	)
	(segment
		(start 146.53639 115.8123)
		(end 147.69091 115.8123)
		(width 0.2032)
		(layer "F.Cu")
		(net "EXT_GPIO_9")
	)
	(segment
		(start 145.8761 115.8742)
		(end 146.47449 115.8742)
		(width 0.2032)
		(layer "F.Cu")
		(net "EXT_GPIO_9")
	)
	(segment
		(start 146.47449 115.8742)
		(end 146.53639 115.8123)
		(width 0.2032)
		(layer "F.Cu")
		(net "EXT_GPIO_9")
	)
	(via
		(at 145.8761 115.8742)
		(size 0.4064)
		(drill 0.2032)
		(layers "F.Cu" "B.Cu")
		(tenting
			(front yes)
			(back yes)
		)
		(net "EXT_GPIO_9")
	)
	(segment
		(start 205.6969 59.5454)
		(end 207.6661 57.5762)
		(width 0.2032)
		(layer "B.Cu")
		(net "EXT_GPIO_9")
	)
	(segment
		(start 148.81005 117.8662)
		(end 200.47519 117.8662)
		(width 0.2032)
		(layer "B.Cu")
		(net "EXT_GPIO_9")
	)
	(segment
		(start 205.6969 112.64449)
		(end 205.6969 59.5454)
		(width 0.2032)
		(layer "B.Cu")
		(net "EXT_GPIO_9")
	)
	(segment
		(start 146.81805 115.8742)
		(end 148.81005 117.8662)
		(width 0.2032)
		(layer "B.Cu")
		(net "EXT_GPIO_9")
	)
	(segment
		(start 145.8761 115.8742)
		(end 146.81805 115.8742)
		(width 0.2032)
		(layer "B.Cu")
		(net "EXT_GPIO_9")
	)
	(segment
		(start 200.47519 117.8662)
		(end 205.6969 112.64449)
		(width 0.2032)
		(layer "B.Cu")
		(net "EXT_GPIO_9")
	)
	(segment
		(start 207.6661 57.5762)
		(end 207.6661 54.1162)
		(width 0.2032)
		(layer "B.Cu")
		(net "EXT_GPIO_9")
	)
	(segment
		(start 145.3921 116.3822)
		(end 146.22056 116.3822)
		(width 0.2032)
		(layer "F.Cu")
		(net "EXT_GPIO_8")
	)
	(segment
		(start 145.3841 116.3742)
		(end 145.3921 116.3822)
		(width 0.2032)
		(layer "F.Cu")
		(net "EXT_GPIO_8")
	)
	(segment
		(start 146.22056 116.3822)
		(end 146.29033 116.31242)
		(width 0.2032)
		(layer "F.Cu")
		(net "EXT_GPIO_8")
	)
	(segment
		(start 146.29033 116.31242)
		(end 147.69091 116.31242)
		(width 0.2032)
		(layer "F.Cu")
		(net "EXT_GPIO_8")
	)
	(via
		(at 145.3841 116.3742)
		(size 0.4064)
		(drill 0.2032)
		(layers "F.Cu" "B.Cu")
		(tenting
			(front yes)
			(back yes)
		)
		(net "EXT_GPIO_8")
	)
	(segment
		(start 145.3841 116.3742)
		(end 145.3921 116.3822)
		(width 0.2032)
		(layer "B.Cu")
		(net "EXT_GPIO_8")
	)
	(segment
		(start 206.0271 59.68217)
		(end 210.2061 55.50317)
		(width 0.2032)
		(layer "B.Cu")
		(net "EXT_GPIO_8")
	)
	(segment
		(start 200.61196 118.1964)
		(end 206.0271 112.78126)
		(width 0.2032)
		(layer "B.Cu")
		(net "EXT_GPIO_8")
	)
	(segment
		(start 206.0271 112.78126)
		(end 206.0271 59.68217)
		(width 0.2032)
		(layer "B.Cu")
		(net "EXT_GPIO_8")
	)
	(segment
		(start 210.2061 55.50317)
		(end 210.2061 54.1162)
		(width 0.2032)
		(layer "B.Cu")
		(net "EXT_GPIO_8")
	)
	(segment
		(start 148.67327 118.1964)
		(end 200.61196 118.1964)
		(width 0.2032)
		(layer "B.Cu")
		(net "EXT_GPIO_8")
	)
	(segment
		(start 145.3921 116.3822)
		(end 146.85907 116.3822)
		(width 0.2032)
		(layer "B.Cu")
		(net "EXT_GPIO_8")
	)
	(segment
		(start 146.85907 116.3822)
		(end 148.67327 118.1964)
		(width 0.2032)
		(layer "B.Cu")
		(net "EXT_GPIO_8")
	)
	(segment
		(start 145.93108 116.8902)
		(end 146.00899 116.81229)
		(width 0.2032)
		(layer "F.Cu")
		(net "EXT_GPIO_7")
	)
	(segment
		(start 146.00899 116.81229)
		(end 147.69091 116.81229)
		(width 0.2032)
		(layer "F.Cu")
		(net "EXT_GPIO_7")
	)
	(segment
		(start 145.8761 116.8902)
		(end 145.93108 116.8902)
		(width 0.2032)
		(layer "F.Cu")
		(net "EXT_GPIO_7")
	)
	(via
		(at 145.8761 116.8902)
		(size 0.4064)
		(drill 0.2032)
		(layers "F.Cu" "B.Cu")
		(tenting
			(front yes)
			(back yes)
		)
		(net "EXT_GPIO_7")
	)
	(segment
		(start 206.3573 113.885)
		(end 206.3573 60.505)
		(width 0.2032)
		(layer "B.Cu")
		(net "EXT_GPIO_7")
	)
	(segment
		(start 148.5365 118.5266)
		(end 201.7157 118.5266)
		(width 0.2032)
		(layer "B.Cu")
		(net "EXT_GPIO_7")
	)
	(segment
		(start 145.8761 116.8902)
		(end 146.9001 116.8902)
		(width 0.2032)
		(layer "B.Cu")
		(net "EXT_GPIO_7")
	)
	(segment
		(start 206.3573 60.505)
		(end 212.7461 54.1162)
		(width 0.2032)
		(layer "B.Cu")
		(net "EXT_GPIO_7")
	)
	(segment
		(start 201.7157 118.5266)
		(end 206.3573 113.885)
		(width 0.2032)
		(layer "B.Cu")
		(net "EXT_GPIO_7")
	)
	(segment
		(start 146.9001 116.8902)
		(end 148.5365 118.5266)
		(width 0.2032)
		(layer "B.Cu")
		(net "EXT_GPIO_7")
	)
	(segment
		(start 146.2285 112.8662)
		(end 146.28239 112.8123)
		(width 0.2032)
		(layer "F.Cu")
		(net "EXT_GPIO_4")
	)
	(segment
		(start 145.3761 112.8662)
		(end 146.2285 112.8662)
		(width 0.2032)
		(layer "F.Cu")
		(net "EXT_GPIO_4")
	)
	(segment
		(start 146.28239 112.8123)
		(end 147.69091 112.8123)
		(width 0.2032)
		(layer "F.Cu")
		(net "EXT_GPIO_4")
	)
	(via
		(at 145.3761 112.8662)
		(size 0.4064)
		(drill 0.2032)
		(layers "F.Cu" "B.Cu")
		(tenting
			(front yes)
			(back yes)
		)
		(net "EXT_GPIO_4")
	)
	(segment
		(start 203.4261 113.0474)
		(end 203.4261 58.4162)
		(width 0.2032)
		(layer "B.Cu")
		(net "EXT_GPIO_4")
	)
	(segment
		(start 201.3761 56.3662)
		(end 201.3761 53.6162)
		(width 0.2032)
		(layer "B.Cu")
		(net "EXT_GPIO_4")
	)
	(segment
		(start 201.3761 53.6162)
		(end 202.1261 52.8662)
		(width 0.2032)
		(layer "B.Cu")
		(net "EXT_GPIO_4")
	)
	(segment
		(start 202.1261 52.8662)
		(end 203.8361 52.8662)
		(width 0.2032)
		(layer "B.Cu")
		(net "EXT_GPIO_4")
	)
	(segment
		(start 201.3761 56.3662)
		(end 203.4261 58.4162)
		(width 0.2032)
		(layer "B.Cu")
		(net "EXT_GPIO_4")
	)
	(segment
		(start 171.0835 115.5548)
		(end 200.9187 115.5548)
		(width 0.2032)
		(layer "B.Cu")
		(net "EXT_GPIO_4")
	)
	(segment
		(start 203.8361 52.8662)
		(end 205.1261 51.5762)
		(width 0.2032)
		(layer "B.Cu")
		(net "EXT_GPIO_4")
	)
	(segment
		(start 200.9187 115.5548)
		(end 203.4261 113.0474)
		(width 0.2032)
		(layer "B.Cu")
		(net "EXT_GPIO_4")
	)
	(segment
		(start 145.3761 112.8662)
		(end 168.3949 112.8662)
		(width 0.2032)
		(layer "B.Cu")
		(net "EXT_GPIO_4")
	)
	(segment
		(start 168.3949 112.8662)
		(end 171.0835 115.5548)
		(width 0.2032)
		(layer "B.Cu")
		(net "EXT_GPIO_4")
	)
	(segment
		(start 146.47456 113.3742)
		(end 146.53633 113.31243)
		(width 0.2032)
		(layer "F.Cu")
		(net "EXT_GPIO_3")
	)
	(segment
		(start 145.8761 113.3742)
		(end 146.47456 113.3742)
		(width 0.2032)
		(layer "F.Cu")
		(net "EXT_GPIO_3")
	)
	(segment
		(start 146.53633 113.31243)
		(end 147.69091 113.31243)
		(width 0.2032)
		(layer "F.Cu")
		(net "EXT_GPIO_3")
	)
	(via
		(at 145.8761 113.3742)
		(size 0.4064)
		(drill 0.2032)
		(layers "F.Cu" "B.Cu")
		(tenting
			(front yes)
			(back yes)
		)
		(net "EXT_GPIO_3")
	)
	(segment
		(start 204.45653 52.7312)
		(end 206.8761 52.7312)
		(width 0.2032)
		(layer "B.Cu")
		(net "EXT_GPIO_3")
	)
	(segment
		(start 207.1306 52.46261)
		(end 207.6661 51.92711)
		(width 0.2032)
		(layer "B.Cu")
		(net "EXT_GPIO_3")
	)
	(segment
		(start 204.7063 112.23417)
		(end 204.7063 59.1964)
		(width 0.2032)
		(layer "B.Cu")
		(net "EXT_GPIO_3")
	)
	(segment
		(start 170.94673 115.885)
		(end 201.05547 115.885)
		(width 0.2032)
		(layer "B.Cu")
		(net "EXT_GPIO_3")
	)
	(segment
		(start 203.6409 58.131)
		(end 204.7063 59.1964)
		(width 0.2032)
		(layer "B.Cu")
		(net "EXT_GPIO_3")
	)
	(segment
		(start 201.05547 115.885)
		(end 204.7063 112.23417)
		(width 0.2032)
		(layer "B.Cu")
		(net "EXT_GPIO_3")
	)
	(segment
		(start 168.43593 113.3742)
		(end 170.94673 115.885)
		(width 0.2032)
		(layer "B.Cu")
		(net "EXT_GPIO_3")
	)
	(segment
		(start 203.6409 58.131)
		(end 203.6409 53.54683)
		(width 0.2032)
		(layer "B.Cu")
		(net "EXT_GPIO_3")
	)
	(segment
		(start 203.6409 53.54683)
		(end 204.45653 52.7312)
		(width 0.2032)
		(layer "B.Cu")
		(net "EXT_GPIO_3")
	)
	(segment
		(start 206.8761 52.7312)
		(end 207.1306 52.4767)
		(width 0.2032)
		(layer "B.Cu")
		(net "EXT_GPIO_3")
	)
	(segment
		(start 207.1306 52.4767)
		(end 207.1306 52.46261)
		(width 0.2032)
		(layer "B.Cu")
		(net "EXT_GPIO_3")
	)
	(segment
		(start 145.8761 113.3742)
		(end 168.43593 113.3742)
		(width 0.2032)
		(layer "B.Cu")
		(net "EXT_GPIO_3")
	)
	(segment
		(start 207.6661 51.92711)
		(end 207.6661 51.5762)
		(width 0.2032)
		(layer "B.Cu")
		(net "EXT_GPIO_3")
	)
	(segment
		(start 146.22049 113.8822)
		(end 146.29039 113.8123)
		(width 0.2032)
		(layer "F.Cu")
		(net "EXT_GPIO_2")
	)
	(segment
		(start 146.29039 113.8123)
		(end 147.69091 113.8123)
		(width 0.2032)
		(layer "F.Cu")
		(net "EXT_GPIO_2")
	)
	(segment
		(start 145.3761 113.8662)
		(end 145.3921 113.8822)
		(width 0.2032)
		(layer "F.Cu")
		(net "EXT_GPIO_2")
	)
	(segment
		(start 145.3921 113.8822)
		(end 146.22049 113.8822)
		(width 0.2032)
		(layer "F.Cu")
		(net "EXT_GPIO_2")
	)
	(via
		(at 145.3761 113.8662)
		(size 0.4064)
		(drill 0.2032)
		(layers "F.Cu" "B.Cu")
		(tenting
			(front yes)
			(back yes)
		)
		(net "EXT_GPIO_2")
	)
	(segment
		(start 203.9761 57.9662)
		(end 203.9761 53.6786)
		(width 0.2032)
		(layer "B.Cu")
		(net "EXT_GPIO_2")
	)
	(segment
		(start 209.5713 53.0614)
		(end 210.0017 52.631)
		(width 0.2032)
		(layer "B.Cu")
		(net "EXT_GPIO_2")
	)
	(segment
		(start 170.80996 116.2152)
		(end 201.19224 116.2152)
		(width 0.2032)
		(layer "B.Cu")
		(net "EXT_GPIO_2")
	)
	(segment
		(start 210.0017 51.7806)
		(end 210.2061 51.5762)
		(width 0.2032)
		(layer "B.Cu")
		(net "EXT_GPIO_2")
	)
	(segment
		(start 210.0017 52.631)
		(end 210.0017 51.7806)
		(width 0.2032)
		(layer "B.Cu")
		(net "EXT_GPIO_2")
	)
	(segment
		(start 204.5933 53.0614)
		(end 209.5713 53.0614)
		(width 0.2032)
		(layer "B.Cu")
		(net "EXT_GPIO_2")
	)
	(segment
		(start 203.9761 57.9662)
		(end 205.0365 59.0266)
		(width 0.2032)
		(layer "B.Cu")
		(net "EXT_GPIO_2")
	)
	(segment
		(start 145.3761 113.8662)
		(end 145.3921 113.8822)
		(width 0.2032)
		(layer "B.Cu")
		(net "EXT_GPIO_2")
	)
	(segment
		(start 168.47696 113.8822)
		(end 170.80996 116.2152)
		(width 0.2032)
		(layer "B.Cu")
		(net "EXT_GPIO_2")
	)
	(segment
		(start 201.19224 116.2152)
		(end 205.0365 112.37094)
		(width 0.2032)
		(layer "B.Cu")
		(net "EXT_GPIO_2")
	)
	(segment
		(start 205.0365 112.37094)
		(end 205.0365 59.0266)
		(width 0.2032)
		(layer "B.Cu")
		(net "EXT_GPIO_2")
	)
	(segment
		(start 203.9761 53.6786)
		(end 204.5933 53.0614)
		(width 0.2032)
		(layer "B.Cu")
		(net "EXT_GPIO_2")
	)
	(segment
		(start 145.3921 113.8822)
		(end 168.47696 113.8822)
		(width 0.2032)
		(layer "B.Cu")
		(net "EXT_GPIO_2")
	)
	(segment
		(start 145.8761 114.3902)
		(end 145.93108 114.3902)
		(width 0.2032)
		(layer "F.Cu")
		(net "EXT_GPIO_1")
	)
	(segment
		(start 146.00886 114.31243)
		(end 147.69091 114.31243)
		(width 0.2032)
		(layer "F.Cu")
		(net "EXT_GPIO_1")
	)
	(segment
		(start 145.93108 114.3902)
		(end 146.00886 114.31243)
		(width 0.2032)
		(layer "F.Cu")
		(net "EXT_GPIO_1")
	)
	(via
		(at 145.8761 114.3902)
		(size 0.4064)
		(drill 0.2032)
		(layers "F.Cu" "B.Cu")
		(tenting
			(front yes)
			(back yes)
		)
		(net "EXT_GPIO_1")
	)
	(segment
		(start 146.6261 118.8662)
		(end 202.0761 118.8662)
		(width 0.2032)
		(layer "B.Cu")
		(net "EXT_GPIO_1")
	)
	(segment
		(start 145.3521 114.3902)
		(end 145.8761 114.3902)
		(width 0.2032)
		(layer "B.Cu")
		(net "EXT_GPIO_1")
	)
	(segment
		(start 213.8009 54.55311)
		(end 213.8009 52.631)
		(width 0.2032)
		(layer "B.Cu")
		(net "EXT_GPIO_1")
	)
	(segment
		(start 144.8761 117.1162)
		(end 144.8761 114.8662)
		(width 0.2032)
		(layer "B.Cu")
		(net "EXT_GPIO_1")
	)
	(segment
		(start 144.8761 117.1162)
		(end 146.6261 118.8662)
		(width 0.2032)
		(layer "B.Cu")
		(net "EXT_GPIO_1")
	)
	(segment
		(start 206.6875 91.7162)
		(end 206.6875 86.5162)
		(width 0.2032)
		(layer "B.Cu")
		(net "EXT_GPIO_1")
	)
	(segment
		(start 202.0761 118.8662)
		(end 206.6875 114.2548)
		(width 0.2032)
		(layer "B.Cu")
		(net "EXT_GPIO_1")
	)
	(segment
		(start 206.6875 61.66651)
		(end 213.8009 54.55311)
		(width 0.2032)
		(layer "B.Cu")
		(net "EXT_GPIO_1")
	)
	(segment
		(start 206.6875 114.2548)
		(end 206.6875 91.7162)
		(width 0.2032)
		(layer "B.Cu")
		(net "EXT_GPIO_1")
	)
	(segment
		(start 212.7461 51.5762)
		(end 213.8009 52.631)
		(width 0.2032)
		(layer "B.Cu")
		(net "EXT_GPIO_1")
	)
	(segment
		(start 206.6875 86.5162)
		(end 206.6875 61.66651)
		(width 0.2032)
		(layer "B.Cu")
		(net "EXT_GPIO_1")
	)
	(segment
		(start 144.8761 114.8662)
		(end 145.3521 114.3902)
		(width 0.2032)
		(layer "B.Cu")
		(net "EXT_GPIO_1")
	)
	(segment
		(start 170.17266 99.53586)
		(end 170.21154 99.57474)
		(width 0.2032)
		(layer "F.Cu")
		(net "ANT4_OUT")
	)
	(segment
		(start 169.32587 98.98917)
		(end 169.87256 99.53586)
		(width 0.2032)
		(layer "F.Cu")
		(net "ANT4_OUT")
	)
	(segment
		(start 169.32587 98.98917)
		(end 169.32587 97.91825)
		(width 0.2032)
		(layer "F.Cu")
		(net "ANT4_OUT")
	)
	(segment
		(start 84.82111 136.4758)
		(end 84.8761 136.4758)
		(width 0.2032)
		(layer "F.Cu")
		(net "ANT4_OUT")
	)
	(segment
		(start 84.71151 136.3662)
		(end 84.82111 136.4758)
		(width 0.2032)
		(layer "F.Cu")
		(net "ANT4_OUT")
	)
	(segment
		(start 169.87256 99.53586)
		(end 170.17266 99.53586)
		(width 0.2032)
		(layer "F.Cu")
		(net "ANT4_OUT")
	)
	(segment
		(start 83.7011 136.3662)
		(end 84.71151 136.3662)
		(width 0.2032)
		(layer "F.Cu")
		(net "ANT4_OUT")
	)
	(via
		(at 84.8761 136.4758)
		(size 0.4064)
		(drill 0.2032)
		(layers "F.Cu" "B.Cu")
		(tenting
			(front yes)
			(back yes)
		)
		(net "ANT4_OUT")
	)
	(via
		(at 170.21154 99.57474)
		(size 0.4064)
		(drill 0.2032)
		(layers "F.Cu" "B.Cu")
		(tenting
			(front yes)
			(back yes)
		)
		(net "ANT4_OUT")
	)
	(segment
		(start 90.54283 103.9825)
		(end 166.62768 103.9825)
		(width 0.2032)
		(layer "In3.Cu")
		(net "ANT4_OUT")
	)
	(segment
		(start 84.8761 136.4758)
		(end 86.8761 134.4758)
		(width 0.2032)
		(layer "In3.Cu")
		(net "ANT4_OUT")
	)
	(segment
		(start 166.62768 103.9825)
		(end 170.21154 100.39864)
		(width 0.2032)
		(layer "In3.Cu")
		(net "ANT4_OUT")
	)
	(segment
		(start 86.8761 134.4758)
		(end 86.8761 107.64923)
		(width 0.2032)
		(layer "In3.Cu")
		(net "ANT4_OUT")
	)
	(segment
		(start 86.8761 107.64923)
		(end 90.54283 103.9825)
		(width 0.2032)
		(layer "In3.Cu")
		(net "ANT4_OUT")
	)
	(segment
		(start 170.21154 100.39864)
		(end 170.21154 99.57474)
		(width 0.2032)
		(layer "In3.Cu")
		(net "ANT4_OUT")
	)
	(segment
		(start 82.8761 137.1162)
		(end 83.0777 136.9146)
		(width 0.2032)
		(layer "F.Cu")
		(net "ANT4_IO_OUT")
	)
	(segment
		(start 83.0777 136.9146)
		(end 83.6527 136.9146)
		(width 0.2032)
		(layer "F.Cu")
		(net "ANT4_IO_OUT")
	)
	(segment
		(start 83.7527 138.50387)
		(end 83.84442 138.59559)
		(width 0.2032)
		(layer "F.Cu")
		(net "ANT4_IO_OUT")
	)
	(segment
		(start 153.65794 112.83436)
		(end 153.65794 112.36778)
		(width 0.2032)
		(layer "F.Cu")
		(net "ANT4_IO_OUT")
	)
	(segment
		(start 153.20324 113.28906)
		(end 153.65794 112.83436)
		(width 0.2032)
		(layer "F.Cu")
		(net "ANT4_IO_OUT")
	)
	(segment
		(start 82.8761 137.8662)
		(end 83.51377 138.50387)
		(width 0.2032)
		(layer "F.Cu")
		(net "ANT4_IO_OUT")
	)
	(segment
		(start 83.51377 138.50387)
		(end 83.7527 138.50387)
		(width 0.2032)
		(layer "F.Cu")
		(net "ANT4_IO_OUT")
	)
	(segment
		(start 151.74069 113.31243)
		(end 151.76406 113.28906)
		(width 0.2032)
		(layer "F.Cu")
		(net "ANT4_IO_OUT")
	)
	(segment
		(start 83.6527 136.9146)
		(end 83.7011 136.8662)
		(width 0.2032)
		(layer "F.Cu")
		(net "ANT4_IO_OUT")
	)
	(segment
		(start 83.84442 138.83452)
		(end 83.84442 138.59559)
		(width 0.2032)
		(layer "F.Cu")
		(net "ANT4_IO_OUT")
	)
	(segment
		(start 84.1261 138.8662)
		(end 85.3761 138.8662)
		(width 0.254)
		(layer "F.Cu")
		(net "ANT4_IO_OUT")
	)
	(segment
		(start 153.65794 112.36778)
		(end 153.69682 112.3289)
		(width 0.2032)
		(layer "F.Cu")
		(net "ANT4_IO_OUT")
	)
	(segment
		(start 82.8761 137.8662)
		(end 82.8761 137.1162)
		(width 0.2032)
		(layer "F.Cu")
		(net "ANT4_IO_OUT")
	)
	(segment
		(start 151.76406 113.28906)
		(end 153.20324 113.28906)
		(width 0.2032)
		(layer "F.Cu")
		(net "ANT4_IO_OUT")
	)
	(via
		(at 85.3761 138.8662)
		(size 0.4064)
		(drill 0.2032)
		(layers "F.Cu" "B.Cu")
		(tenting
			(front yes)
			(back yes)
		)
		(net "ANT4_IO_OUT")
	)
	(via
		(at 153.69682 112.3289)
		(size 0.4064)
		(drill 0.2032)
		(layers "F.Cu" "B.Cu")
		(tenting
			(front yes)
			(back yes)
		)
		(net "ANT4_IO_OUT")
	)
	(segment
		(start 153.69682 112.3289)
		(end 153.71298 112.31274)
		(width 0.254)
		(layer "In3.Cu")
		(net "ANT4_IO_OUT")
	)
	(segment
		(start 92.3761 135.3662)
		(end 92.3761 112.6162)
		(width 0.254)
		(layer "In3.Cu")
		(net "ANT4_IO_OUT")
	)
	(segment
		(start 94.3761 110.6162)
		(end 152.63044 110.6162)
		(width 0.254)
		(layer "In3.Cu")
		(net "ANT4_IO_OUT")
	)
	(segment
		(start 85.3761 138.8662)
		(end 88.8761 138.8662)
		(width 0.254)
		(layer "In3.Cu")
		(net "ANT4_IO_OUT")
	)
	(segment
		(start 92.3761 112.6162)
		(end 94.3761 110.6162)
		(width 0.254)
		(layer "In3.Cu")
		(net "ANT4_IO_OUT")
	)
	(segment
		(start 88.8761 138.8662)
		(end 92.3761 135.3662)
		(width 0.254)
		(layer "In3.Cu")
		(net "ANT4_IO_OUT")
	)
	(segment
		(start 152.63044 110.6162)
		(end 153.71298 111.69874)
		(width 0.254)
		(layer "In3.Cu")
		(net "ANT4_IO_OUT")
	)
	(segment
		(start 153.71298 112.31274)
		(end 153.71298 111.69874)
		(width 0.254)
		(layer "In3.Cu")
		(net "ANT4_IO_OUT")
	)
	(segment
		(start 82.1261 138.8662)
		(end 82.1261 136.6162)
		(width 0.2032)
		(layer "F.Cu")
		(net "ANT4_IO_IN")
	)
	(segment
		(start 82.1261 138.8662)
		(end 83.00707 138.8662)
		(width 0.2032)
		(layer "F.Cu")
		(net "ANT4_IO_IN")
	)
	(segment
		(start 153.17958 112.43693)
		(end 153.17958 111.91968)
		(width 0.2032)
		(layer "F.Cu")
		(net "ANT4_IO_IN")
	)
	(segment
		(start 153.08722 112.52929)
		(end 153.17958 112.43693)
		(width 0.2032)
		(layer "F.Cu")
		(net "ANT4_IO_IN")
	)
	(segment
		(start 81.8761 136.3662)
		(end 82.1261 136.6162)
		(width 0.2032)
		(layer "F.Cu")
		(net "ANT4_IO_IN")
	)
	(segment
		(start 152.93 112.8123)
		(end 153.08722 112.65508)
		(width 0.2032)
		(layer "F.Cu")
		(net "ANT4_IO_IN")
	)
	(segment
		(start 151.74069 112.8123)
		(end 151.74069 112.8123)
		(width 0.2032)
		(layer "F.Cu")
		(net "ANT4_IO_IN")
	)
	(segment
		(start 83.1261 141.6162)
		(end 83.1261 138.98523)
		(width 0.2032)
		(layer "F.Cu")
		(net "ANT4_IO_IN")
	)
	(segment
		(start 80.5511 136.3662)
		(end 81.8761 136.3662)
		(width 0.2032)
		(layer "F.Cu")
		(net "ANT4_IO_IN")
	)
	(segment
		(start 151.74069 112.8123)
		(end 152.93 112.8123)
		(width 0.2032)
		(layer "F.Cu")
		(net "ANT4_IO_IN")
	)
	(segment
		(start 83.00707 138.8662)
		(end 83.1261 138.98523)
		(width 0.2032)
		(layer "F.Cu")
		(net "ANT4_IO_IN")
	)
	(segment
		(start 153.08722 112.65508)
		(end 153.08722 112.52929)
		(width 0.2032)
		(layer "F.Cu")
		(net "ANT4_IO_IN")
	)
	(via
		(at 153.17958 111.91968)
		(size 0.4064)
		(drill 0.2032)
		(layers "F.Cu" "B.Cu")
		(tenting
			(front yes)
			(back yes)
		)
		(net "ANT4_IO_IN")
	)
	(via
		(at 83.1261 141.6162)
		(size 0.4064)
		(drill 0.2032)
		(layers "F.Cu" "B.Cu")
		(tenting
			(front yes)
			(back yes)
		)
		(net "ANT4_IO_IN")
	)
	(segment
		(start 152.3761 111.1162)
		(end 153.17958 111.91968)
		(width 0.2032)
		(layer "In3.Cu")
		(net "ANT4_IO_IN")
	)
	(segment
		(start 153.17958 111.91968)
		(end 153.17958 111.91968)
		(width 0.2032)
		(layer "In3.Cu")
		(net "ANT4_IO_IN")
	)
	(segment
		(start 93.1261 136.1162)
		(end 93.1261 112.8662)
		(width 0.2032)
		(layer "In3.Cu")
		(net "ANT4_IO_IN")
	)
	(segment
		(start 83.1261 141.6162)
		(end 87.6261 141.6162)
		(width 0.2032)
		(layer "In3.Cu")
		(net "ANT4_IO_IN")
	)
	(segment
		(start 93.1261 112.8662)
		(end 94.8761 111.1162)
		(width 0.2032)
		(layer "In3.Cu")
		(net "ANT4_IO_IN")
	)
	(segment
		(start 94.8761 111.1162)
		(end 152.3761 111.1162)
		(width 0.2032)
		(layer "In3.Cu")
		(net "ANT4_IO_IN")
	)
	(segment
		(start 87.6261 141.6162)
		(end 93.1261 136.1162)
		(width 0.2032)
		(layer "In3.Cu")
		(net "ANT4_IO_IN")
	)
	(segment
		(start 84.79449 135.83899)
		(end 84.82169 135.81179)
		(width 0.2032)
		(layer "F.Cu")
		(net "ANT4_IN")
	)
	(segment
		(start 166.6261 95.81121)
		(end 166.8921 95.54521)
		(width 0.2032)
		(layer "F.Cu")
		(net "ANT4_IN")
	)
	(segment
		(start 83.7011 135.8662)
		(end 83.72831 135.83899)
		(width 0.2032)
		(layer "F.Cu")
		(net "ANT4_IN")
	)
	(segment
		(start 166.6261 95.8662)
		(end 166.6261 95.81121)
		(width 0.2032)
		(layer "F.Cu")
		(net "ANT4_IN")
	)
	(segment
		(start 83.72831 135.83899)
		(end 84.79449 135.83899)
		(width 0.2032)
		(layer "F.Cu")
		(net "ANT4_IN")
	)
	(segment
		(start 166.82575 94.91219)
		(end 166.8921 94.97854)
		(width 0.2032)
		(layer "F.Cu")
		(net "ANT4_IN")
	)
	(segment
		(start 166.8921 95.54521)
		(end 166.8921 94.97854)
		(width 0.2032)
		(layer "F.Cu")
		(net "ANT4_IN")
	)
	(segment
		(start 166.82575 94.91219)
		(end 166.82575 93.86847)
		(width 0.2032)
		(layer "F.Cu")
		(net "ANT4_IN")
	)
	(via
		(at 166.6261 95.8662)
		(size 0.4064)
		(drill 0.2032)
		(layers "F.Cu" "B.Cu")
		(tenting
			(front yes)
			(back yes)
		)
		(net "ANT4_IN")
	)
	(via
		(at 84.82169 135.81179)
		(size 0.4064)
		(drill 0.2032)
		(layers "F.Cu" "B.Cu")
		(tenting
			(front yes)
			(back yes)
		)
		(net "ANT4_IN")
	)
	(segment
		(start 84.82169 135.81179)
		(end 86.5459 134.08758)
		(width 0.2032)
		(layer "In3.Cu")
		(net "ANT4_IN")
	)
	(segment
		(start 168.01287 94.286)
		(end 168.7063 94.97943)
		(width 0.2032)
		(layer "In3.Cu")
		(net "ANT4_IN")
	)
	(segment
		(start 165.8761 95.39938)
		(end 166.03208 95.55536)
		(width 0.2032)
		(layer "In3.Cu")
		(net "ANT4_IN")
	)
	(segment
		(start 169.70354 100.43967)
		(end 169.70354 98.94364)
		(width 0.2032)
		(layer "In3.Cu")
		(net "ANT4_IN")
	)
	(segment
		(start 86.5459 134.08758)
		(end 86.5459 107.51245)
		(width 0.2032)
		(layer "In3.Cu")
		(net "ANT4_IN")
	)
	(segment
		(start 166.03223 95.55536)
		(end 166.30419 95.82732)
		(width 0.2032)
		(layer "In3.Cu")
		(net "ANT4_IN")
	)
	(segment
		(start 168.7063 97.9464)
		(end 169.70354 98.94364)
		(width 0.2032)
		(layer "In3.Cu")
		(net "ANT4_IN")
	)
	(segment
		(start 166.03208 95.55536)
		(end 166.03223 95.55536)
		(width 0.2032)
		(layer "In3.Cu")
		(net "ANT4_IN")
	)
	(segment
		(start 166.58722 95.82732)
		(end 166.6261 95.8662)
		(width 0.2032)
		(layer "In3.Cu")
		(net "ANT4_IN")
	)
	(segment
		(start 166.49091 103.6523)
		(end 169.70354 100.43967)
		(width 0.2032)
		(layer "In3.Cu")
		(net "ANT4_IN")
	)
	(segment
		(start 90.40605 103.6523)
		(end 166.49091 103.6523)
		(width 0.2032)
		(layer "In3.Cu")
		(net "ANT4_IN")
	)
	(segment
		(start 166.30419 95.82732)
		(end 166.58722 95.82732)
		(width 0.2032)
		(layer "In3.Cu")
		(net "ANT4_IN")
	)
	(segment
		(start 165.8761 95.39938)
		(end 165.8761 94.8662)
		(width 0.2032)
		(layer "In3.Cu")
		(net "ANT4_IN")
	)
	(segment
		(start 166.4563 94.286)
		(end 168.01287 94.286)
		(width 0.2032)
		(layer "In3.Cu")
		(net "ANT4_IN")
	)
	(segment
		(start 168.7063 97.9464)
		(end 168.7063 94.97943)
		(width 0.2032)
		(layer "In3.Cu")
		(net "ANT4_IN")
	)
	(segment
		(start 86.5459 107.51245)
		(end 90.40605 103.6523)
		(width 0.2032)
		(layer "In3.Cu")
		(net "ANT4_IN")
	)
	(segment
		(start 165.8761 94.8662)
		(end 166.4563 94.286)
		(width 0.2032)
		(layer "In3.Cu")
		(net "ANT4_IN")
	)
	(segment
		(start 84.71151 122.6162)
		(end 84.82111 122.7258)
		(width 0.2032)
		(layer "F.Cu")
		(net "ANT3_OUT")
	)
	(segment
		(start 168.8261 99.24676)
		(end 168.8261 97.91861)
		(width 0.2032)
		(layer "F.Cu")
		(net "ANT3_OUT")
	)
	(segment
		(start 84.82111 122.7258)
		(end 84.8761 122.7258)
		(width 0.2032)
		(layer "F.Cu")
		(net "ANT3_OUT")
	)
	(segment
		(start 83.9511 122.6162)
		(end 84.71151 122.6162)
		(width 0.2032)
		(layer "F.Cu")
		(net "ANT3_OUT")
	)
	(segment
		(start 168.8261 99.24676)
		(end 169.19554 99.6162)
		(width 0.2032)
		(layer "F.Cu")
		(net "ANT3_OUT")
	)
	(segment
		(start 168.82575 97.91825)
		(end 168.8261 97.91861)
		(width 0.2032)
		(layer "F.Cu")
		(net "ANT3_OUT")
	)
	(via
		(at 169.19554 99.6162)
		(size 0.4064)
		(drill 0.2032)
		(layers "F.Cu" "B.Cu")
		(tenting
			(front yes)
			(back yes)
		)
		(net "ANT3_OUT")
	)
	(via
		(at 84.8761 122.7258)
		(size 0.4064)
		(drill 0.2032)
		(layers "F.Cu" "B.Cu")
		(tenting
			(front yes)
			(back yes)
		)
		(net "ANT3_OUT")
	)
	(segment
		(start 84.93108 122.7258)
		(end 85.03268 122.6242)
		(width 0.2032)
		(layer "In3.Cu")
		(net "ANT3_OUT")
	)
	(segment
		(start 86.2157 121.49502)
		(end 86.2157 107.37568)
		(width 0.2032)
		(layer "In3.Cu")
		(net "ANT3_OUT")
	)
	(segment
		(start 166.35414 103.3221)
		(end 169.19554 100.4807)
		(width 0.2032)
		(layer "In3.Cu")
		(net "ANT3_OUT")
	)
	(segment
		(start 90.26928 103.3221)
		(end 166.35414 103.3221)
		(width 0.2032)
		(layer "In3.Cu")
		(net "ANT3_OUT")
	)
	(segment
		(start 84.8761 122.7258)
		(end 84.93108 122.7258)
		(width 0.2032)
		(layer "In3.Cu")
		(net "ANT3_OUT")
	)
	(segment
		(start 85.03268 122.6242)
		(end 85.08652 122.6242)
		(width 0.2032)
		(layer "In3.Cu")
		(net "ANT3_OUT")
	)
	(segment
		(start 169.19554 100.4807)
		(end 169.19554 99.6162)
		(width 0.2032)
		(layer "In3.Cu")
		(net "ANT3_OUT")
	)
	(segment
		(start 85.08652 122.6242)
		(end 86.2157 121.49502)
		(width 0.2032)
		(layer "In3.Cu")
		(net "ANT3_OUT")
	)
	(segment
		(start 86.2157 107.37568)
		(end 90.26928 103.3221)
		(width 0.2032)
		(layer "In3.Cu")
		(net "ANT3_OUT")
	)
	(segment
		(start 153.11382 114.31243)
		(end 154.9549 112.47134)
		(width 0.2032)
		(layer "F.Cu")
		(net "ANT3_IO_OUT")
	)
	(segment
		(start 83.1261 124.1162)
		(end 83.1261 123.3662)
		(width 0.2032)
		(layer "F.Cu")
		(net "ANT3_IO_OUT")
	)
	(segment
		(start 154.9549 112.47134)
		(end 154.9549 111.8662)
		(width 0.2032)
		(layer "F.Cu")
		(net "ANT3_IO_OUT")
	)
	(segment
		(start 83.1261 124.1162)
		(end 84.1261 125.1162)
		(width 0.2032)
		(layer "F.Cu")
		(net "ANT3_IO_OUT")
	)
	(segment
		(start 83.3277 123.1646)
		(end 83.9027 123.1646)
		(width 0.2032)
		(layer "F.Cu")
		(net "ANT3_IO_OUT")
	)
	(segment
		(start 83.9027 123.1646)
		(end 83.9511 123.1162)
		(width 0.2032)
		(layer "F.Cu")
		(net "ANT3_IO_OUT")
	)
	(segment
		(start 84.3761 125.1162)
		(end 85.3761 125.1162)
		(width 0.2032)
		(layer "F.Cu")
		(net "ANT3_IO_OUT")
	)
	(segment
		(start 151.74069 114.31243)
		(end 153.11382 114.31243)
		(width 0.2032)
		(layer "F.Cu")
		(net "ANT3_IO_OUT")
	)
	(segment
		(start 83.1261 123.3662)
		(end 83.3277 123.1646)
		(width 0.2032)
		(layer "F.Cu")
		(net "ANT3_IO_OUT")
	)
	(via
		(at 85.3761 125.1162)
		(size 0.4064)
		(drill 0.2032)
		(layers "F.Cu" "B.Cu")
		(tenting
			(front yes)
			(back yes)
		)
		(net "ANT3_IO_OUT")
	)
	(via
		(at 154.9549 111.8662)
		(size 0.4064)
		(drill 0.2032)
		(layers "F.Cu" "B.Cu")
		(tenting
			(front yes)
			(back yes)
		)
		(net "ANT3_IO_OUT")
	)
	(segment
		(start 84.25372 137.24382)
		(end 84.6261 137.6162)
		(width 0.2032)
		(layer "In3.Cu")
		(net "ANT3_IO_OUT")
	)
	(segment
		(start 84.6261 125.8662)
		(end 85.3761 125.1162)
		(width 0.2032)
		(layer "In3.Cu")
		(net "ANT3_IO_OUT")
	)
	(segment
		(start 91.3761 111.1162)
		(end 93.79193 108.70037)
		(width 0.2032)
		(layer "In3.Cu")
		(net "ANT3_IO_OUT")
	)
	(segment
		(start 154.9549 111.8662)
		(end 154.9549 110.945)
		(width 0.2032)
		(layer "In3.Cu")
		(net "ANT3_IO_OUT")
	)
	(segment
		(start 84.25372 137.24382)
		(end 84.25372 132.17739)
		(width 0.2032)
		(layer "In3.Cu")
		(net "ANT3_IO_OUT")
	)
	(segment
		(start 93.79193 108.70037)
		(end 152.71027 108.70037)
		(width 0.2032)
		(layer "In3.Cu")
		(net "ANT3_IO_OUT")
	)
	(segment
		(start 84.25372 132.17739)
		(end 84.6261 131.80501)
		(width 0.2032)
		(layer "In3.Cu")
		(net "ANT3_IO_OUT")
	)
	(segment
		(start 152.71027 108.70037)
		(end 154.9549 110.945)
		(width 0.2032)
		(layer "In3.Cu")
		(net "ANT3_IO_OUT")
	)
	(segment
		(start 91.3761 134.1162)
		(end 91.3761 111.1162)
		(width 0.2032)
		(layer "In3.Cu")
		(net "ANT3_IO_OUT")
	)
	(segment
		(start 84.6261 137.6162)
		(end 87.8761 137.6162)
		(width 0.2032)
		(layer "In3.Cu")
		(net "ANT3_IO_OUT")
	)
	(segment
		(start 84.6261 131.80501)
		(end 84.6261 125.8662)
		(width 0.2032)
		(layer "In3.Cu")
		(net "ANT3_IO_OUT")
	)
	(segment
		(start 87.8761 137.6162)
		(end 91.3761 134.1162)
		(width 0.2032)
		(layer "In3.Cu")
		(net "ANT3_IO_OUT")
	)
	(segment
		(start 83.1261 125.1162)
		(end 83.3761 125.3662)
		(width 0.2032)
		(layer "F.Cu")
		(net "ANT3_IO_IN")
	)
	(segment
		(start 153.14697 113.8123)
		(end 154.3453 112.61397)
		(width 0.2032)
		(layer "F.Cu")
		(net "ANT3_IO_IN")
	)
	(segment
		(start 82.3761 125.1162)
		(end 83.1261 125.1162)
		(width 0.2032)
		(layer "F.Cu")
		(net "ANT3_IO_IN")
	)
	(segment
		(start 151.74069 113.8123)
		(end 153.14697 113.8123)
		(width 0.2032)
		(layer "F.Cu")
		(net "ANT3_IO_IN")
	)
	(segment
		(start 154.3453 112.61397)
		(end 154.3453 111.8662)
		(width 0.2032)
		(layer "F.Cu")
		(net "ANT3_IO_IN")
	)
	(segment
		(start 82.3761 125.1162)
		(end 82.3761 122.8662)
		(width 0.2032)
		(layer "F.Cu")
		(net "ANT3_IO_IN")
	)
	(segment
		(start 83.3761 127.6162)
		(end 83.8761 128.1162)
		(width 0.2032)
		(layer "F.Cu")
		(net "ANT3_IO_IN")
	)
	(segment
		(start 80.8011 122.6162)
		(end 82.1261 122.6162)
		(width 0.2032)
		(layer "F.Cu")
		(net "ANT3_IO_IN")
	)
	(segment
		(start 82.1261 122.6162)
		(end 82.3761 122.8662)
		(width 0.2032)
		(layer "F.Cu")
		(net "ANT3_IO_IN")
	)
	(segment
		(start 83.3761 127.6162)
		(end 83.3761 125.3662)
		(width 0.2032)
		(layer "F.Cu")
		(net "ANT3_IO_IN")
	)
	(via
		(at 154.3453 111.8662)
		(size 0.4064)
		(drill 0.2032)
		(layers "F.Cu" "B.Cu")
		(tenting
			(front yes)
			(back yes)
		)
		(net "ANT3_IO_IN")
	)
	(via
		(at 83.92352 128.16213)
		(size 0.4064)
		(drill 0.2032)
		(layers "F.Cu" "B.Cu")
		(tenting
			(front yes)
			(back yes)
		)
		(net "ANT3_IO_IN")
	)
	(segment
		(start 94.3761 109.1162)
		(end 152.3761 109.1162)
		(width 0.2032)
		(layer "In3.Cu")
		(net "ANT3_IO_IN")
	)
	(segment
		(start 91.71027 111.95037)
		(end 91.71027 111.78203)
		(width 0.2032)
		(layer "In3.Cu")
		(net "ANT3_IO_IN")
	)
	(segment
		(start 88.6261 138.1162)
		(end 91.8761 134.8662)
		(width 0.2032)
		(layer "In3.Cu")
		(net "ANT3_IO_IN")
	)
	(segment
		(start 84.3761 138.1162)
		(end 88.6261 138.1162)
		(width 0.2032)
		(layer "In3.Cu")
		(net "ANT3_IO_IN")
	)
	(segment
		(start 91.71027 111.95037)
		(end 91.8761 112.1162)
		(width 0.2032)
		(layer "In3.Cu")
		(net "ANT3_IO_IN")
	)
	(segment
		(start 83.92352 137.66361)
		(end 83.92352 128.16213)
		(width 0.2032)
		(layer "In3.Cu")
		(net "ANT3_IO_IN")
	)
	(segment
		(start 154.3453 111.8662)
		(end 154.3453 111.0854)
		(width 0.2032)
		(layer "In3.Cu")
		(net "ANT3_IO_IN")
	)
	(segment
		(start 152.3761 109.1162)
		(end 154.3453 111.0854)
		(width 0.2032)
		(layer "In3.Cu")
		(net "ANT3_IO_IN")
	)
	(segment
		(start 91.71027 111.78203)
		(end 94.3761 109.1162)
		(width 0.2032)
		(layer "In3.Cu")
		(net "ANT3_IO_IN")
	)
	(segment
		(start 91.8761 134.8662)
		(end 91.8761 112.1162)
		(width 0.2032)
		(layer "In3.Cu")
		(net "ANT3_IO_IN")
	)
	(segment
		(start 83.92352 137.66361)
		(end 84.3761 138.1162)
		(width 0.2032)
		(layer "In3.Cu")
		(net "ANT3_IO_IN")
	)
	(segment
		(start 166.32588 95.07575)
		(end 166.3841 95.13397)
		(width 0.2032)
		(layer "F.Cu")
		(net "ANT3_IN")
	)
	(segment
		(start 166.3841 95.18896)
		(end 166.3841 95.13397)
		(width 0.2032)
		(layer "F.Cu")
		(net "ANT3_IN")
	)
	(segment
		(start 166.32588 95.07575)
		(end 166.32588 93.86847)
		(width 0.2032)
		(layer "F.Cu")
		(net "ANT3_IN")
	)
	(segment
		(start 83.9511 122.1162)
		(end 84.8761 122.1162)
		(width 0.2032)
		(layer "F.Cu")
		(net "ANT3_IN")
	)
	(via
		(at 166.3841 95.18896)
		(size 0.4064)
		(drill 0.2032)
		(layers "F.Cu" "B.Cu")
		(tenting
			(front yes)
			(back yes)
		)
		(net "ANT3_IN")
	)
	(via
		(at 84.8761 122.1162)
		(size 0.4064)
		(drill 0.2032)
		(layers "F.Cu" "B.Cu")
		(tenting
			(front yes)
			(back yes)
		)
		(net "ANT3_IN")
	)
	(segment
		(start 168.68754 100.52172)
		(end 168.68754 98.42764)
		(width 0.2032)
		(layer "In3.Cu")
		(net "ANT3_IN")
	)
	(segment
		(start 168.3761 98.1162)
		(end 168.3761 95.1162)
		(width 0.2032)
		(layer "In3.Cu")
		(net "ANT3_IN")
	)
	(segment
		(start 166.21737 102.9919)
		(end 168.68754 100.52172)
		(width 0.2032)
		(layer "In3.Cu")
		(net "ANT3_IN")
	)
	(segment
		(start 90.13251 102.9919)
		(end 166.21737 102.9919)
		(width 0.2032)
		(layer "In3.Cu")
		(net "ANT3_IN")
	)
	(segment
		(start 166.3841 95.18896)
		(end 166.95686 94.6162)
		(width 0.2032)
		(layer "In3.Cu")
		(net "ANT3_IN")
	)
	(segment
		(start 166.95686 94.6162)
		(end 167.8761 94.6162)
		(width 0.2032)
		(layer "In3.Cu")
		(net "ANT3_IN")
	)
	(segment
		(start 84.8761 122.1162)
		(end 85.8855 121.1068)
		(width 0.2032)
		(layer "In3.Cu")
		(net "ANT3_IN")
	)
	(segment
		(start 167.8761 94.6162)
		(end 168.3761 95.1162)
		(width 0.2032)
		(layer "In3.Cu")
		(net "ANT3_IN")
	)
	(segment
		(start 85.8855 107.23891)
		(end 90.13251 102.9919)
		(width 0.2032)
		(layer "In3.Cu")
		(net "ANT3_IN")
	)
	(segment
		(start 85.8855 121.1068)
		(end 85.8855 107.23891)
		(width 0.2032)
		(layer "In3.Cu")
		(net "ANT3_IN")
	)
	(segment
		(start 168.3761 98.1162)
		(end 168.68754 98.42764)
		(width 0.2032)
		(layer "In3.Cu")
		(net "ANT3_IN")
	)
	(segment
		(start 166.6261 96.63884)
		(end 166.6261 96.6162)
		(width 0.2032)
		(layer "F.Cu")
		(net "ANT2_OUT")
	)
	(segment
		(start 83.9511 109.3662)
		(end 84.8761 109.3662)
		(width 0.2032)
		(layer "F.Cu")
		(net "ANT2_OUT")
	)
	(segment
		(start 166.6261 96.63884)
		(end 166.82575 96.8385)
		(width 0.2032)
		(layer "F.Cu")
		(net "ANT2_OUT")
	)
	(segment
		(start 166.82575 97.91825)
		(end 166.82575 96.8385)
		(width 0.2032)
		(layer "F.Cu")
		(net "ANT2_OUT")
	)
	(segment
		(start 84.8761 109.3662)
		(end 84.8761 109.3662)
		(width 0.2032)
		(layer "F.Cu")
		(net "ANT2_OUT")
	)
	(via
		(at 84.8761 109.3662)
		(size 0.4064)
		(drill 0.2032)
		(layers "F.Cu" "B.Cu")
		(tenting
			(front yes)
			(back yes)
		)
		(net "ANT2_OUT")
	)
	(via
		(at 166.6261 96.6162)
		(size 0.4064)
		(drill 0.2032)
		(layers "F.Cu" "B.Cu")
		(tenting
			(front yes)
			(back yes)
		)
		(net "ANT2_OUT")
	)
	(segment
		(start 85.50791 96.4162)
		(end 108.35913 96.4162)
		(width 0.2032)
		(layer "In3.Cu")
		(net "ANT2_OUT")
	)
	(segment
		(start 84.3261 108.86676)
		(end 84.82554 109.3662)
		(width 0.2032)
		(layer "In3.Cu")
		(net "ANT2_OUT")
	)
	(segment
		(start 137.6563 94.186)
		(end 139.1261 92.7162)
		(width 0.2032)
		(layer "In3.Cu")
		(net "ANT2_OUT")
	)
	(segment
		(start 108.35913 96.4162)
		(end 110.58933 94.186)
		(width 0.2032)
		(layer "In3.Cu")
		(net "ANT2_OUT")
	)
	(segment
		(start 162.8042 96.48506)
		(end 163.4037 95.88556)
		(width 0.2032)
		(layer "In3.Cu")
		(net "ANT2_OUT")
	)
	(segment
		(start 154.6261 96.48506)
		(end 162.8042 96.48506)
		(width 0.2032)
		(layer "In3.Cu")
		(net "ANT2_OUT")
	)
	(segment
		(start 84.82554 109.3662)
		(end 84.8761 109.3662)
		(width 0.2032)
		(layer "In3.Cu")
		(net "ANT2_OUT")
	)
	(segment
		(start 163.4037 95.88556)
		(end 165.89545 95.88556)
		(width 0.2032)
		(layer "In3.Cu")
		(net "ANT2_OUT")
	)
	(segment
		(start 139.1261 92.7162)
		(end 150.85724 92.7162)
		(width 0.2032)
		(layer "In3.Cu")
		(net "ANT2_OUT")
	)
	(segment
		(start 110.58933 94.186)
		(end 137.6563 94.186)
		(width 0.2032)
		(layer "In3.Cu")
		(net "ANT2_OUT")
	)
	(segment
		(start 84.3261 97.59801)
		(end 85.50791 96.4162)
		(width 0.2032)
		(layer "In3.Cu")
		(net "ANT2_OUT")
	)
	(segment
		(start 165.89545 95.88556)
		(end 166.6261 96.6162)
		(width 0.2032)
		(layer "In3.Cu")
		(net "ANT2_OUT")
	)
	(segment
		(start 84.3261 108.86676)
		(end 84.3261 97.59801)
		(width 0.2032)
		(layer "In3.Cu")
		(net "ANT2_OUT")
	)
	(segment
		(start 150.85724 92.7162)
		(end 154.6261 96.48506)
		(width 0.2032)
		(layer "In3.Cu")
		(net "ANT2_OUT")
	)
	(segment
		(start 153.7665 115.4758)
		(end 153.7665 114.8662)
		(width 0.2032)
		(layer "F.Cu")
		(net "ANT2_IO_OUT")
	)
	(segment
		(start 83.24513 109.8662)
		(end 83.9511 109.8662)
		(width 0.2032)
		(layer "F.Cu")
		(net "ANT2_IO_OUT")
	)
	(segment
		(start 83.1261 109.98523)
		(end 83.24513 109.8662)
		(width 0.2032)
		(layer "F.Cu")
		(net "ANT2_IO_OUT")
	)
	(segment
		(start 151.74069 115.8123)
		(end 153.43 115.8123)
		(width 0.2032)
		(layer "F.Cu")
		(net "ANT2_IO_OUT")
	)
	(segment
		(start 83.1261 110.6162)
		(end 83.8761 111.3662)
		(width 0.2032)
		(layer "F.Cu")
		(net "ANT2_IO_OUT")
	)
	(segment
		(start 83.1261 110.6162)
		(end 83.1261 109.98523)
		(width 0.2032)
		(layer "F.Cu")
		(net "ANT2_IO_OUT")
	)
	(segment
		(start 84.1261 111.3662)
		(end 85.1261 111.3662)
		(width 0.2032)
		(layer "F.Cu")
		(net "ANT2_IO_OUT")
	)
	(segment
		(start 153.43 115.8123)
		(end 153.7665 115.4758)
		(width 0.2032)
		(layer "F.Cu")
		(net "ANT2_IO_OUT")
	)
	(via
		(at 85.1261 111.3662)
		(size 0.4064)
		(drill 0.2032)
		(layers "F.Cu" "B.Cu")
		(tenting
			(front yes)
			(back yes)
		)
		(net "ANT2_IO_OUT")
	)
	(via
		(at 88.3761 110.1162)
		(size 0.4064)
		(drill 0.2032)
		(layers "F.Cu" "B.Cu")
		(tenting
			(front yes)
			(back yes)
		)
		(net "ANT2_IO_OUT")
	)
	(via
		(at 153.7665 114.8662)
		(size 0.4064)
		(drill 0.2032)
		(layers "F.Cu" "B.Cu")
		(tenting
			(front yes)
			(back yes)
		)
		(net "ANT2_IO_OUT")
	)
	(segment
		(start 86.3761 110.1162)
		(end 88.3761 110.1162)
		(width 0.2032)
		(layer "In2.Cu")
		(net "ANT2_IO_OUT")
	)
	(segment
		(start 85.1261 111.3662)
		(end 86.3761 110.1162)
		(width 0.2032)
		(layer "In2.Cu")
		(net "ANT2_IO_OUT")
	)
	(segment
		(start 153.7665 114.92119)
		(end 153.8681 115.02279)
		(width 0.2032)
		(layer "In3.Cu")
		(net "ANT2_IO_OUT")
	)
	(segment
		(start 151.93093 106.138)
		(end 156.1261 110.33317)
		(width 0.2032)
		(layer "In3.Cu")
		(net "ANT2_IO_OUT")
	)
	(segment
		(start 88.1261 109.8662)
		(end 88.3761 110.1162)
		(width 0.2032)
		(layer "In3.Cu")
		(net "ANT2_IO_OUT")
	)
	(segment
		(start 155.33289 115.6964)
		(end 156.1261 114.90319)
		(width 0.2032)
		(layer "In3.Cu")
		(net "ANT2_IO_OUT")
	)
	(segment
		(start 154.48788 115.6964)
		(end 155.33289 115.6964)
		(width 0.2032)
		(layer "In3.Cu")
		(net "ANT2_IO_OUT")
	)
	(segment
		(start 153.8681 115.07662)
		(end 154.48788 115.6964)
		(width 0.2032)
		(layer "In3.Cu")
		(net "ANT2_IO_OUT")
	)
	(segment
		(start 153.7665 114.92119)
		(end 153.7665 114.8662)
		(width 0.2032)
		(layer "In3.Cu")
		(net "ANT2_IO_OUT")
	)
	(segment
		(start 88.1261 109.8662)
		(end 88.1261 108.58317)
		(width 0.2032)
		(layer "In3.Cu")
		(net "ANT2_IO_OUT")
	)
	(segment
		(start 156.1261 114.90319)
		(end 156.1261 110.33317)
		(width 0.2032)
		(layer "In3.Cu")
		(net "ANT2_IO_OUT")
	)
	(segment
		(start 153.8681 115.07662)
		(end 153.8681 115.02279)
		(width 0.2032)
		(layer "In3.Cu")
		(net "ANT2_IO_OUT")
	)
	(segment
		(start 90.57127 106.138)
		(end 151.93093 106.138)
		(width 0.2032)
		(layer "In3.Cu")
		(net "ANT2_IO_OUT")
	)
	(segment
		(start 88.1261 108.58317)
		(end 90.57127 106.138)
		(width 0.2032)
		(layer "In3.Cu")
		(net "ANT2_IO_OUT")
	)
	(segment
		(start 153.11802 114.90508)
		(end 153.1569 114.8662)
		(width 0.2032)
		(layer "F.Cu")
		(net "ANT2_IO_IN")
	)
	(segment
		(start 82.3761 111.3662)
		(end 82.3761 109.8662)
		(width 0.2032)
		(layer "F.Cu")
		(net "ANT2_IO_IN")
	)
	(segment
		(start 83.6261 114.1162)
		(end 84.1261 114.1162)
		(width 0.2032)
		(layer "F.Cu")
		(net "ANT2_IO_IN")
	)
	(segment
		(start 151.74069 115.31242)
		(end 152.96819 115.31242)
		(width 0.2032)
		(layer "F.Cu")
		(net "ANT2_IO_IN")
	)
	(segment
		(start 80.8011 109.3662)
		(end 81.8761 109.3662)
		(width 0.2032)
		(layer "F.Cu")
		(net "ANT2_IO_IN")
	)
	(segment
		(start 82.3761 111.3662)
		(end 83.1261 111.3662)
		(width 0.2032)
		(layer "F.Cu")
		(net "ANT2_IO_IN")
	)
	(segment
		(start 81.8761 109.3662)
		(end 82.3761 109.8662)
		(width 0.2032)
		(layer "F.Cu")
		(net "ANT2_IO_IN")
	)
	(segment
		(start 83.2511 113.7412)
		(end 83.2511 111.4912)
		(width 0.2032)
		(layer "F.Cu")
		(net "ANT2_IO_IN")
	)
	(segment
		(start 80.8011 109.3662)
		(end 80.8011 109.3662)
		(width 0.2032)
		(layer "F.Cu")
		(net "ANT2_IO_IN")
	)
	(segment
		(start 153.11802 115.16259)
		(end 153.11802 114.90508)
		(width 0.2032)
		(layer "F.Cu")
		(net "ANT2_IO_IN")
	)
	(segment
		(start 152.96819 115.31242)
		(end 153.11802 115.16259)
		(width 0.2032)
		(layer "F.Cu")
		(net "ANT2_IO_IN")
	)
	(segment
		(start 83.2511 113.7412)
		(end 83.6261 114.1162)
		(width 0.2032)
		(layer "F.Cu")
		(net "ANT2_IO_IN")
	)
	(segment
		(start 83.1261 111.3662)
		(end 83.2511 111.4912)
		(width 0.2032)
		(layer "F.Cu")
		(net "ANT2_IO_IN")
	)
	(via
		(at 84.1261 114.1162)
		(size 0.4064)
		(drill 0.2032)
		(layers "F.Cu" "B.Cu")
		(tenting
			(front yes)
			(back yes)
		)
		(net "ANT2_IO_IN")
	)
	(via
		(at 87.7959 110.8662)
		(size 0.4064)
		(drill 0.2032)
		(layers "F.Cu" "B.Cu")
		(tenting
			(front yes)
			(back yes)
		)
		(net "ANT2_IO_IN")
	)
	(via
		(at 153.1569 114.8662)
		(size 0.4064)
		(drill 0.2032)
		(layers "F.Cu" "B.Cu")
		(tenting
			(front yes)
			(back yes)
		)
		(net "ANT2_IO_IN")
	)
	(segment
		(start 86.40768 110.8662)
		(end 87.7959 110.8662)
		(width 0.2032)
		(layer "In2.Cu")
		(net "ANT2_IO_IN")
	)
	(segment
		(start 84.1261 113.14778)
		(end 86.40768 110.8662)
		(width 0.2032)
		(layer "In2.Cu")
		(net "ANT2_IO_IN")
	)
	(segment
		(start 84.1261 114.1162)
		(end 84.1261 113.14778)
		(width 0.2032)
		(layer "In2.Cu")
		(net "ANT2_IO_IN")
	)
	(segment
		(start 153.1569 114.92119)
		(end 153.2585 115.02279)
		(width 0.2032)
		(layer "In3.Cu")
		(net "ANT2_IO_IN")
	)
	(segment
		(start 87.7959 110.8662)
		(end 87.7959 108.4464)
		(width 0.2032)
		(layer "In3.Cu")
		(net "ANT2_IO_IN")
	)
	(segment
		(start 153.1569 114.92119)
		(end 153.1569 114.8662)
		(width 0.2032)
		(layer "In3.Cu")
		(net "ANT2_IO_IN")
	)
	(segment
		(start 154.20848 116.0266)
		(end 155.49873 116.0266)
		(width 0.2032)
		(layer "In3.Cu")
		(net "ANT2_IO_IN")
	)
	(segment
		(start 153.2585 115.07662)
		(end 153.2585 115.02279)
		(width 0.2032)
		(layer "In3.Cu")
		(net "ANT2_IO_IN")
	)
	(segment
		(start 153.2585 115.07662)
		(end 154.20848 116.0266)
		(width 0.2032)
		(layer "In3.Cu")
		(net "ANT2_IO_IN")
	)
	(segment
		(start 155.49873 116.0266)
		(end 156.4563 115.06903)
		(width 0.2032)
		(layer "In3.Cu")
		(net "ANT2_IO_IN")
	)
	(segment
		(start 87.7959 108.4464)
		(end 90.4345 105.8078)
		(width 0.2032)
		(layer "In3.Cu")
		(net "ANT2_IO_IN")
	)
	(segment
		(start 90.4345 105.8078)
		(end 152.0677 105.8078)
		(width 0.2032)
		(layer "In3.Cu")
		(net "ANT2_IO_IN")
	)
	(segment
		(start 156.4563 115.06903)
		(end 156.4563 110.1964)
		(width 0.2032)
		(layer "In3.Cu")
		(net "ANT2_IO_IN")
	)
	(segment
		(start 152.0677 105.8078)
		(end 156.4563 110.1964)
		(width 0.2032)
		(layer "In3.Cu")
		(net "ANT2_IO_IN")
	)
	(segment
		(start 168.13973 99.4731)
		(end 168.32587 99.28696)
		(width 0.2032)
		(layer "F.Cu")
		(net "ANT2_IN")
	)
	(segment
		(start 84.6809 108.8662)
		(end 84.75162 108.79548)
		(width 0.2032)
		(layer "F.Cu")
		(net "ANT2_IN")
	)
	(segment
		(start 84.75162 108.79548)
		(end 85.07403 108.79548)
		(width 0.2032)
		(layer "F.Cu")
		(net "ANT2_IN")
	)
	(segment
		(start 168.13973 99.52808)
		(end 168.13973 99.4731)
		(width 0.2032)
		(layer "F.Cu")
		(net "ANT2_IN")
	)
	(segment
		(start 85.07403 108.79548)
		(end 85.11291 108.7566)
		(width 0.2032)
		(layer "F.Cu")
		(net "ANT2_IN")
	)
	(segment
		(start 168.32587 99.28696)
		(end 168.32587 97.91825)
		(width 0.2032)
		(layer "F.Cu")
		(net "ANT2_IN")
	)
	(segment
		(start 83.9511 108.8662)
		(end 84.6809 108.8662)
		(width 0.2032)
		(layer "F.Cu")
		(net "ANT2_IN")
	)
	(via
		(at 168.13973 99.52808)
		(size 0.4064)
		(drill 0.2032)
		(layers "F.Cu" "B.Cu")
		(tenting
			(front yes)
			(back yes)
		)
		(net "ANT2_IN")
	)
	(via
		(at 85.11291 108.7566)
		(size 0.4064)
		(drill 0.2032)
		(layers "F.Cu" "B.Cu")
		(tenting
			(front yes)
			(back yes)
		)
		(net "ANT2_IN")
	)
	(segment
		(start 166.2865 102.4558)
		(end 168.10085 100.64144)
		(width 0.2032)
		(layer "In3.Cu")
		(net "ANT2_IN")
	)
	(segment
		(start 85.11291 107.54454)
		(end 90.20164 102.4558)
		(width 0.2032)
		(layer "In3.Cu")
		(net "ANT2_IN")
	)
	(segment
		(start 85.11291 108.7566)
		(end 85.11291 107.54454)
		(width 0.2032)
		(layer "In3.Cu")
		(net "ANT2_IN")
	)
	(segment
		(start 168.10085 100.64144)
		(end 168.10085 99.56696)
		(width 0.2032)
		(layer "In3.Cu")
		(net "ANT2_IN")
	)
	(segment
		(start 90.20164 102.4558)
		(end 166.2865 102.4558)
		(width 0.2032)
		(layer "In3.Cu")
		(net "ANT2_IN")
	)
	(segment
		(start 168.10085 99.56696)
		(end 168.13973 99.52808)
		(width 0.2032)
		(layer "In3.Cu")
		(net "ANT2_IN")
	)
	(segment
		(start 166.30251 97.89488)
		(end 166.32588 97.91825)
		(width 0.2032)
		(layer "F.Cu")
		(net "ANT1_OUT")
	)
	(segment
		(start 84.6261 95.8662)
		(end 85.26658 96.50668)
		(width 0.2032)
		(layer "F.Cu")
		(net "ANT1_OUT")
	)
	(segment
		(start 166.30251 97.89488)
		(end 166.30251 97.04261)
		(width 0.2032)
		(layer "F.Cu")
		(net "ANT1_OUT")
	)
	(segment
		(start 85.26658 97.37595)
		(end 85.26658 96.50668)
		(width 0.2032)
		(layer "F.Cu")
		(net "ANT1_OUT")
	)
	(segment
		(start 83.7011 95.8662)
		(end 84.6261 95.8662)
		(width 0.2032)
		(layer "F.Cu")
		(net "ANT1_OUT")
	)
	(segment
		(start 165.8761 96.6162)
		(end 166.30251 97.04261)
		(width 0.2032)
		(layer "F.Cu")
		(net "ANT1_OUT")
	)
	(via
		(at 85.26658 97.37595)
		(size 0.4064)
		(drill 0.2032)
		(layers "F.Cu" "B.Cu")
		(tenting
			(front yes)
			(back yes)
		)
		(net "ANT1_OUT")
	)
	(via
		(at 165.8761 96.6162)
		(size 0.4064)
		(drill 0.2032)
		(layers "F.Cu" "B.Cu")
		(tenting
			(front yes)
			(back yes)
		)
		(net "ANT1_OUT")
	)
	(segment
		(start 165.3761 97.1162)
		(end 165.8761 96.6162)
		(width 0.2032)
		(layer "In3.Cu")
		(net "ANT1_OUT")
	)
	(segment
		(start 108.3261 96.9162)
		(end 110.7261 94.5162)
		(width 0.2032)
		(layer "In3.Cu")
		(net "ANT1_OUT")
	)
	(segment
		(start 146.4261 97.1162)
		(end 165.3761 97.1162)
		(width 0.2032)
		(layer "In3.Cu")
		(net "ANT1_OUT")
	)
	(segment
		(start 138.1261 94.5162)
		(end 139.3261 93.3162)
		(width 0.2032)
		(layer "In3.Cu")
		(net "ANT1_OUT")
	)
	(segment
		(start 142.6261 93.3162)
		(end 146.4261 97.1162)
		(width 0.2032)
		(layer "In3.Cu")
		(net "ANT1_OUT")
	)
	(segment
		(start 85.26658 97.37595)
		(end 85.26658 97.32097)
		(width 0.2032)
		(layer "In3.Cu")
		(net "ANT1_OUT")
	)
	(segment
		(start 139.3261 93.3162)
		(end 142.6261 93.3162)
		(width 0.2032)
		(layer "In3.Cu")
		(net "ANT1_OUT")
	)
	(segment
		(start 85.36817 97.16378)
		(end 85.61575 96.9162)
		(width 0.2032)
		(layer "In3.Cu")
		(net "ANT1_OUT")
	)
	(segment
		(start 110.7261 94.5162)
		(end 138.1261 94.5162)
		(width 0.2032)
		(layer "In3.Cu")
		(net "ANT1_OUT")
	)
	(segment
		(start 85.61575 96.9162)
		(end 108.3261 96.9162)
		(width 0.2032)
		(layer "In3.Cu")
		(net "ANT1_OUT")
	)
	(segment
		(start 85.36817 97.21937)
		(end 85.36817 97.16378)
		(width 0.2032)
		(layer "In3.Cu")
		(net "ANT1_OUT")
	)
	(segment
		(start 85.26658 97.32097)
		(end 85.36817 97.21937)
		(width 0.2032)
		(layer "In3.Cu")
		(net "ANT1_OUT")
	)
	(segment
		(start 154.94682 114.89708)
		(end 154.9857 114.8582)
		(width 0.2032)
		(layer "F.Cu")
		(net "ANT1_IO_OUT")
	)
	(segment
		(start 154.94682 115.2639)
		(end 154.94682 114.89708)
		(width 0.2032)
		(layer "F.Cu")
		(net "ANT1_IO_OUT")
	)
	(segment
		(start 83.3761 97.8662)
		(end 84.1261 97.8662)
		(width 0.2032)
		(layer "F.Cu")
		(net "ANT1_IO_OUT")
	)
	(segment
		(start 153.39842 116.81229)
		(end 154.94682 115.2639)
		(width 0.2032)
		(layer "F.Cu")
		(net "ANT1_IO_OUT")
	)
	(segment
		(start 83.68877 96.37853)
		(end 83.7011 96.3662)
		(width 0.2032)
		(layer "F.Cu")
		(net "ANT1_IO_OUT")
	)
	(segment
		(start 82.8761 97.3662)
		(end 82.8761 96.6162)
		(width 0.2032)
		(layer "F.Cu")
		(net "ANT1_IO_OUT")
	)
	(segment
		(start 85.1261 98.1162)
		(end 85.1261 98.1162)
		(width 0.2032)
		(layer "F.Cu")
		(net "ANT1_IO_OUT")
	)
	(segment
		(start 82.8761 97.3662)
		(end 83.3761 97.8662)
		(width 0.2032)
		(layer "F.Cu")
		(net "ANT1_IO_OUT")
	)
	(segment
		(start 84.1261 98.1162)
		(end 85.1261 98.1162)
		(width 0.2032)
		(layer "F.Cu")
		(net "ANT1_IO_OUT")
	)
	(segment
		(start 82.8761 96.6162)
		(end 83.11377 96.37853)
		(width 0.2032)
		(layer "F.Cu")
		(net "ANT1_IO_OUT")
	)
	(segment
		(start 83.11377 96.37853)
		(end 83.68877 96.37853)
		(width 0.2032)
		(layer "F.Cu")
		(net "ANT1_IO_OUT")
	)
	(segment
		(start 151.74069 116.81229)
		(end 153.39842 116.81229)
		(width 0.2032)
		(layer "F.Cu")
		(net "ANT1_IO_OUT")
	)
	(via
		(at 154.9857 114.8582)
		(size 0.4064)
		(drill 0.2032)
		(layers "F.Cu" "B.Cu")
		(tenting
			(front yes)
			(back yes)
		)
		(net "ANT1_IO_OUT")
	)
	(via
		(at 89.1681 108.8582)
		(size 0.4064)
		(drill 0.2032)
		(layers "F.Cu" "B.Cu")
		(tenting
			(front yes)
			(back yes)
		)
		(net "ANT1_IO_OUT")
	)
	(via
		(at 85.11291 98.10747)
		(size 0.4064)
		(drill 0.2032)
		(layers "F.Cu" "B.Cu")
		(tenting
			(front yes)
			(back yes)
		)
		(net "ANT1_IO_OUT")
	)
	(segment
		(start 85.11291 98.10747)
		(end 89.1341 102.12866)
		(width 0.2032)
		(layer "In2.Cu")
		(net "ANT1_IO_OUT")
	)
	(segment
		(start 89.1341 108.8242)
		(end 89.1341 102.12866)
		(width 0.2032)
		(layer "In2.Cu")
		(net "ANT1_IO_OUT")
	)
	(segment
		(start 89.1341 108.8242)
		(end 89.1681 108.8582)
		(width 0.2032)
		(layer "In2.Cu")
		(net "ANT1_IO_OUT")
	)
	(segment
		(start 154.9857 114.8582)
		(end 154.9937 114.8582)
		(width 0.2032)
		(layer "In3.Cu")
		(net "ANT1_IO_OUT")
	)
	(segment
		(start 89.16511 108.85521)
		(end 89.1681 108.8582)
		(width 0.2032)
		(layer "In3.Cu")
		(net "ANT1_IO_OUT")
	)
	(segment
		(start 89.16511 108.57719)
		(end 90.9439 106.7984)
		(width 0.2032)
		(layer "In3.Cu")
		(net "ANT1_IO_OUT")
	)
	(segment
		(start 154.9937 114.8582)
		(end 155.4629 114.389)
		(width 0.2032)
		(layer "In3.Cu")
		(net "ANT1_IO_OUT")
	)
	(segment
		(start 151.65739 106.7984)
		(end 155.4629 110.60391)
		(width 0.2032)
		(layer "In3.Cu")
		(net "ANT1_IO_OUT")
	)
	(segment
		(start 90.9439 106.7984)
		(end 151.65739 106.7984)
		(width 0.2032)
		(layer "In3.Cu")
		(net "ANT1_IO_OUT")
	)
	(segment
		(start 155.4629 114.389)
		(end 155.4629 110.60391)
		(width 0.2032)
		(layer "In3.Cu")
		(net "ANT1_IO_OUT")
	)
	(segment
		(start 89.16511 108.85521)
		(end 89.16511 108.57719)
		(width 0.2032)
		(layer "In3.Cu")
		(net "ANT1_IO_OUT")
	)
	(segment
		(start 82.8761 98.1162)
		(end 83.1261 98.3662)
		(width 0.2032)
		(layer "F.Cu")
		(net "ANT1_IO_IN")
	)
	(segment
		(start 80.5511 95.8662)
		(end 81.6261 95.8662)
		(width 0.2032)
		(layer "F.Cu")
		(net "ANT1_IO_IN")
	)
	(segment
		(start 81.6261 95.8662)
		(end 82.1261 96.3662)
		(width 0.2032)
		(layer "F.Cu")
		(net "ANT1_IO_IN")
	)
	(segment
		(start 154.33722 115.37205)
		(end 154.33722 114.90508)
		(width 0.2032)
		(layer "F.Cu")
		(net "ANT1_IO_IN")
	)
	(segment
		(start 154.33722 114.90508)
		(end 154.3761 114.8662)
		(width 0.2032)
		(layer "F.Cu")
		(net "ANT1_IO_IN")
	)
	(segment
		(start 83.1261 100.3662)
		(end 83.6261 100.8662)
		(width 0.2032)
		(layer "F.Cu")
		(net "ANT1_IO_IN")
	)
	(segment
		(start 151.74069 116.31242)
		(end 153.39685 116.31242)
		(width 0.2032)
		(layer "F.Cu")
		(net "ANT1_IO_IN")
	)
	(segment
		(start 82.1261 98.4162)
		(end 82.1261 98.4146)
		(width 0.2032)
		(layer "F.Cu")
		(net "ANT1_IO_IN")
	)
	(segment
		(start 153.39685 116.31242)
		(end 154.33722 115.37205)
		(width 0.2032)
		(layer "F.Cu")
		(net "ANT1_IO_IN")
	)
	(segment
		(start 83.1261 100.3662)
		(end 83.1261 98.3662)
		(width 0.2032)
		(layer "F.Cu")
		(net "ANT1_IO_IN")
	)
	(segment
		(start 82.1261 98.1662)
		(end 82.1761 98.1162)
		(width 0.2032)
		(layer "F.Cu")
		(net "ANT1_IO_IN")
	)
	(segment
		(start 82.1261 98.1162)
		(end 82.8761 98.1162)
		(width 0.2032)
		(layer "F.Cu")
		(net "ANT1_IO_IN")
	)
	(segment
		(start 82.1261 98.1162)
		(end 82.1261 96.3662)
		(width 0.2032)
		(layer "F.Cu")
		(net "ANT1_IO_IN")
	)
	(via
		(at 88.8761 109.6162)
		(size 0.4064)
		(drill 0.2032)
		(layers "F.Cu" "B.Cu")
		(tenting
			(front yes)
			(back yes)
		)
		(net "ANT1_IO_IN")
	)
	(via
		(at 83.6261 100.8662)
		(size 0.4064)
		(drill 0.2032)
		(layers "F.Cu" "B.Cu")
		(tenting
			(front yes)
			(back yes)
		)
		(net "ANT1_IO_IN")
	)
	(via
		(at 154.3761 114.8662)
		(size 0.4064)
		(drill 0.2032)
		(layers "F.Cu" "B.Cu")
		(tenting
			(front yes)
			(back yes)
		)
		(net "ANT1_IO_IN")
	)
	(segment
		(start 87.3761 108.1162)
		(end 88.8761 109.6162)
		(width 0.2032)
		(layer "In2.Cu")
		(net "ANT1_IO_IN")
	)
	(segment
		(start 83.6261 100.8662)
		(end 86.1261 100.8662)
		(width 0.2032)
		(layer "In2.Cu")
		(net "ANT1_IO_IN")
	)
	(segment
		(start 87.3761 108.1162)
		(end 87.3761 102.1162)
		(width 0.2032)
		(layer "In2.Cu")
		(net "ANT1_IO_IN")
	)
	(segment
		(start 86.1261 100.8662)
		(end 87.3761 102.1162)
		(width 0.2032)
		(layer "In2.Cu")
		(net "ANT1_IO_IN")
	)
	(segment
		(start 151.79416 106.4682)
		(end 155.7959 110.46994)
		(width 0.2032)
		(layer "In3.Cu")
		(net "ANT1_IO_IN")
	)
	(segment
		(start 154.77528 115.3662)
		(end 155.19612 115.3662)
		(width 0.2032)
		(layer "In3.Cu")
		(net "ANT1_IO_IN")
	)
	(segment
		(start 154.3761 114.92119)
		(end 154.3761 114.8662)
		(width 0.2032)
		(layer "In3.Cu")
		(net "ANT1_IO_IN")
	)
	(segment
		(start 88.6261 109.31121)
		(end 88.8761 109.56121)
		(width 0.2032)
		(layer "In3.Cu")
		(net "ANT1_IO_IN")
	)
	(segment
		(start 155.19612 115.3662)
		(end 155.7959 114.76642)
		(width 0.2032)
		(layer "In3.Cu")
		(net "ANT1_IO_IN")
	)
	(segment
		(start 88.8761 109.6162)
		(end 88.8761 109.56121)
		(width 0.2032)
		(layer "In3.Cu")
		(net "ANT1_IO_IN")
	)
	(segment
		(start 155.7959 114.76642)
		(end 155.7959 110.46994)
		(width 0.2032)
		(layer "In3.Cu")
		(net "ANT1_IO_IN")
	)
	(segment
		(start 88.6261 109.31121)
		(end 88.6261 108.55014)
		(width 0.2032)
		(layer "In3.Cu")
		(net "ANT1_IO_IN")
	)
	(segment
		(start 154.3761 114.92119)
		(end 154.4777 115.02279)
		(width 0.2032)
		(layer "In3.Cu")
		(net "ANT1_IO_IN")
	)
	(segment
		(start 88.6261 108.55014)
		(end 90.70804 106.4682)
		(width 0.2032)
		(layer "In3.Cu")
		(net "ANT1_IO_IN")
	)
	(segment
		(start 90.70804 106.4682)
		(end 151.79416 106.4682)
		(width 0.2032)
		(layer "In3.Cu")
		(net "ANT1_IO_IN")
	)
	(segment
		(start 154.4777 115.06862)
		(end 154.4777 115.02279)
		(width 0.2032)
		(layer "In3.Cu")
		(net "ANT1_IO_IN")
	)
	(segment
		(start 154.4777 115.06862)
		(end 154.77528 115.3662)
		(width 0.2032)
		(layer "In3.Cu")
		(net "ANT1_IO_IN")
	)
	(segment
		(start 85.87617 97.3742)
		(end 85.87617 96.11627)
		(width 0.2032)
		(layer "F.Cu")
		(net "ANT1_IN")
	)
	(segment
		(start 167.56983 99.52073)
		(end 167.56983 99.26251)
		(width 0.2032)
		(layer "F.Cu")
		(net "ANT1_IN")
	)
	(segment
		(start 167.82575 99.00659)
		(end 167.82575 97.91825)
		(width 0.2032)
		(layer "F.Cu")
		(net "ANT1_IN")
	)
	(segment
		(start 167.53095 99.55961)
		(end 167.56983 99.52073)
		(width 0.2032)
		(layer "F.Cu")
		(net "ANT1_IN")
	)
	(segment
		(start 167.56983 99.26251)
		(end 167.82575 99.00659)
		(width 0.2032)
		(layer "F.Cu")
		(net "ANT1_IN")
	)
	(segment
		(start 83.7011 95.3662)
		(end 85.1261 95.3662)
		(width 0.2032)
		(layer "F.Cu")
		(net "ANT1_IN")
	)
	(segment
		(start 85.1261 95.3662)
		(end 85.87617 96.11627)
		(width 0.2032)
		(layer "F.Cu")
		(net "ANT1_IN")
	)
	(via
		(at 85.87617 97.3742)
		(size 0.4064)
		(drill 0.2032)
		(layers "F.Cu" "B.Cu")
		(tenting
			(front yes)
			(back yes)
		)
		(net "ANT1_IN")
	)
	(via
		(at 167.53095 99.55961)
		(size 0.4064)
		(drill 0.2032)
		(layers "F.Cu" "B.Cu")
		(tenting
			(front yes)
			(back yes)
		)
		(net "ANT1_IN")
	)
	(segment
		(start 89.46357 100.9616)
		(end 166.15035 100.9616)
		(width 0.2032)
		(layer "In3.Cu")
		(net "ANT1_IN")
	)
	(segment
		(start 167.53095 99.581)
		(end 167.53095 99.55961)
		(width 0.2032)
		(layer "In3.Cu")
		(net "ANT1_IN")
	)
	(segment
		(start 85.87617 97.3742)
		(end 89.46357 100.9616)
		(width 0.2032)
		(layer "In3.Cu")
		(net "ANT1_IN")
	)
	(segment
		(start 166.15035 100.9616)
		(end 167.53095 99.581)
		(width 0.2032)
		(layer "In3.Cu")
		(net "ANT1_IN")
	)
	(segment
		(start 180.01334 99.67989)
		(end 180.01334 99.62896)
		(width 0.2032)
		(layer "F.Cu")
		(net "UART1_TXD")
	)
	(segment
		(start 180.32844 99.31386)
		(end 180.32844 97.90213)
		(width 0.2032)
		(layer "F.Cu")
		(net "UART1_TXD")
	)
	(segment
		(start 220.60557 77.93673)
		(end 220.60557 76.52607)
		(width 0.2032)
		(layer "F.Cu")
		(net "UART1_TXD")
	)
	(segment
		(start 220.3261 76.2466)
		(end 220.3261 76.0162)
		(width 0.2032)
		(layer "F.Cu")
		(net "UART1_TXD")
	)
	(segment
		(start 180.01334 99.62896)
		(end 180.32844 99.31386)
		(width 0.2032)
		(layer "F.Cu")
		(net "UART1_TXD")
	)
	(segment
		(start 220.60557 76.52607)
		(end 220.60557 76.52607)
		(width 0.2032)
		(layer "F.Cu")
		(net "UART1_TXD")
	)
	(segment
		(start 220.5261 78.0162)
		(end 220.60557 77.93673)
		(width 0.2032)
		(layer "F.Cu")
		(net "UART1_TXD")
	)
	(segment
		(start 218.5261 75.9162)
		(end 220.2261 75.9162)
		(width 0.2032)
		(layer "F.Cu")
		(net "UART1_TXD")
	)
	(segment
		(start 220.2261 75.9162)
		(end 220.3261 76.0162)
		(width 0.2032)
		(layer "F.Cu")
		(net "UART1_TXD")
	)
	(segment
		(start 220.3261 76.2466)
		(end 220.60557 76.52607)
		(width 0.2032)
		(layer "F.Cu")
		(net "UART1_TXD")
	)
	(via
		(at 220.3261 76.0162)
		(size 0.4064)
		(drill 0.2032)
		(layers "F.Cu" "B.Cu")
		(net "UART1_TXD")
	)
	(via
		(at 180.01334 99.67989)
		(size 0.4064)
		(drill 0.2032)
		(layers "F.Cu" "B.Cu")
		(net "UART1_TXD")
	)
	(via
		(at 184.2702 99.1162)
		(size 0.4064)
		(drill 0.2032)
		(layers "F.Cu" "B.Cu")
		(net "UART1_TXD")
	)
	(segment
		(start 181.07703 98.6162)
		(end 182.8261 98.6162)
		(width 0.2032)
		(layer "B.Cu")
		(net "UART1_TXD")
	)
	(segment
		(start 180.01334 99.67989)
		(end 181.07703 98.6162)
		(width 0.2032)
		(layer "B.Cu")
		(net "UART1_TXD")
	)
	(segment
		(start 183.3261 99.1162)
		(end 184.2702 99.1162)
		(width 0.2032)
		(layer "B.Cu")
		(net "UART1_TXD")
	)
	(segment
		(start 182.8261 98.6162)
		(end 183.3261 99.1162)
		(width 0.2032)
		(layer "B.Cu")
		(net "UART1_TXD")
	)
	(segment
		(start 195.5261 90.2162)
		(end 201.7261 90.2162)
		(width 0.2032)
		(layer "In3.Cu")
		(net "UART1_TXD")
	)
	(segment
		(start 184.2702 99.1162)
		(end 186.6261 99.1162)
		(width 0.2032)
		(layer "In3.Cu")
		(net "UART1_TXD")
	)
	(segment
		(start 210.5261 92.1162)
		(end 219.3261 83.3162)
		(width 0.2032)
		(layer "In3.Cu")
		(net "UART1_TXD")
	)
	(segment
		(start 203.6261 92.1162)
		(end 210.5261 92.1162)
		(width 0.2032)
		(layer "In3.Cu")
		(net "UART1_TXD")
	)
	(segment
		(start 186.6261 99.1162)
		(end 195.5261 90.2162)
		(width 0.2032)
		(layer "In3.Cu")
		(net "UART1_TXD")
	)
	(segment
		(start 201.7261 90.2162)
		(end 203.6261 92.1162)
		(width 0.2032)
		(layer "In3.Cu")
		(net "UART1_TXD")
	)
	(segment
		(start 219.3261 80.0162)
		(end 220.3261 79.0162)
		(width 0.2032)
		(layer "In3.Cu")
		(net "UART1_TXD")
	)
	(segment
		(start 219.3261 83.3162)
		(end 219.3261 80.0162)
		(width 0.2032)
		(layer "In3.Cu")
		(net "UART1_TXD")
	)
	(segment
		(start 220.3261 79.0162)
		(end 220.3261 76.0162)
		(width 0.2032)
		(layer "In3.Cu")
		(net "UART1_TXD")
	)
	(segment
		(start 217.5761 80.8162)
		(end 218.1261 80.8162)
		(width 0.2032)
		(layer "F.Cu")
		(net "UART1_RXD")
	)
	(segment
		(start 218.4261 81.1162)
		(end 220.26166 81.1162)
		(width 0.2032)
		(layer "F.Cu")
		(net "UART1_RXD")
	)
	(segment
		(start 220.5261 80.2047)
		(end 220.5261 79.6162)
		(width 0.2032)
		(layer "F.Cu")
		(net "UART1_RXD")
	)
	(segment
		(start 218.1261 80.8162)
		(end 218.4261 81.1162)
		(width 0.2032)
		(layer "F.Cu")
		(net "UART1_RXD")
	)
	(segment
		(start 181.82831 99.91841)
		(end 182.1261 100.2162)
		(width 0.2032)
		(layer "F.Cu")
		(net "UART1_RXD")
	)
	(segment
		(start 220.5261 80.2047)
		(end 220.84963 80.52823)
		(width 0.2032)
		(layer "F.Cu")
		(net "UART1_RXD")
	)
	(segment
		(start 220.26166 81.1162)
		(end 220.84963 80.52823)
		(width 0.2032)
		(layer "F.Cu")
		(net "UART1_RXD")
	)
	(segment
		(start 182.1261 100.2162)
		(end 183.2261 100.2162)
		(width 0.2032)
		(layer "F.Cu")
		(net "UART1_RXD")
	)
	(segment
		(start 183.2261 100.2162)
		(end 183.5261 99.9162)
		(width 0.2032)
		(layer "F.Cu")
		(net "UART1_RXD")
	)
	(segment
		(start 181.82831 99.91841)
		(end 181.82831 97.90213)
		(width 0.2032)
		(layer "F.Cu")
		(net "UART1_RXD")
	)
	(via
		(at 183.5261 99.9162)
		(size 0.4064)
		(drill 0.2032)
		(layers "F.Cu" "B.Cu")
		(net "UART1_RXD")
	)
	(via
		(at 220.84963 80.52823)
		(size 0.4064)
		(drill 0.2032)
		(layers "F.Cu" "B.Cu")
		(net "UART1_RXD")
	)
	(segment
		(start 202.11435 91.1162)
		(end 203.61435 92.6162)
		(width 0.2032)
		(layer "In3.Cu")
		(net "UART1_RXD")
	)
	(segment
		(start 220.84963 82.49267)
		(end 220.84963 80.52823)
		(width 0.2032)
		(layer "In3.Cu")
		(net "UART1_RXD")
	)
	(segment
		(start 186.5261 99.9162)
		(end 195.1261 91.3162)
		(width 0.2032)
		(layer "In3.Cu")
		(net "UART1_RXD")
	)
	(segment
		(start 200.6261 91.3162)
		(end 200.8261 91.1162)
		(width 0.2032)
		(layer "In3.Cu")
		(net "UART1_RXD")
	)
	(segment
		(start 183.5261 99.9162)
		(end 186.5261 99.9162)
		(width 0.2032)
		(layer "In3.Cu")
		(net "UART1_RXD")
	)
	(segment
		(start 203.61435 92.6162)
		(end 210.7261 92.6162)
		(width 0.2032)
		(layer "In3.Cu")
		(net "UART1_RXD")
	)
	(segment
		(start 200.8261 91.1162)
		(end 202.11435 91.1162)
		(width 0.2032)
		(layer "In3.Cu")
		(net "UART1_RXD")
	)
	(segment
		(start 210.7261 92.6162)
		(end 220.84963 82.49267)
		(width 0.2032)
		(layer "In3.Cu")
		(net "UART1_RXD")
	)
	(segment
		(start 195.1261 91.3162)
		(end 200.6261 91.3162)
		(width 0.2032)
		(layer "In3.Cu")
		(net "UART1_RXD")
	)
	(segment
		(start 73.3761 54.9412)
		(end 73.3761 52.8662)
		(width 0.2032)
		(layer "F.Cu")
		(net "NetD10_1")
	)
	(segment
		(start 71.6261 54.9412)
		(end 71.6261 52.8662)
		(width 0.2032)
		(layer "F.Cu")
		(net "NetD9_1")
	)
	(segment
		(start 228.0711 60.6786)
		(end 230.3761 60.6786)
		(width 0.2032)
		(layer "F.Cu")
		(net "GPS2_TX")
	)
	(segment
		(start 213.2261 77.5162)
		(end 213.2261 76.4151)
		(width 0.2032)
		(layer "F.Cu")
		(net "GPS2_TX")
	)
	(segment
		(start 214.44193 74.70037)
		(end 214.82187 74.70037)
		(width 0.2032)
		(layer "F.Cu")
		(net "GPS2_TX")
	)
	(segment
		(start 213.2261 75.9162)
		(end 214.44193 74.70037)
		(width 0.2032)
		(layer "F.Cu")
		(net "GPS2_TX")
	)
	(segment
		(start 213.2261 76.4151)
		(end 213.2261 75.9162)
		(width 0.2032)
		(layer "F.Cu")
		(net "GPS2_TX")
	)
	(segment
		(start 212.6761 77.5162)
		(end 213.2261 77.5162)
		(width 0.2032)
		(layer "F.Cu")
		(net "GPS2_TX")
	)
	(segment
		(start 211.7761 75.6162)
		(end 212.4272 75.6162)
		(width 0.2032)
		(layer "F.Cu")
		(net "GPS2_TX")
	)
	(segment
		(start 212.1761 78.0162)
		(end 212.6761 77.5162)
		(width 0.2032)
		(layer "F.Cu")
		(net "GPS2_TX")
	)
	(segment
		(start 212.4272 75.6162)
		(end 213.2261 76.4151)
		(width 0.2032)
		(layer "F.Cu")
		(net "GPS2_TX")
	)
	(via
		(at 230.3761 60.6786)
		(size 0.4064)
		(drill 0.2032)
		(layers "F.Cu" "B.Cu")
		(tenting
			(front yes)
			(back yes)
		)
		(net "GPS2_TX")
	)
	(via
		(at 214.82187 74.70037)
		(size 0.4064)
		(drill 0.2032)
		(layers "F.Cu" "B.Cu")
		(net "GPS2_TX")
	)
	(segment
		(start 226.8637 60.6786)
		(end 230.3761 60.6786)
		(width 0.2032)
		(layer "B.Cu")
		(net "GPS2_TX")
	)
	(segment
		(start 214.82187 72.72043)
		(end 226.8637 60.6786)
		(width 0.2032)
		(layer "B.Cu")
		(net "GPS2_TX")
	)
	(segment
		(start 214.82187 74.70037)
		(end 214.82187 72.72043)
		(width 0.2032)
		(layer "B.Cu")
		(net "GPS2_TX")
	)
	(segment
		(start 154.0165 122.6882)
		(end 154.18483 122.6882)
		(width 0.2032)
		(layer "F.Cu")
		(net "GPS2_TP2")
	)
	(segment
		(start 154.18514 122.68851)
		(end 154.58722 122.68851)
		(width 0.2032)
		(layer "F.Cu")
		(net "GPS2_TP2")
	)
	(segment
		(start 153.89242 122.81228)
		(end 154.0165 122.6882)
		(width 0.2032)
		(layer "F.Cu")
		(net "GPS2_TP2")
	)
	(segment
		(start 228.0711 64.6786)
		(end 230.3761 64.6786)
		(width 0.2032)
		(layer "F.Cu")
		(net "GPS2_TP2")
	)
	(segment
		(start 151.74069 122.81228)
		(end 153.89242 122.81228)
		(width 0.2032)
		(layer "F.Cu")
		(net "GPS2_TP2")
	)
	(segment
		(start 154.58722 122.68851)
		(end 154.6261 122.72739)
		(width 0.2032)
		(layer "F.Cu")
		(net "GPS2_TP2")
	)
	(segment
		(start 154.18483 122.6882)
		(end 154.18514 122.68851)
		(width 0.2032)
		(layer "F.Cu")
		(net "GPS2_TP2")
	)
	(via
		(at 154.6261 122.72739)
		(size 0.4064)
		(drill 0.2032)
		(layers "F.Cu" "B.Cu")
		(tenting
			(front yes)
			(back yes)
		)
		(net "GPS2_TP2")
	)
	(via
		(at 230.3761 64.6786)
		(size 0.4064)
		(drill 0.2032)
		(layers "F.Cu" "B.Cu")
		(tenting
			(front yes)
			(back yes)
		)
		(net "GPS2_TP2")
	)
	(segment
		(start 223.34216 64.6786)
		(end 230.3761 64.6786)
		(width 0.2032)
		(layer "In2.Cu")
		(net "GPS2_TP2")
	)
	(segment
		(start 168.3761 110.3286)
		(end 177.69216 110.3286)
		(width 0.2032)
		(layer "In2.Cu")
		(net "GPS2_TP2")
	)
	(segment
		(start 154.6261 122.72739)
		(end 155.97731 122.72739)
		(width 0.2032)
		(layer "In2.Cu")
		(net "GPS2_TP2")
	)
	(segment
		(start 177.69216 110.3286)
		(end 223.34216 64.6786)
		(width 0.2032)
		(layer "In2.Cu")
		(net "GPS2_TP2")
	)
	(segment
		(start 155.97731 122.72739)
		(end 168.3761 110.3286)
		(width 0.2032)
		(layer "In2.Cu")
		(net "GPS2_TP2")
	)
	(segment
		(start 151.74878 123.3205)
		(end 154.60961 123.3205)
		(width 0.2032)
		(layer "F.Cu")
		(net "GPS2_TP1")
	)
	(segment
		(start 151.74069 123.31241)
		(end 151.74878 123.3205)
		(width 0.2032)
		(layer "F.Cu")
		(net "GPS2_TP1")
	)
	(segment
		(start 154.60961 123.3205)
		(end 154.6261 123.33699)
		(width 0.2032)
		(layer "F.Cu")
		(net "GPS2_TP1")
	)
	(segment
		(start 221.8761 62.6786)
		(end 223.6261 62.6786)
		(width 0.2032)
		(layer "F.Cu")
		(net "GPS2_TP1")
	)
	(via
		(at 154.6261 123.33699)
		(size 0.4064)
		(drill 0.2032)
		(layers "F.Cu" "B.Cu")
		(tenting
			(front yes)
			(back yes)
		)
		(net "GPS2_TP1")
	)
	(via
		(at 221.8761 67.3286)
		(size 0.4064)
		(drill 0.2032)
		(layers "F.Cu" "B.Cu")
		(tenting
			(front yes)
			(back yes)
		)
		(net "GPS2_TP1")
	)
	(via
		(at 221.8761 62.6786)
		(size 0.4064)
		(drill 0.2032)
		(layers "F.Cu" "B.Cu")
		(tenting
			(front yes)
			(back yes)
		)
		(net "GPS2_TP1")
	)
	(segment
		(start 154.6261 123.33699)
		(end 155.83468 123.33699)
		(width 0.2032)
		(layer "In2.Cu")
		(net "GPS2_TP1")
	)
	(segment
		(start 155.83468 123.33699)
		(end 168.34307 110.8286)
		(width 0.2032)
		(layer "In2.Cu")
		(net "GPS2_TP1")
	)
	(segment
		(start 168.34307 110.8286)
		(end 177.65913 110.8286)
		(width 0.2032)
		(layer "In2.Cu")
		(net "GPS2_TP1")
	)
	(segment
		(start 177.65913 110.8286)
		(end 221.15913 67.3286)
		(width 0.2032)
		(layer "In2.Cu")
		(net "GPS2_TP1")
	)
	(segment
		(start 221.15913 67.3286)
		(end 221.8761 67.3286)
		(width 0.2032)
		(layer "In2.Cu")
		(net "GPS2_TP1")
	)
	(segment
		(start 221.8761 67.3286)
		(end 221.8761 62.6786)
		(width 0.2032)
		(layer "In3.Cu")
		(net "GPS2_TP1")
	)
	(segment
		(start 210.7261 82.1162)
		(end 211.4261 81.4162)
		(width 0.2032)
		(layer "F.Cu")
		(net "GPS2_RX")
	)
	(segment
		(start 211.4261 81.4162)
		(end 211.91258 81.4162)
		(width 0.2032)
		(layer "F.Cu")
		(net "GPS2_RX")
	)
	(segment
		(start 212.1761 80.35959)
		(end 212.1761 79.6162)
		(width 0.2032)
		(layer "F.Cu")
		(net "GPS2_RX")
	)
	(segment
		(start 228.0711 62.6786)
		(end 230.3761 62.6786)
		(width 0.2032)
		(layer "F.Cu")
		(net "GPS2_RX")
	)
	(segment
		(start 209.8261 82.1162)
		(end 210.7261 82.1162)
		(width 0.2032)
		(layer "F.Cu")
		(net "GPS2_RX")
	)
	(segment
		(start 212.1761 80.35959)
		(end 212.57265 80.75614)
		(width 0.2032)
		(layer "F.Cu")
		(net "GPS2_RX")
	)
	(segment
		(start 211.91258 81.4162)
		(end 212.57265 80.75614)
		(width 0.2032)
		(layer "F.Cu")
		(net "GPS2_RX")
	)
	(via
		(at 230.3761 62.6786)
		(size 0.4064)
		(drill 0.2032)
		(layers "F.Cu" "B.Cu")
		(tenting
			(front yes)
			(back yes)
		)
		(net "GPS2_RX")
	)
	(via
		(at 212.57265 80.75614)
		(size 0.4064)
		(drill 0.2032)
		(layers "F.Cu" "B.Cu")
		(net "GPS2_RX")
	)
	(segment
		(start 215.3261 79.5162)
		(end 216.5261 78.3162)
		(width 0.2032)
		(layer "B.Cu")
		(net "GPS2_RX")
	)
	(segment
		(start 222.8261 70.2286)
		(end 230.3761 62.6786)
		(width 0.2032)
		(layer "B.Cu")
		(net "GPS2_RX")
	)
	(segment
		(start 214.6261 79.5162)
		(end 215.3261 79.5162)
		(width 0.2032)
		(layer "B.Cu")
		(net "GPS2_RX")
	)
	(segment
		(start 213.38616 80.75614)
		(end 214.6261 79.5162)
		(width 0.2032)
		(layer "B.Cu")
		(net "GPS2_RX")
	)
	(segment
		(start 212.57265 80.75614)
		(end 213.38616 80.75614)
		(width 0.2032)
		(layer "B.Cu")
		(net "GPS2_RX")
	)
	(segment
		(start 218.7261 72.3162)
		(end 222.1261 72.3162)
		(width 0.2032)
		(layer "B.Cu")
		(net "GPS2_RX")
	)
	(segment
		(start 222.8261 71.6162)
		(end 222.8261 70.2286)
		(width 0.2032)
		(layer "B.Cu")
		(net "GPS2_RX")
	)
	(segment
		(start 222.1261 72.3162)
		(end 222.8261 71.6162)
		(width 0.2032)
		(layer "B.Cu")
		(net "GPS2_RX")
	)
	(segment
		(start 216.5261 74.5162)
		(end 218.7261 72.3162)
		(width 0.2032)
		(layer "B.Cu")
		(net "GPS2_RX")
	)
	(segment
		(start 216.5261 78.3162)
		(end 216.5261 74.5162)
		(width 0.2032)
		(layer "B.Cu")
		(net "GPS2_RX")
	)
	(segment
		(start 151.74069 121.81228)
		(end 154.47022 121.81228)
		(width 0.2032)
		(layer "F.Cu")
		(net "GPS2_RST")
	)
	(segment
		(start 221.8761 60.6786)
		(end 223.6261 60.6786)
		(width 0.2032)
		(layer "F.Cu")
		(net "GPS2_RST")
	)
	(segment
		(start 154.47022 121.81228)
		(end 154.57112 121.71139)
		(width 0.2032)
		(layer "F.Cu")
		(net "GPS2_RST")
	)
	(segment
		(start 154.57112 121.71139)
		(end 154.6261 121.71139)
		(width 0.2032)
		(layer "F.Cu")
		(net "GPS2_RST")
	)
	(via
		(at 221.8761 60.6786)
		(size 0.4064)
		(drill 0.2032)
		(layers "F.Cu" "B.Cu")
		(tenting
			(front yes)
			(back yes)
		)
		(net "GPS2_RST")
	)
	(via
		(at 154.6261 121.71139)
		(size 0.4064)
		(drill 0.2032)
		(layers "F.Cu" "B.Cu")
		(tenting
			(front yes)
			(back yes)
		)
		(net "GPS2_RST")
	)
	(segment
		(start 220.1261 62.4286)
		(end 221.8761 60.6786)
		(width 0.2032)
		(layer "In2.Cu")
		(net "GPS2_RST")
	)
	(segment
		(start 154.6261 121.71139)
		(end 155.99331 121.71139)
		(width 0.2032)
		(layer "In2.Cu")
		(net "GPS2_RST")
	)
	(segment
		(start 220.1261 66.96071)
		(end 220.1261 62.4286)
		(width 0.2032)
		(layer "In2.Cu")
		(net "GPS2_RST")
	)
	(segment
		(start 177.50821 109.5786)
		(end 220.1261 66.96071)
		(width 0.2032)
		(layer "In2.Cu")
		(net "GPS2_RST")
	)
	(segment
		(start 155.99331 121.71139)
		(end 168.1261 109.5786)
		(width 0.2032)
		(layer "In2.Cu")
		(net "GPS2_RST")
	)
	(segment
		(start 168.1261 109.5786)
		(end 177.50821 109.5786)
		(width 0.2032)
		(layer "In2.Cu")
		(net "GPS2_RST")
	)
	(segment
		(start 78.3261 95.1162)
		(end 78.4261 95.2162)
		(width 0.2032)
		(layer "F.Cu")
		(net "NetR25_1")
	)
	(segment
		(start 79.6261 95.1162)
		(end 79.8761 95.3662)
		(width 0.2032)
		(layer "F.Cu")
		(net "NetR25_1")
	)
	(segment
		(start 79.8761 94.8662)
		(end 80.5511 94.8662)
		(width 0.2032)
		(layer "F.Cu")
		(net "NetR25_1")
	)
	(segment
		(start 79.6261 95.1162)
		(end 79.8761 94.8662)
		(width 0.2032)
		(layer "F.Cu")
		(net "NetR25_1")
	)
	(segment
		(start 78.3261 95.1162)
		(end 79.6261 95.1162)
		(width 0.2032)
		(layer "F.Cu")
		(net "NetR25_1")
	)
	(segment
		(start 79.8761 95.3662)
		(end 80.5511 95.3662)
		(width 0.2032)
		(layer "F.Cu")
		(net "NetR25_1")
	)
	(segment
		(start 239.4761 66.4662)
		(end 240.0261 66.4662)
		(width 0.2032)
		(layer "F.Cu")
		(net "NetR13_1")
	)
	(segment
		(start 238.3511 67.2007)
		(end 238.7416 67.2007)
		(width 0.2032)
		(layer "F.Cu")
		(net "NetR13_1")
	)
	(segment
		(start 238.7416 67.2007)
		(end 239.4761 66.4662)
		(width 0.2032)
		(layer "F.Cu")
		(net "NetR13_1")
	)
	(segment
		(start 138.9261 84.0586)
		(end 138.9361 84.0686)
		(width 0.2032)
		(layer "F.Cu")
		(net "MAC_PPS_IN1-")
	)
	(segment
		(start 136.54282 113.43292)
		(end 137.66107 113.43292)
		(width 0.2032)
		(layer "F.Cu")
		(net "MAC_PPS_IN1-")
	)
	(segment
		(start 138.9361 84.0686)
		(end 141.6161 84.0686)
		(width 0.2032)
		(layer "F.Cu")
		(net "MAC_PPS_IN1-")
	)
	(segment
		(start 136.3261 113.2162)
		(end 136.54282 113.43292)
		(width 0.2032)
		(layer "F.Cu")
		(net "MAC_PPS_IN1-")
	)
	(segment
		(start 141.6161 84.0686)
		(end 141.6261 84.0786)
		(width 0.2032)
		(layer "F.Cu")
		(net "MAC_PPS_IN1-")
	)
	(via
		(at 136.3261 113.2162)
		(size 0.4064)
		(drill 0.2032)
		(layers "F.Cu" "B.Cu")
		(tenting
			(front yes)
			(back yes)
		)
		(net "MAC_PPS_IN1-")
	)
	(via
		(at 141.6161 84.0686)
		(size 0.4064)
		(drill 0.2032)
		(layers "F.Cu" "B.Cu")
		(tenting
			(front yes)
			(back yes)
		)
		(net "MAC_PPS_IN1-")
	)
	(segment
		(start 142.3261 109.68125)
		(end 142.3261 90.4162)
		(width 0.2032)
		(layer "In2.Cu")
		(net "MAC_PPS_IN1-")
	)
	(segment
		(start 136.3261 113.2162)
		(end 138.79114 113.2162)
		(width 0.2032)
		(layer "In2.Cu")
		(net "MAC_PPS_IN1-")
	)
	(segment
		(start 143.8261 89.3162)
		(end 143.8261 84.9162)
		(width 0.2032)
		(layer "In2.Cu")
		(net "MAC_PPS_IN1-")
	)
	(segment
		(start 141.6161 84.0686)
		(end 142.9785 84.0686)
		(width 0.2032)
		(layer "In2.Cu")
		(net "MAC_PPS_IN1-")
	)
	(segment
		(start 142.9261 89.8162)
		(end 143.3261 89.8162)
		(width 0.2032)
		(layer "In2.Cu")
		(net "MAC_PPS_IN1-")
	)
	(arc
		(start 143.8261 89.3162)
		(mid 143.679653 89.669753)
		(end 143.3261 89.8162)
		(width 0.2032)
		(layer "In2.Cu")
		(net "MAC_PPS_IN1-")
	)
	(arc
		(start 142.9785 84.0686)
		(mid 143.577844 84.316856)
		(end 143.8261 84.9162)
		(width 0.2032)
		(layer "In2.Cu")
		(net "MAC_PPS_IN1-")
	)
	(arc
		(start 142.3261 90.4162)
		(mid 142.501836 89.991936)
		(end 142.9261 89.8162)
		(width 0.2032)
		(layer "In2.Cu")
		(net "MAC_PPS_IN1-")
	)
	(arc
		(start 142.32609 109.68125)
		(mid 141.290727 112.180837)
		(end 138.79114 113.2162)
		(width 0.2032)
		(layer "In2.Cu")
		(net "MAC_PPS_IN1-")
	)
	(segment
		(start 99.79457 88.4162)
		(end 99.92332 88.54496)
		(width 0.2032)
		(layer "F.Cu")
		(net "MAC_FREQ_CTRL")
	)
	(segment
		(start 170.6261 101.8162)
		(end 170.6261 100.60798)
		(width 0.2032)
		(layer "F.Cu")
		(net "MAC_FREQ_CTRL")
	)
	(segment
		(start 98.7261 88.4162)
		(end 99.79457 88.4162)
		(width 0.2032)
		(layer "F.Cu")
		(net "MAC_FREQ_CTRL")
	)
	(segment
		(start 170.6261 100.60798)
		(end 170.68514 100.54894)
		(width 0.2032)
		(layer "F.Cu")
		(net "MAC_FREQ_CTRL")
	)
	(via
		(at 170.68514 100.54894)
		(size 0.4064)
		(drill 0.2032)
		(layers "F.Cu" "B.Cu")
		(net "MAC_FREQ_CTRL")
	)
	(via
		(at 99.92332 88.54496)
		(size 0.4064)
		(drill 0.2032)
		(layers "F.Cu" "B.Cu")
		(net "MAC_FREQ_CTRL")
	)
	(segment
		(start 99.92332 94.31898)
		(end 99.92332 88.54496)
		(width 0.2032)
		(layer "B.Cu")
		(net "MAC_FREQ_CTRL")
	)
	(segment
		(start 99.3261 94.9162)
		(end 99.92332 94.31898)
		(width 0.2032)
		(layer "B.Cu")
		(net "MAC_FREQ_CTRL")
	)
	(segment
		(start 170.68514 100.54894)
		(end 170.8761 100.35797)
		(width 0.2032)
		(layer "In3.Cu")
		(net "MAC_FREQ_CTRL")
	)
	(segment
		(start 137.2261 93.2162)
		(end 138.3261 92.1162)
		(width 0.2032)
		(layer "In3.Cu")
		(net "MAC_FREQ_CTRL")
	)
	(segment
		(start 99.3261 94.6162)
		(end 102.4261 91.5162)
		(width 0.2032)
		(layer "In3.Cu")
		(net "MAC_FREQ_CTRL")
	)
	(segment
		(start 170.8761 100.35797)
		(end 170.8761 99.1662)
		(width 0.2032)
		(layer "In3.Cu")
		(net "MAC_FREQ_CTRL")
	)
	(segment
		(start 99.3261 94.9162)
		(end 99.3261 94.6162)
		(width 0.2032)
		(layer "In3.Cu")
		(net "MAC_FREQ_CTRL")
	)
	(segment
		(start 168.99218 93.80879)
		(end 169.3261 94.14271)
		(width 0.2032)
		(layer "In3.Cu")
		(net "MAC_FREQ_CTRL")
	)
	(segment
		(start 169.3261 97.6162)
		(end 169.3261 94.14271)
		(width 0.2032)
		(layer "In3.Cu")
		(net "MAC_FREQ_CTRL")
	)
	(segment
		(start 108.9261 93.2162)
		(end 137.2261 93.2162)
		(width 0.2032)
		(layer "In3.Cu")
		(net "MAC_FREQ_CTRL")
	)
	(segment
		(start 102.4261 91.5162)
		(end 107.2261 91.5162)
		(width 0.2032)
		(layer "In3.Cu")
		(net "MAC_FREQ_CTRL")
	)
	(segment
		(start 169.3261 97.6162)
		(end 170.8761 99.1662)
		(width 0.2032)
		(layer "In3.Cu")
		(net "MAC_FREQ_CTRL")
	)
	(segment
		(start 138.3261 92.1162)
		(end 157.0261 92.1162)
		(width 0.2032)
		(layer "In3.Cu")
		(net "MAC_FREQ_CTRL")
	)
	(segment
		(start 107.2261 91.5162)
		(end 108.9261 93.2162)
		(width 0.2032)
		(layer "In3.Cu")
		(net "MAC_FREQ_CTRL")
	)
	(segment
		(start 158.71869 93.80879)
		(end 168.99218 93.80879)
		(width 0.2032)
		(layer "In3.Cu")
		(net "MAC_FREQ_CTRL")
	)
	(segment
		(start 157.0261 92.1162)
		(end 158.71869 93.80879)
		(width 0.2032)
		(layer "In3.Cu")
		(net "MAC_FREQ_CTRL")
	)
	(segment
		(start 122.8261 84.7912)
		(end 123.0011 84.6162)
		(width 0.2032)
		(layer "F.Cu")
		(net "FPGA_MAC_PPS_OUT-")
	)
	(segment
		(start 123.6261 84.6162)
		(end 124.62012 84.6162)
		(width 0.2032)
		(layer "F.Cu")
		(net "FPGA_MAC_PPS_OUT-")
	)
	(segment
		(start 123.6261 85.3162)
		(end 124.2011 85.8912)
		(width 0.2032)
		(layer "F.Cu")
		(net "FPGA_MAC_PPS_OUT-")
	)
	(segment
		(start 173.32598 99.62848)
		(end 173.3261 99.6286)
		(width 0.2032)
		(layer "F.Cu")
		(net "FPGA_MAC_PPS_OUT-")
	)
	(segment
		(start 173.32586 97.91825)
		(end 173.32598 97.91837)
		(width 0.2032)
		(layer "F.Cu")
		(net "FPGA_MAC_PPS_OUT-")
	)
	(segment
		(start 125.27012 85.2662)
		(end 125.4261 85.2662)
		(width 0.2032)
		(layer "F.Cu")
		(net "FPGA_MAC_PPS_OUT-")
	)
	(segment
		(start 123.0011 84.6162)
		(end 123.6261 84.6162)
		(width 0.2032)
		(layer "F.Cu")
		(net "FPGA_MAC_PPS_OUT-")
	)
	(segment
		(start 124.62012 84.6162)
		(end 125.27012 85.2662)
		(width 0.2032)
		(layer "F.Cu")
		(net "FPGA_MAC_PPS_OUT-")
	)
	(segment
		(start 123.6261 85.3162)
		(end 123.6261 84.6162)
		(width 0.2032)
		(layer "F.Cu")
		(net "FPGA_MAC_PPS_OUT-")
	)
	(segment
		(start 173.32598 99.62848)
		(end 173.32598 97.91837)
		(width 0.2032)
		(layer "F.Cu")
		(net "FPGA_MAC_PPS_OUT-")
	)
	(segment
		(start 124.2011 86.2162)
		(end 124.2011 85.8912)
		(width 0.2032)
		(layer "F.Cu")
		(net "FPGA_MAC_PPS_OUT-")
	)
	(via
		(at 123.6261 84.6162)
		(size 0.4064)
		(drill 0.2032)
		(layers "F.Cu" "B.Cu")
		(net "FPGA_MAC_PPS_OUT-")
	)
	(via
		(at 173.3261 99.6286)
		(size 0.4064)
		(drill 0.2032)
		(layers "F.Cu" "B.Cu")
		(tenting
			(front yes)
			(back yes)
		)
		(net "FPGA_MAC_PPS_OUT-")
	)
	(segment
		(start 169.2261 93.1162)
		(end 170.0261 93.9162)
		(width 0.2032)
		(layer "In3.Cu")
		(net "FPGA_MAC_PPS_OUT-")
	)
	(segment
		(start 126.2261 91.1162)
		(end 157.2261 91.1162)
		(width 0.2032)
		(layer "In3.Cu")
		(net "FPGA_MAC_PPS_OUT-")
	)
	(segment
		(start 170.0261 93.9162)
		(end 172.1261 93.9162)
		(width 0.2032)
		(layer "In3.Cu")
		(net "FPGA_MAC_PPS_OUT-")
	)
	(segment
		(start 172.1261 93.9162)
		(end 173.3261 95.1162)
		(width 0.2032)
		(layer "In3.Cu")
		(net "FPGA_MAC_PPS_OUT-")
	)
	(segment
		(start 173.3261 99.6286)
		(end 173.3261 95.1162)
		(width 0.2032)
		(layer "In3.Cu")
		(net "FPGA_MAC_PPS_OUT-")
	)
	(segment
		(start 122.9261 87.8162)
		(end 126.2261 91.1162)
		(width 0.2032)
		(layer "In3.Cu")
		(net "FPGA_MAC_PPS_OUT-")
	)
	(segment
		(start 122.9261 87.8162)
		(end 122.9261 85.3162)
		(width 0.2032)
		(layer "In3.Cu")
		(net "FPGA_MAC_PPS_OUT-")
	)
	(segment
		(start 157.2261 91.1162)
		(end 159.2261 93.1162)
		(width 0.2032)
		(layer "In3.Cu")
		(net "FPGA_MAC_PPS_OUT-")
	)
	(segment
		(start 122.9261 85.3162)
		(end 123.6261 84.6162)
		(width 0.2032)
		(layer "In3.Cu")
		(net "FPGA_MAC_PPS_OUT-")
	)
	(segment
		(start 159.2261 93.1162)
		(end 169.2261 93.1162)
		(width 0.2032)
		(layer "In3.Cu")
		(net "FPGA_MAC_PPS_OUT-")
	)
	(segment
		(start 132.1261 86.3162)
		(end 132.1261 86.3162)
		(width 0.2032)
		(layer "F.Cu")
		(net "FPGA_MAC_PPS_IN1-")
	)
	(segment
		(start 175.82573 99.47324)
		(end 175.8761 99.52361)
		(width 0.2032)
		(layer "F.Cu")
		(net "FPGA_MAC_PPS_IN1-")
	)
	(segment
		(start 175.8761 99.5786)
		(end 175.8761 99.52361)
		(width 0.2032)
		(layer "F.Cu")
		(net "FPGA_MAC_PPS_IN1-")
	)
	(segment
		(start 134.1137 85.3162)
		(end 134.1261 85.3286)
		(width 0.2032)
		(layer "F.Cu")
		(net "FPGA_MAC_PPS_IN1-")
	)
	(segment
		(start 132.1261 85.3162)
		(end 134.1137 85.3162)
		(width 0.2032)
		(layer "F.Cu")
		(net "FPGA_MAC_PPS_IN1-")
	)
	(segment
		(start 132.1261 86.3162)
		(end 132.1261 85.3162)
		(width 0.2032)
		(layer "F.Cu")
		(net "FPGA_MAC_PPS_IN1-")
	)
	(segment
		(start 175.82573 99.47324)
		(end 175.82573 97.91825)
		(width 0.2032)
		(layer "F.Cu")
		(net "FPGA_MAC_PPS_IN1-")
	)
	(via
		(at 132.1261 86.3162)
		(size 0.4064)
		(drill 0.2032)
		(layers "F.Cu" "B.Cu")
		(tenting
			(front yes)
			(back yes)
		)
		(net "FPGA_MAC_PPS_IN1-")
	)
	(via
		(at 175.8761 99.5786)
		(size 0.4064)
		(drill 0.2032)
		(layers "F.Cu" "B.Cu")
		(tenting
			(front yes)
			(back yes)
		)
		(net "FPGA_MAC_PPS_IN1-")
	)
	(segment
		(start 132.4261 87.7286)
		(end 133.0011 88.3036)
		(width 0.2032)
		(layer "In3.Cu")
		(net "FPGA_MAC_PPS_IN1-")
	)
	(segment
		(start 132.1261 86.3162)
		(end 132.4261 86.6162)
		(width 0.2032)
		(layer "In3.Cu")
		(net "FPGA_MAC_PPS_IN1-")
	)
	(segment
		(start 175.4261 99.1286)
		(end 175.4261 94.77859)
		(width 0.2032)
		(layer "In3.Cu")
		(net "FPGA_MAC_PPS_IN1-")
	)
	(segment
		(start 175.4261 99.1286)
		(end 175.8761 99.5786)
		(width 0.2032)
		(layer "In3.Cu")
		(net "FPGA_MAC_PPS_IN1-")
	)
	(segment
		(start 132.4261 87.7286)
		(end 132.4261 86.6162)
		(width 0.2032)
		(layer "In3.Cu")
		(net "FPGA_MAC_PPS_IN1-")
	)
	(segment
		(start 168.9511 88.3036)
		(end 175.4261 94.77859)
		(width 0.2032)
		(layer "In3.Cu")
		(net "FPGA_MAC_PPS_IN1-")
	)
	(segment
		(start 133.0011 88.3036)
		(end 168.9511 88.3036)
		(width 0.2032)
		(layer "In3.Cu")
		(net "FPGA_MAC_PPS_IN1-")
	)
	(segment
		(start 174.3011 99.6286)
		(end 174.31348 99.61622)
		(width 0.2032)
		(layer "F.Cu")
		(net "FPGA_MAC_PPS_IN0-")
	)
	(segment
		(start 127.8761 85.2662)
		(end 127.9261 85.2162)
		(width 0.2032)
		(layer "F.Cu")
		(net "FPGA_MAC_PPS_IN0-")
	)
	(segment
		(start 127.9261 85.2162)
		(end 129.0011 85.2162)
		(width 0.2032)
		(layer "F.Cu")
		(net "FPGA_MAC_PPS_IN0-")
	)
	(segment
		(start 174.31348 97.93063)
		(end 174.32586 97.91825)
		(width 0.2032)
		(layer "F.Cu")
		(net "FPGA_MAC_PPS_IN0-")
	)
	(segment
		(start 129.1261 85.3412)
		(end 129.1261 81.8412)
		(width 0.2032)
		(layer "F.Cu")
		(net "FPGA_MAC_PPS_IN0-")
	)
	(segment
		(start 129.0011 85.2162)
		(end 129.1261 85.3412)
		(width 0.2032)
		(layer "F.Cu")
		(net "FPGA_MAC_PPS_IN0-")
	)
	(segment
		(start 127.0261 85.2662)
		(end 127.8761 85.2662)
		(width 0.2032)
		(layer "F.Cu")
		(net "FPGA_MAC_PPS_IN0-")
	)
	(segment
		(start 129.0011 81.7162)
		(end 129.1261 81.8412)
		(width 0.2032)
		(layer "F.Cu")
		(net "FPGA_MAC_PPS_IN0-")
	)
	(segment
		(start 174.31348 99.61622)
		(end 174.31348 97.93063)
		(width 0.2032)
		(layer "F.Cu")
		(net "FPGA_MAC_PPS_IN0-")
	)
	(via
		(at 127.9261 85.2162)
		(size 0.4064)
		(drill 0.2032)
		(layers "F.Cu" "B.Cu")
		(net "FPGA_MAC_PPS_IN0-")
	)
	(via
		(at 174.3011 99.6286)
		(size 0.4064)
		(drill 0.2032)
		(layers "F.Cu" "B.Cu")
		(tenting
			(front yes)
			(back yes)
		)
		(net "FPGA_MAC_PPS_IN0-")
	)
	(segment
		(start 127.0261 86.1162)
		(end 127.9261 85.2162)
		(width 0.2032)
		(layer "In3.Cu")
		(net "FPGA_MAC_PPS_IN0-")
	)
	(segment
		(start 133.5261 89.9162)
		(end 134.78745 88.65485)
		(width 0.2032)
		(layer "In3.Cu")
		(net "FPGA_MAC_PPS_IN0-")
	)
	(segment
		(start 174.3011 99.6286)
		(end 174.3011 94.9786)
		(width 0.2032)
		(layer "In3.Cu")
		(net "FPGA_MAC_PPS_IN0-")
	)
	(segment
		(start 129.2261 89.9162)
		(end 133.5261 89.9162)
		(width 0.2032)
		(layer "In3.Cu")
		(net "FPGA_MAC_PPS_IN0-")
	)
	(segment
		(start 127.0261 87.7162)
		(end 129.2261 89.9162)
		(width 0.2032)
		(layer "In3.Cu")
		(net "FPGA_MAC_PPS_IN0-")
	)
	(segment
		(start 134.78745 88.65485)
		(end 167.97735 88.65485)
		(width 0.2032)
		(layer "In3.Cu")
		(net "FPGA_MAC_PPS_IN0-")
	)
	(segment
		(start 167.97735 88.65485)
		(end 174.3011 94.9786)
		(width 0.2032)
		(layer "In3.Cu")
		(net "FPGA_MAC_PPS_IN0-")
	)
	(segment
		(start 127.0261 87.7162)
		(end 127.0261 86.1162)
		(width 0.2032)
		(layer "In3.Cu")
		(net "FPGA_MAC_PPS_IN0-")
	)
	(segment
		(start 165.3011 99.6536)
		(end 165.31349 99.64121)
		(width 0.2032)
		(layer "F.Cu")
		(net "MAC_RF_OUT")
	)
	(segment
		(start 165.31349 99.64121)
		(end 165.31349 97.93064)
		(width 0.2032)
		(layer "F.Cu")
		(net "MAC_RF_OUT")
	)
	(segment
		(start 165.82575 99.47327)
		(end 165.82575 97.91825)
		(width 0.2032)
		(layer "F.Cu")
		(net "MAC_RF_OUT")
	)
	(segment
		(start 165.9511 99.6536)
		(end 165.9511 99.59861)
		(width 0.2032)
		(layer "F.Cu")
		(net "MAC_RF_OUT")
	)
	(segment
		(start 165.31349 97.93064)
		(end 165.32588 97.91825)
		(width 0.2032)
		(layer "F.Cu")
		(net "MAC_RF_OUT")
	)
	(segment
		(start 165.82575 99.47327)
		(end 165.9511 99.59861)
		(width 0.2032)
		(layer "F.Cu")
		(net "MAC_RF_OUT")
	)
	(via
		(at 165.9511 99.6536)
		(size 0.4064)
		(drill 0.2032)
		(layers "F.Cu" "B.Cu")
		(tenting
			(front yes)
			(back yes)
		)
		(net "MAC_RF_OUT")
	)
	(via
		(at 165.3011 99.6536)
		(size 0.4064)
		(drill 0.2032)
		(layers "F.Cu" "B.Cu")
		(tenting
			(front yes)
			(back yes)
		)
		(net "MAC_RF_OUT")
	)
	(segment
		(start 165.3011 99.6536)
		(end 165.9511 99.6536)
		(width 0.2032)
		(layer "In2.Cu")
		(net "MAC_RF_OUT")
	)
	(segment
		(start 141.6261 125.9162)
		(end 154.20184 125.9162)
		(width 0.2032)
		(layer "In2.Cu")
		(net "MAC_RF_OUT")
	)
	(segment
		(start 99.3261 135.5162)
		(end 102.28215 132.56015)
		(width 0.2032)
		(layer "In2.Cu")
		(net "MAC_RF_OUT")
	)
	(segment
		(start 164.37005 98.72255)
		(end 165.3011 99.6536)
		(width 0.2032)
		(layer "In2.Cu")
		(net "MAC_RF_OUT")
	)
	(segment
		(start 144.2261 113.6641)
		(end 144.2261 95.91223)
		(width 0.2032)
		(layer "In2.Cu")
		(net "MAC_RF_OUT")
	)
	(segment
		(start 144.97005 94.11618)
		(end 146.22608 92.86015)
		(width 0.2032)
		(layer "In2.Cu")
		(net "MAC_RF_OUT")
	)
	(segment
		(start 163.6261 96.92649)
		(end 163.6261 94.8162)
		(width 0.2032)
		(layer "In2.Cu")
		(net "MAC_RF_OUT")
	)
	(segment
		(start 164.6882 91.1783)
		(end 165.5261 92.0162)
		(width 0.2032)
		(layer "In2.Cu")
		(net "MAC_RF_OUT")
	)
	(segment
		(start 164.37255 94.06975)
		(end 164.37278 94.06952)
		(width 0.2032)
		(layer "In2.Cu")
		(net "MAC_RF_OUT")
	)
	(segment
		(start 157.1261 124.2162)
		(end 161.674 124.2162)
		(width 0.2032)
		(layer "In2.Cu")
		(net "MAC_RF_OUT")
	)
	(segment
		(start 154.9261 125.6162)
		(end 155.76042 124.78188)
		(width 0.2032)
		(layer "In2.Cu")
		(net "MAC_RF_OUT")
	)
	(segment
		(start 169.8782 118.1162)
		(end 194.3261 118.1162)
		(width 0.2032)
		(layer "In2.Cu")
		(net "MAC_RF_OUT")
	)
	(segment
		(start 165.5261 92.99193)
		(end 165.5261 92.0162)
		(width 0.2032)
		(layer "In2.Cu")
		(net "MAC_RF_OUT")
	)
	(segment
		(start 163.6261 94.8162)
		(end 164.37255 94.06975)
		(width 0.2032)
		(layer "In2.Cu")
		(net "MAC_RF_OUT")
	)
	(segment
		(start 106.25099 130.9162)
		(end 191.0261 130.9162)
		(width 0.2032)
		(layer "In2.Cu")
		(net "MAC_RF_OUT")
	)
	(segment
		(start 163.47005 123.47225)
		(end 168.08215 118.86015)
		(width 0.2032)
		(layer "In2.Cu")
		(net "MAC_RF_OUT")
	)
	(segment
		(start 148.02213 92.1162)
		(end 159.86042 92.1162)
		(width 0.2032)
		(layer "In2.Cu")
		(net "MAC_RF_OUT")
	)
	(segment
		(start 140.1261 123.3641)
		(end 140.1261 119.8683)
		(width 0.2032)
		(layer "In2.Cu")
		(net "MAC_RF_OUT")
	)
	(segment
		(start 162.1247 91.1783)
		(end 164.6882 91.1783)
		(width 0.2032)
		(layer "In2.Cu")
		(net "MAC_RF_OUT")
	)
	(segment
		(start 140.87005 125.16015)
		(end 141.6261 125.9162)
		(width 0.2032)
		(layer "In2.Cu")
		(net "MAC_RF_OUT")
	)
	(segment
		(start 194.7261 127.2162)
		(end 194.7261 119.08189)
		(width 0.2032)
		(layer "In2.Cu")
		(net "MAC_RF_OUT")
	)
	(segment
		(start 140.87005 118.07225)
		(end 143.48215 115.46015)
		(width 0.2032)
		(layer "In2.Cu")
		(net "MAC_RF_OUT")
	)
	(segment
		(start 191.0261 130.9162)
		(end 194.7261 127.2162)
		(width 0.2032)
		(layer "In2.Cu")
		(net "MAC_RF_OUT")
	)
	(arc
		(start 160.826102 91.716202)
		(mid 160.383043 92.012244)
		(end 159.86042 92.116201)
		(width 0.2032)
		(layer "In2.Cu")
		(net "MAC_RF_OUT")
	)
	(arc
		(start 194.326099 118.116201)
		(mid 194.622143 118.559263)
		(end 194.7261 119.08189)
		(width 0.2032)
		(layer "In2.Cu")
		(net "MAC_RF_OUT")
	)
	(arc
		(start 160.826098 91.716198)
		(mid 161.421902 91.318095)
		(end 162.1247 91.178299)
		(width 0.2032)
		(layer "In2.Cu")
		(net "MAC_RF_OUT")
	)
	(arc
		(start 164.370049 98.722541)
		(mid 163.819446 97.898506)
		(end 163.6261 96.92649)
		(width 0.2032)
		(layer "In2.Cu")
		(net "MAC_RF_OUT")
	)
	(arc
		(start 155.760415 124.781885)
		(mid 156.386997 124.363217)
		(end 157.1261 124.2162)
		(width 0.2032)
		(layer "In2.Cu")
		(net "MAC_RF_OUT")
	)
	(arc
		(start 168.082149 118.860149)
		(mid 168.906184 118.309546)
		(end 169.8782 118.1162)
		(width 0.2032)
		(layer "In2.Cu")
		(net "MAC_RF_OUT")
	)
	(arc
		(start 140.1261 119.8683)
		(mid 140.319446 118.896284)
		(end 140.870049 118.072249)
		(width 0.2032)
		(layer "In2.Cu")
		(net "MAC_RF_OUT")
	)
	(arc
		(start 146.226079 92.860149)
		(mid 147.050114 92.309546)
		(end 148.02213 92.1162)
		(width 0.2032)
		(layer "In2.Cu")
		(net "MAC_RF_OUT")
	)
	(arc
		(start 165.5261 92.99193)
		(mid 165.448133 93.3839)
		(end 165.2261 93.716196)
		(width 0.2032)
		(layer "In2.Cu")
		(net "MAC_RF_OUT")
	)
	(arc
		(start 154.926101 125.616201)
		(mid 154.593807 125.838233)
		(end 154.20184 125.9162)
		(width 0.2032)
		(layer "In2.Cu")
		(net "MAC_RF_OUT")
	)
	(arc
		(start 144.2261 113.6641)
		(mid 144.032754 114.636116)
		(end 143.482151 115.460151)
		(width 0.2032)
		(layer "In2.Cu")
		(net "MAC_RF_OUT")
	)
	(arc
		(start 140.870049 125.160151)
		(mid 140.319446 124.336116)
		(end 140.1261 123.3641)
		(width 0.2032)
		(layer "In2.Cu")
		(net "MAC_RF_OUT")
	)
	(arc
		(start 144.2261 95.91223)
		(mid 144.419446 94.940214)
		(end 144.970049 94.116179)
		(width 0.2032)
		(layer "In2.Cu")
		(net "MAC_RF_OUT")
	)
	(arc
		(start 163.470051 123.472251)
		(mid 162.646016 124.022854)
		(end 161.674 124.2162)
		(width 0.2032)
		(layer "In2.Cu")
		(net "MAC_RF_OUT")
	)
	(arc
		(start 102.282149 132.560147)
		(mid 104.103069 131.343448)
		(end 106.25099 130.9162)
		(width 0.2032)
		(layer "In2.Cu")
		(net "MAC_RF_OUT")
	)
	(arc
		(start 164.372777 94.069512)
		(mid 164.764311 93.808013)
		(end 165.2261 93.71619)
		(width 0.2032)
		(layer "In2.Cu")
		(net "MAC_RF_OUT")
	)
	(segment
		(start 180.2011 90.0786)
		(end 180.2261 90.1036)
		(width 0.2032)
		(layer "F.Cu")
		(net "EXT_EEPROM_WP")
	)
	(segment
		(start 180.7761 90.0786)
		(end 182.3761 90.0786)
		(width 0.2032)
		(layer "F.Cu")
		(net "EXT_EEPROM_WP")
	)
	(segment
		(start 181.0761 89.7786)
		(end 181.0761 88.14481)
		(width 0.2032)
		(layer "F.Cu")
		(net "EXT_EEPROM_WP")
	)
	(segment
		(start 180.7761 90.0786)
		(end 181.0761 89.7786)
		(width 0.2032)
		(layer "F.Cu")
		(net "EXT_EEPROM_WP")
	)
	(segment
		(start 200.42886 115.31344)
		(end 201.3761 114.3662)
		(width 0.2032)
		(layer "F.Cu")
		(net "EXT_EEPROM_WP")
	)
	(segment
		(start 199.3634 115.31344)
		(end 200.42886 115.31344)
		(width 0.2032)
		(layer "F.Cu")
		(net "EXT_EEPROM_WP")
	)
	(segment
		(start 180.2011 90.0786)
		(end 180.7761 90.0786)
		(width 0.2032)
		(layer "F.Cu")
		(net "EXT_EEPROM_WP")
	)
	(via
		(at 201.3761 114.3662)
		(size 0.4064)
		(drill 0.2032)
		(layers "F.Cu" "B.Cu")
		(tenting
			(front yes)
			(back yes)
		)
		(net "EXT_EEPROM_WP")
	)
	(via
		(at 182.38436 90.07034)
		(size 0.4064)
		(drill 0.2032)
		(layers "F.Cu" "B.Cu")
		(tenting
			(front yes)
			(back yes)
		)
		(net "EXT_EEPROM_WP")
	)
	(segment
		(start 202.6261 113.1162)
		(end 202.6261 108.82859)
		(width 0.2032)
		(layer "B.Cu")
		(net "EXT_EEPROM_WP")
	)
	(segment
		(start 201.3761 114.3662)
		(end 202.6261 113.1162)
		(width 0.2032)
		(layer "B.Cu")
		(net "EXT_EEPROM_WP")
	)
	(segment
		(start 183.86785 90.07034)
		(end 198.63879 104.84129)
		(width 0.2032)
		(layer "B.Cu")
		(net "EXT_EEPROM_WP")
	)
	(segment
		(start 202.43071 108.6332)
		(end 202.6261 108.82859)
		(width 0.2032)
		(layer "B.Cu")
		(net "EXT_EEPROM_WP")
	)
	(segment
		(start 198.63879 107.12889)
		(end 198.63879 104.84129)
		(width 0.2032)
		(layer "B.Cu")
		(net "EXT_EEPROM_WP")
	)
	(segment
		(start 198.63879 107.12889)
		(end 200.1431 108.6332)
		(width 0.2032)
		(layer "B.Cu")
		(net "EXT_EEPROM_WP")
	)
	(segment
		(start 182.38436 90.07034)
		(end 183.86785 90.07034)
		(width 0.2032)
		(layer "B.Cu")
		(net "EXT_EEPROM_WP")
	)
	(segment
		(start 200.1431 108.6332)
		(end 202.43071 108.6332)
		(width 0.2032)
		(layer "B.Cu")
		(net "EXT_EEPROM_WP")
	)
	(segment
		(start 79.8761 71.8286)
		(end 81.9311 71.8286)
		(width 0.2032)
		(layer "F.Cu")
		(net "GPS1_TX")
	)
	(segment
		(start 182.32598 91.65373)
		(end 182.3261 91.6536)
		(width 0.2032)
		(layer "F.Cu")
		(net "GPS1_TX")
	)
	(segment
		(start 182.32598 93.86834)
		(end 182.32598 91.65373)
		(width 0.2032)
		(layer "F.Cu")
		(net "GPS1_TX")
	)
	(segment
		(start 182.32585 93.86847)
		(end 182.32598 93.86834)
		(width 0.2032)
		(layer "F.Cu")
		(net "GPS1_TX")
	)
	(via
		(at 79.8761 71.8286)
		(size 0.4064)
		(drill 0.2032)
		(layers "F.Cu" "B.Cu")
		(tenting
			(front yes)
			(back yes)
		)
		(net "GPS1_TX")
	)
	(via
		(at 182.3261 91.6536)
		(size 0.4064)
		(drill 0.2032)
		(layers "F.Cu" "B.Cu")
		(tenting
			(front yes)
			(back yes)
		)
		(net "GPS1_TX")
	)
	(segment
		(start 157.49467 80.8162)
		(end 161.6261 80.8162)
		(width 0.2032)
		(layer "In3.Cu")
		(net "GPS1_TX")
	)
	(segment
		(start 155.55727 82.7536)
		(end 157.49467 80.8162)
		(width 0.2032)
		(layer "In3.Cu")
		(net "GPS1_TX")
	)
	(segment
		(start 161.6261 80.8162)
		(end 163.5635 82.7536)
		(width 0.2032)
		(layer "In3.Cu")
		(net "GPS1_TX")
	)
	(segment
		(start 173.4261 82.7536)
		(end 182.3261 91.6536)
		(width 0.2032)
		(layer "In3.Cu")
		(net "GPS1_TX")
	)
	(segment
		(start 136.8261 82.7536)
		(end 155.55727 82.7536)
		(width 0.2032)
		(layer "In3.Cu")
		(net "GPS1_TX")
	)
	(segment
		(start 79.8761 71.8286)
		(end 85.1761 77.1286)
		(width 0.2032)
		(layer "In3.Cu")
		(net "GPS1_TX")
	)
	(segment
		(start 163.5635 82.7536)
		(end 173.4261 82.7536)
		(width 0.2032)
		(layer "In3.Cu")
		(net "GPS1_TX")
	)
	(segment
		(start 131.2011 77.1286)
		(end 136.8261 82.7536)
		(width 0.2032)
		(layer "In3.Cu")
		(net "GPS1_TX")
	)
	(segment
		(start 85.1761 77.1286)
		(end 131.2011 77.1286)
		(width 0.2032)
		(layer "In3.Cu")
		(net "GPS1_TX")
	)
	(segment
		(start 199.3634 112.31345)
		(end 200.56014 112.31345)
		(width 0.2032)
		(layer "F.Cu")
		(net "GPS1_TP1")
	)
	(segment
		(start 200.79851 112.07508)
		(end 201.37688 112.07508)
		(width 0.2032)
		(layer "F.Cu")
		(net "GPS1_TP1")
	)
	(segment
		(start 200.56014 112.31345)
		(end 200.79851 112.07508)
		(width 0.2032)
		(layer "F.Cu")
		(net "GPS1_TP1")
	)
	(segment
		(start 86.3761 69.8286)
		(end 88.3761 69.8286)
		(width 0.2032)
		(layer "F.Cu")
		(net "GPS1_TP1")
	)
	(via
		(at 201.37688 112.07508)
		(size 0.4064)
		(drill 0.2032)
		(layers "F.Cu" "B.Cu")
		(tenting
			(front yes)
			(back yes)
		)
		(net "GPS1_TP1")
	)
	(via
		(at 88.3761 69.8286)
		(size 0.4064)
		(drill 0.2032)
		(layers "F.Cu" "B.Cu")
		(tenting
			(front yes)
			(back yes)
		)
		(net "GPS1_TP1")
	)
	(segment
		(start 201.6261 113.0078)
		(end 201.6261 112.3286)
		(width 0.2032)
		(layer "B.Cu")
		(net "GPS1_TP1")
	)
	(segment
		(start 201.37688 112.07938)
		(end 201.37688 112.07508)
		(width 0.2032)
		(layer "B.Cu")
		(net "GPS1_TP1")
	)
	(segment
		(start 122.77531 76.46699)
		(end 122.8261 76.4162)
		(width 0.2032)
		(layer "B.Cu")
		(net "GPS1_TP1")
	)
	(segment
		(start 131.318 101.2188)
		(end 158.02513 101.2188)
		(width 0.2032)
		(layer "B.Cu")
		(net "GPS1_TP1")
	)
	(segment
		(start 122.8261 76.4162)
		(end 129.8261 83.4162)
		(width 0.2032)
		(layer "B.Cu")
		(net "GPS1_TP1")
	)
	(segment
		(start 129.8261 99.7269)
		(end 129.8261 83.4162)
		(width 0.2032)
		(layer "B.Cu")
		(net "GPS1_TP1")
	)
	(segment
		(start 201.3247 113.3092)
		(end 201.6261 113.0078)
		(width 0.2032)
		(layer "B.Cu")
		(net "GPS1_TP1")
	)
	(segment
		(start 107.6261 69.8286)
		(end 114.26449 76.46699)
		(width 0.2032)
		(layer "B.Cu")
		(net "GPS1_TP1")
	)
	(segment
		(start 158.02513 101.2188)
		(end 170.11553 113.3092)
		(width 0.2032)
		(layer "B.Cu")
		(net "GPS1_TP1")
	)
	(segment
		(start 129.8261 99.7269)
		(end 131.318 101.2188)
		(width 0.2032)
		(layer "B.Cu")
		(net "GPS1_TP1")
	)
	(segment
		(start 88.3761 69.8286)
		(end 107.6261 69.8286)
		(width 0.2032)
		(layer "B.Cu")
		(net "GPS1_TP1")
	)
	(segment
		(start 170.11553 113.3092)
		(end 201.3247 113.3092)
		(width 0.2032)
		(layer "B.Cu")
		(net "GPS1_TP1")
	)
	(segment
		(start 201.37688 112.07938)
		(end 201.6261 112.3286)
		(width 0.2032)
		(layer "B.Cu")
		(net "GPS1_TP1")
	)
	(segment
		(start 114.26449 76.46699)
		(end 122.77531 76.46699)
		(width 0.2032)
		(layer "B.Cu")
		(net "GPS1_TP1")
	)
	(segment
		(start 182.33847 99.59097)
		(end 182.3511 99.6036)
		(width 0.2032)
		(layer "F.Cu")
		(net "GPS1_RX")
	)
	(segment
		(start 182.33847 99.59097)
		(end 182.33847 97.93088)
		(width 0.2032)
		(layer "F.Cu")
		(net "GPS1_RX")
	)
	(segment
		(start 79.8761 69.8286)
		(end 81.9311 69.8286)
		(width 0.2032)
		(layer "F.Cu")
		(net "GPS1_RX")
	)
	(segment
		(start 182.32585 97.91825)
		(end 182.33847 97.93088)
		(width 0.2032)
		(layer "F.Cu")
		(net "GPS1_RX")
	)
	(via
		(at 182.3511 99.6036)
		(size 0.4064)
		(drill 0.2032)
		(layers "F.Cu" "B.Cu")
		(tenting
			(front yes)
			(back yes)
		)
		(net "GPS1_RX")
	)
	(via
		(at 79.8761 69.8286)
		(size 0.4064)
		(drill 0.2032)
		(layers "F.Cu" "B.Cu")
		(tenting
			(front yes)
			(back yes)
		)
		(net "GPS1_RX")
	)
	(segment
		(start 137.0011 82.3036)
		(end 153.82419 82.3036)
		(width 0.2032)
		(layer "In3.Cu")
		(net "GPS1_RX")
	)
	(segment
		(start 79.8761 70.8286)
		(end 79.8761 69.8286)
		(width 0.2032)
		(layer "In3.Cu")
		(net "GPS1_RX")
	)
	(segment
		(start 164.2739 82.3036)
		(end 173.8761 82.3036)
		(width 0.2032)
		(layer "In3.Cu")
		(net "GPS1_RX")
	)
	(segment
		(start 182.3511 99.6036)
		(end 183.3261 98.6286)
		(width 0.2032)
		(layer "In3.Cu")
		(net "GPS1_RX")
	)
	(segment
		(start 173.8761 82.3036)
		(end 183.3261 91.7536)
		(width 0.2032)
		(layer "In3.Cu")
		(net "GPS1_RX")
	)
	(segment
		(start 79.8761 70.8286)
		(end 85.7761 76.7286)
		(width 0.2032)
		(layer "In3.Cu")
		(net "GPS1_RX")
	)
	(segment
		(start 161.68649 79.7162)
		(end 164.2739 82.3036)
		(width 0.2032)
		(layer "In3.Cu")
		(net "GPS1_RX")
	)
	(segment
		(start 85.7761 76.7286)
		(end 131.4261 76.7286)
		(width 0.2032)
		(layer "In3.Cu")
		(net "GPS1_RX")
	)
	(segment
		(start 131.4261 76.7286)
		(end 137.0011 82.3036)
		(width 0.2032)
		(layer "In3.Cu")
		(net "GPS1_RX")
	)
	(segment
		(start 153.82419 82.3036)
		(end 156.41159 79.7162)
		(width 0.2032)
		(layer "In3.Cu")
		(net "GPS1_RX")
	)
	(segment
		(start 156.41159 79.7162)
		(end 161.68649 79.7162)
		(width 0.2032)
		(layer "In3.Cu")
		(net "GPS1_RX")
	)
	(segment
		(start 183.3261 98.6286)
		(end 183.3261 91.7536)
		(width 0.2032)
		(layer "In3.Cu")
		(net "GPS1_RX")
	)
	(segment
		(start 115.5461 157.7576)
		(end 115.5621 157.7416)
		(width 0.2032)
		(layer "B.Cu")
		(net "NetC44_1")
	)
	(segment
		(start 115.5621 156.99168)
		(end 115.5621 152.2186)
		(width 0.127)
		(layer "B.Cu")
		(net "NetC44_1")
	)
	(arc
		(start 115.5621 156.99168)
		(mid 115.552743 157.038719)
		(end 115.526098 157.078598)
		(width 0.127)
		(layer "B.Cu")
		(net "NetC44_1")
	)
	(arc
		(start 115.54609 152.25723)
		(mid 115.550249 152.236321)
		(end 115.562093 152.218594)
		(width 0.127)
		(layer "B.Cu")
		(net "NetC44_1")
	)
	(segment
		(start 116.5781 156.95305)
		(end 116.5781 152.2186)
		(width 0.127)
		(layer "B.Cu")
		(net "NetC45_1")
	)
	(arc
		(start 116.5781 156.95305)
		(mid 116.564585 157.020995)
		(end 116.526097 157.078597)
		(width 0.127)
		(layer "B.Cu")
		(net "NetC45_1")
	)
	(segment
		(start 118.5847 156.93711)
		(end 118.5847 152.2186)
		(width 0.127)
		(layer "B.Cu")
		(net "NetC46_1")
	)
	(arc
		(start 118.5847 157.66439)
		(mid 118.574687 157.714783)
		(end 118.546171 157.757521)
		(width 0.127)
		(layer "B.Cu")
		(net "NetC46_1")
	)
	(arc
		(start 118.5847 156.93711)
		(mid 118.569468 157.013685)
		(end 118.526092 157.078602)
		(width 0.127)
		(layer "B.Cu")
		(net "NetC46_1")
	)
	(segment
		(start 119.6769 156.71451)
		(end 119.6769 152.2186)
		(width 0.127)
		(layer "B.Cu")
		(net "NetC47_1")
	)
	(arc
		(start 119.6769 156.71451)
		(mid 119.637706 156.911554)
		(end 119.526089 157.078599)
		(width 0.127)
		(layer "B.Cu")
		(net "NetC47_1")
	)
	(segment
		(start 123.5631 156.98923)
		(end 123.5631 152.2186)
		(width 0.127)
		(layer "B.Cu")
		(net "NetC48_1")
	)
	(arc
		(start 123.5631 157.71651)
		(mid 123.558677 157.738744)
		(end 123.546083 157.757593)
		(width 0.127)
		(layer "B.Cu")
		(net "NetC48_1")
	)
	(arc
		(start 123.5631 156.98923)
		(mid 123.553479 157.037597)
		(end 123.526081 157.078601)
		(width 0.127)
		(layer "B.Cu")
		(net "NetC48_1")
	)
	(segment
		(start 127.5001 157.01589)
		(end 127.5001 152.2186)
		(width 0.127)
		(layer "B.Cu")
		(net "NetC50_1")
	)
	(arc
		(start 127.526074 157.078596)
		(mid 127.506851 157.049826)
		(end 127.5001 157.01589)
		(width 0.127)
		(layer "B.Cu")
		(net "NetC50_1")
	)
	(arc
		(start 127.500097 152.218603)
		(mid 127.534122 152.269524)
		(end 127.546069 152.32959)
		(width 0.127)
		(layer "B.Cu")
		(net "NetC50_1")
	)
	(segment
		(start 128.3891 156.74792)
		(end 128.3891 152.2186)
		(width 0.127)
		(layer "B.Cu")
		(net "NetC51_1")
	)
	(arc
		(start 128.526072 157.078598)
		(mid 128.424698 156.926882)
		(end 128.389101 156.74792)
		(width 0.127)
		(layer "B.Cu")
		(net "NetC51_1")
	)
	(arc
		(start 128.5456 157.757133)
		(mid 128.429768 157.583426)
		(end 128.3891 157.37864)
		(width 0.127)
		(layer "B.Cu")
		(net "NetC51_1")
	)
	(segment
		(start 131.5641 156.98678)
		(end 131.5641 152.2186)
		(width 0.127)
		(layer "B.Cu")
		(net "NetC52_1")
	)
	(arc
		(start 131.56411 156.98678)
		(mid 131.554225 157.036475)
		(end 131.526075 157.078605)
		(width 0.127)
		(layer "B.Cu")
		(net "NetC52_1")
	)
	(arc
		(start 131.5641 157.71406)
		(mid 131.559413 157.737622)
		(end 131.546067 157.757597)
		(width 0.127)
		(layer "B.Cu")
		(net "NetC52_1")
	)
	(arc
		(start 131.54607 152.26214)
		(mid 131.550757 152.238578)
		(end 131.564103 152.218603)
		(width 0.127)
		(layer "B.Cu")
		(net "NetC52_1")
	)
	(segment
		(start 132.54606 157.7576)
		(end 132.5801 157.72356)
		(width 0.2032)
		(layer "B.Cu")
		(net "NetC53_1")
	)
	(segment
		(start 132.5801 156.94814)
		(end 132.5801 152.2186)
		(width 0.127)
		(layer "B.Cu")
		(net "NetC53_1")
	)
	(arc
		(start 132.54606 152.30077)
		(mid 132.554906 152.256298)
		(end 132.580097 152.218597)
		(width 0.127)
		(layer "B.Cu")
		(net "NetC53_1")
	)
	(arc
		(start 132.5801 156.94814)
		(mid 132.566057 157.018741)
		(end 132.526064 157.078594)
		(width 0.127)
		(layer "B.Cu")
		(net "NetC53_1")
	)
	(segment
		(start 75.1261 54.9412)
		(end 75.1261 52.8662)
		(width 0.2032)
		(layer "F.Cu")
		(net "NetD11_1")
	)
	(segment
		(start 97.3511 142.2162)
		(end 99.3261 142.2162)
		(width 0.2032)
		(layer "F.Cu")
		(net "NetP2_B17")
	)
	(segment
		(start 99.3261 142.2162)
		(end 99.3261 142.2162)
		(width 0.2032)
		(layer "F.Cu")
		(net "NetP2_B17")
	)
	(segment
		(start 119.92657 149.22907)
		(end 120.3761 149.6786)
		(width 0.2032)
		(layer "F.Cu")
		(net "NetP2_B17")
	)
	(segment
		(start 119.5761 153.6786)
		(end 120.3761 152.8786)
		(width 0.2032)
		(layer "F.Cu")
		(net "NetP2_B17")
	)
	(segment
		(start 120.3761 152.8786)
		(end 120.3761 149.6786)
		(width 0.2032)
		(layer "F.Cu")
		(net "NetP2_B17")
	)
	(segment
		(start 113.0881 149.22907)
		(end 119.92657 149.22907)
		(width 0.2032)
		(layer "F.Cu")
		(net "NetP2_B17")
	)
	(segment
		(start 119.52609 157.0786)
		(end 119.5761 157.02859)
		(width 0.2032)
		(layer "F.Cu")
		(net "NetP2_B17")
	)
	(segment
		(start 119.5761 157.02859)
		(end 119.5761 153.6786)
		(width 0.2032)
		(layer "F.Cu")
		(net "NetP2_B17")
	)
	(via
		(at 113.0881 149.22907)
		(size 0.4064)
		(drill 0.2032)
		(layers "F.Cu" "B.Cu")
		(net "NetP2_B17")
	)
	(via
		(at 99.3261 142.2162)
		(size 0.4064)
		(drill 0.2032)
		(layers "F.Cu" "B.Cu")
		(net "NetP2_B17")
	)
	(segment
		(start 114.6261 148.6162)
		(end 114.6261 147.4162)
		(width 0.2032)
		(layer "In2.Cu")
		(net "NetP2_B17")
	)
	(segment
		(start 109.4261 142.2162)
		(end 114.6261 147.4162)
		(width 0.2032)
		(layer "In2.Cu")
		(net "NetP2_B17")
	)
	(segment
		(start 114.01323 149.22907)
		(end 114.6261 148.6162)
		(width 0.2032)
		(layer "In2.Cu")
		(net "NetP2_B17")
	)
	(segment
		(start 99.3261 142.2162)
		(end 109.4261 142.2162)
		(width 0.2032)
		(layer "In2.Cu")
		(net "NetP2_B17")
	)
	(segment
		(start 113.0881 149.22907)
		(end 114.01323 149.22907)
		(width 0.2032)
		(layer "In2.Cu")
		(net "NetP2_B17")
	)
	(segment
		(start 121.66749 149.5576)
		(end 133.4761 149.5576)
		(width 0.2032)
		(layer "F.Cu")
		(net "NetP2_B31")
	)
	(segment
		(start 99.13831 143.3162)
		(end 99.18932 143.26518)
		(width 0.2032)
		(layer "F.Cu")
		(net "NetP2_B31")
	)
	(segment
		(start 133.54606 157.2623)
		(end 133.5961 157.21226)
		(width 0.2032)
		(layer "F.Cu")
		(net "NetP2_B31")
	)
	(segment
		(start 97.3511 143.3162)
		(end 99.13831 143.3162)
		(width 0.2032)
		(layer "F.Cu")
		(net "NetP2_B31")
	)
	(segment
		(start 133.4761 156.53334)
		(end 133.4761 149.5576)
		(width 0.2032)
		(layer "F.Cu")
		(net "NetP2_B31")
	)
	(segment
		(start 120.40396 148.29406)
		(end 121.66749 149.5576)
		(width 0.2032)
		(layer "F.Cu")
		(net "NetP2_B31")
	)
	(segment
		(start 133.4761 156.53334)
		(end 133.52606 156.5833)
		(width 0.2032)
		(layer "F.Cu")
		(net "NetP2_B31")
	)
	(segment
		(start 97.3511 143.3162)
		(end 97.40114 143.36624)
		(width 0.2032)
		(layer "F.Cu")
		(net "NetP2_B31")
	)
	(segment
		(start 113.51771 148.29406)
		(end 120.40396 148.29406)
		(width 0.2032)
		(layer "F.Cu")
		(net "NetP2_B31")
	)
	(via
		(at 113.51771 148.29406)
		(size 0.4064)
		(drill 0.2032)
		(layers "F.Cu" "B.Cu")
		(net "NetP2_B31")
	)
	(via
		(at 99.18932 143.26518)
		(size 0.4064)
		(drill 0.2032)
		(layers "F.Cu" "B.Cu")
		(net "NetP2_B31")
	)
	(segment
		(start 108.48883 143.26518)
		(end 113.51771 148.29406)
		(width 0.2032)
		(layer "In2.Cu")
		(net "NetP2_B31")
	)
	(segment
		(start 99.18932 143.26518)
		(end 108.48883 143.26518)
		(width 0.2032)
		(layer "In2.Cu")
		(net "NetP2_B31")
	)
	(segment
		(start 203.40993 142.3762)
		(end 207.7261 142.3762)
		(width 0.2032)
		(layer "F.Cu")
		(net "NetR18_2")
	)
	(segment
		(start 200.41136 139.37763)
		(end 203.40993 142.3762)
		(width 0.2032)
		(layer "F.Cu")
		(net "NetR18_2")
	)
	(segment
		(start 226.4261 146.2162)
		(end 229.5261 143.1162)
		(width 0.2032)
		(layer "F.Cu")
		(net "NetR20_2")
	)
	(segment
		(start 212.8061 142.3762)
		(end 212.82673 142.39683)
		(width 0.2032)
		(layer "F.Cu")
		(net "NetR20_2")
	)
	(segment
		(start 213.9261 146.2162)
		(end 226.4261 146.2162)
		(width 0.2032)
		(layer "F.Cu")
		(net "NetR20_2")
	)
	(segment
		(start 212.8061 145.0962)
		(end 212.8061 142.3762)
		(width 0.2032)
		(layer "F.Cu")
		(net "NetR20_2")
	)
	(segment
		(start 212.8061 145.0962)
		(end 213.9261 146.2162)
		(width 0.2032)
		(layer "F.Cu")
		(net "NetR20_2")
	)
	(segment
		(start 219.0261 145.3162)
		(end 222.8261 145.3162)
		(width 0.2032)
		(layer "F.Cu")
		(net "NetR21_2")
	)
	(segment
		(start 217.8861 144.1762)
		(end 217.8861 142.3762)
		(width 0.2032)
		(layer "F.Cu")
		(net "NetR21_2")
	)
	(segment
		(start 222.8261 145.3162)
		(end 224.9261 143.2162)
		(width 0.2032)
		(layer "F.Cu")
		(net "NetR21_2")
	)
	(segment
		(start 217.8861 142.3762)
		(end 217.9261 142.4162)
		(width 0.2032)
		(layer "F.Cu")
		(net "NetR21_2")
	)
	(segment
		(start 217.8861 144.1762)
		(end 219.0261 145.3162)
		(width 0.2032)
		(layer "F.Cu")
		(net "NetR21_2")
	)
	(segment
		(start 233.8261 110.2162)
		(end 234.3261 110.7162)
		(width 0.2032)
		(layer "F.Cu")
		(net "SDA")
	)
	(segment
		(start 177.64189 99.34439)
		(end 177.64189 99.28941)
		(width 0.2032)
		(layer "F.Cu")
		(net "SDA")
	)
	(segment
		(start 100.8761 84.8862)
		(end 100.8761 82.9162)
		(width 0.2032)
		(layer "F.Cu")
		(net "SDA")
	)
	(segment
		(start 179.15735 85.99364)
		(end 179.1761 86.01239)
		(width 0.2032)
		(layer "F.Cu")
		(net "SDA")
	)
	(segment
		(start 195.1886 87.1161)
		(end 196.3386 87.1161)
		(width 0.2032)
		(layer "F.Cu")
		(net "SDA")
	)
	(segment
		(start 185.0761 88.73648)
		(end 185.0761 87.7787)
		(width 0.2032)
		(layer "F.Cu")
		(net "SDA")
	)
	(segment
		(start 179.15735 85.99364)
		(end 179.15735 84.60985)
		(width 0.2032)
		(layer "F.Cu")
		(net "SDA")
	)
	(segment
		(start 233.8261 130.6812)
		(end 235.3611 130.6812)
		(width 0.2032)
		(layer "F.Cu")
		(net "SDA")
	)
	(segment
		(start 177.82573 99.10557)
		(end 177.82573 97.91825)
		(width 0.2032)
		(layer "F.Cu")
		(net "SDA")
	)
	(segment
		(start 235.0911 112.4812)
		(end 235.8261 112.4812)
		(width 0.2032)
		(layer "F.Cu")
		(net "SDA")
	)
	(segment
		(start 202.4911 84.5162)
		(end 202.4911 84.2812)
		(width 0.2032)
		(layer "F.Cu")
		(net "SDA")
	)
	(segment
		(start 85.28867 90.58188)
		(end 85.28867 88.95363)
		(width 0.2032)
		(layer "F.Cu")
		(net "SDA")
	)
	(segment
		(start 185.0761 88.73648)
		(end 185.07648 88.73686)
		(width 0.2032)
		(layer "F.Cu")
		(net "SDA")
	)
	(segment
		(start 196.3386 87.1161)
		(end 196.3761 87.0786)
		(width 0.2032)
		(layer "F.Cu")
		(net "SDA")
	)
	(segment
		(start 234.3261 111.7162)
		(end 235.0911 112.4812)
		(width 0.2032)
		(layer "F.Cu")
		(net "SDA")
	)
	(segment
		(start 233.7261 110.3162)
		(end 233.8261 110.2162)
		(width 0.2032)
		(layer "F.Cu")
		(net "SDA")
	)
	(segment
		(start 195.1511 87.1536)
		(end 195.1886 87.1161)
		(width 0.2032)
		(layer "F.Cu")
		(net "SDA")
	)
	(segment
		(start 100.8761 84.8862)
		(end 101.6061 85.6162)
		(width 0.2032)
		(layer "F.Cu")
		(net "SDA")
	)
	(segment
		(start 177.64189 99.28941)
		(end 177.82573 99.10557)
		(width 0.2032)
		(layer "F.Cu")
		(net "SDA")
	)
	(segment
		(start 199.9261 83.5162)
		(end 200.1261 83.3162)
		(width 0.2032)
		(layer "F.Cu")
		(net "SDA")
	)
	(segment
		(start 234.3261 111.7162)
		(end 234.3261 110.7162)
		(width 0.2032)
		(layer "F.Cu")
		(net "SDA")
	)
	(segment
		(start 179.1386 84.5911)
		(end 179.15735 84.60985)
		(width 0.2032)
		(layer "F.Cu")
		(net "SDA")
	)
	(segment
		(start 201.5261 83.3162)
		(end 202.4911 84.2812)
		(width 0.2032)
		(layer "F.Cu")
		(net "SDA")
	)
	(segment
		(start 85.28867 88.95363)
		(end 86.1261 88.1162)
		(width 0.2032)
		(layer "F.Cu")
		(net "SDA")
	)
	(segment
		(start 235.3611 130.6812)
		(end 235.4261 130.6162)
		(width 0.2032)
		(layer "F.Cu")
		(net "SDA")
	)
	(segment
		(start 200.1261 83.3162)
		(end 201.5261 83.3162)
		(width 0.2032)
		(layer "F.Cu")
		(net "SDA")
	)
	(segment
		(start 86.1261 88.1162)
		(end 87.0511 88.1162)
		(width 0.2032)
		(layer "F.Cu")
		(net "SDA")
	)
	(via
		(at 197.75296 99.05503)
		(size 0.4064)
		(drill 0.2032)
		(layers "F.Cu" "B.Cu")
		(net "SDA")
	)
	(via
		(at 177.64189 99.34439)
		(size 0.4064)
		(drill 0.2032)
		(layers "F.Cu" "B.Cu")
		(tenting
			(front yes)
			(back yes)
		)
		(net "SDA")
	)
	(via
		(at 179.1386 84.5911)
		(size 0.4064)
		(drill 0.2032)
		(layers "F.Cu" "B.Cu")
		(tenting
			(front yes)
			(back yes)
		)
		(net "SDA")
	)
	(via
		(at 185.07648 88.73686)
		(size 0.4064)
		(drill 0.2032)
		(layers "F.Cu" "B.Cu")
		(net "SDA")
	)
	(via
		(at 235.4261 130.6162)
		(size 0.4064)
		(drill 0.2032)
		(layers "F.Cu" "B.Cu")
		(net "SDA")
	)
	(via
		(at 85.28867 90.58188)
		(size 0.4064)
		(drill 0.2032)
		(layers "F.Cu" "B.Cu")
		(tenting
			(front yes)
			(back yes)
		)
		(net "SDA")
	)
	(via
		(at 199.9261 83.5162)
		(size 0.4064)
		(drill 0.2032)
		(layers "F.Cu" "B.Cu")
		(net "SDA")
	)
	(via
		(at 189.0261 111.5162)
		(size 0.4064)
		(drill 0.2032)
		(layers "F.Cu" "B.Cu")
		(net "SDA")
	)
	(via
		(at 196.3761 87.0786)
		(size 0.4064)
		(drill 0.2032)
		(layers "F.Cu" "B.Cu")
		(tenting
			(front yes)
			(back yes)
		)
		(net "SDA")
	)
	(via
		(at 233.7261 110.3162)
		(size 0.4064)
		(drill 0.2032)
		(layers "F.Cu" "B.Cu")
		(net "SDA")
	)
	(segment
		(start 192.7261 97.2162)
		(end 193.0261 97.5162)
		(width 0.2032)
		(layer "B.Cu")
		(net "SDA")
	)
	(segment
		(start 193.0261 97.5162)
		(end 196.21413 97.5162)
		(width 0.2032)
		(layer "B.Cu")
		(net "SDA")
	)
	(segment
		(start 193.3261 82.2162)
		(end 199.2261 82.2162)
		(width 0.2032)
		(layer "B.Cu")
		(net "SDA")
	)
	(segment
		(start 185.07648 88.73686)
		(end 185.07648 86.96582)
		(width 0.2032)
		(layer "B.Cu")
		(net "SDA")
	)
	(segment
		(start 196.3761 87.0786)
		(end 197.7261 85.7286)
		(width 0.2032)
		(layer "B.Cu")
		(net "SDA")
	)
	(segment
		(start 199.2261 82.2162)
		(end 199.9261 82.9162)
		(width 0.2032)
		(layer "B.Cu")
		(net "SDA")
	)
	(segment
		(start 182.7261 88.2162)
		(end 183.24676 88.73686)
		(width 0.2032)
		(layer "B.Cu")
		(net "SDA")
	)
	(segment
		(start 179.1386 86.3287)
		(end 179.1386 84.5911)
		(width 0.2032)
		(layer "B.Cu")
		(net "SDA")
	)
	(segment
		(start 181.0261 88.2162)
		(end 182.7261 88.2162)
		(width 0.2032)
		(layer "B.Cu")
		(net "SDA")
	)
	(segment
		(start 177.64189 100.13199)
		(end 189.0261 111.5162)
		(width 0.2032)
		(layer "B.Cu")
		(net "SDA")
	)
	(segment
		(start 196.3385 87.1162)
		(end 196.3761 87.0786)
		(width 0.2032)
		(layer "B.Cu")
		(net "SDA")
	)
	(segment
		(start 179.1386 86.3287)
		(end 181.0261 88.2162)
		(width 0.2032)
		(layer "B.Cu")
		(net "SDA")
	)
	(segment
		(start 197.7261 85.7286)
		(end 197.7261 84.2162)
		(width 0.2032)
		(layer "B.Cu")
		(net "SDA")
	)
	(segment
		(start 192.7261 97.2162)
		(end 192.7261 89.9162)
		(width 0.2032)
		(layer "B.Cu")
		(net "SDA")
	)
	(segment
		(start 196.21413 97.5162)
		(end 197.75296 99.05503)
		(width 0.2032)
		(layer "B.Cu")
		(net "SDA")
	)
	(segment
		(start 195.5261 87.1162)
		(end 196.3385 87.1162)
		(width 0.2032)
		(layer "B.Cu")
		(net "SDA")
	)
	(segment
		(start 192.7261 89.9162)
		(end 195.5261 87.1162)
		(width 0.2032)
		(layer "B.Cu")
		(net "SDA")
	)
	(segment
		(start 183.24676 88.73686)
		(end 185.07648 88.73686)
		(width 0.2032)
		(layer "B.Cu")
		(net "SDA")
	)
	(segment
		(start 187.9261 84.1162)
		(end 191.4261 84.1162)
		(width 0.2032)
		(layer "B.Cu")
		(net "SDA")
	)
	(segment
		(start 177.64189 100.13199)
		(end 177.64189 99.34439)
		(width 0.2032)
		(layer "B.Cu")
		(net "SDA")
	)
	(segment
		(start 197.7261 84.2162)
		(end 198.4261 83.5162)
		(width 0.2032)
		(layer "B.Cu")
		(net "SDA")
	)
	(segment
		(start 199.9261 83.5162)
		(end 199.9261 82.9162)
		(width 0.2032)
		(layer "B.Cu")
		(net "SDA")
	)
	(segment
		(start 198.4261 83.5162)
		(end 199.9261 83.5162)
		(width 0.2032)
		(layer "B.Cu")
		(net "SDA")
	)
	(segment
		(start 191.4261 84.1162)
		(end 193.3261 82.2162)
		(width 0.2032)
		(layer "B.Cu")
		(net "SDA")
	)
	(segment
		(start 185.07648 86.96582)
		(end 187.9261 84.1162)
		(width 0.2032)
		(layer "B.Cu")
		(net "SDA")
	)
	(segment
		(start 119.8261 91.1162)
		(end 129.5261 91.1162)
		(width 0.2032)
		(layer "In2.Cu")
		(net "SDA")
	)
	(segment
		(start 164.48697 86.45533)
		(end 166.3512 84.5911)
		(width 0.2032)
		(layer "In2.Cu")
		(net "SDA")
	)
	(segment
		(start 96.4261 91.0162)
		(end 108.3261 91.0162)
		(width 0.2032)
		(layer "In2.Cu")
		(net "SDA")
	)
	(segment
		(start 85.28867 92.27877)
		(end 86.1261 93.1162)
		(width 0.2032)
		(layer "In2.Cu")
		(net "SDA")
	)
	(segment
		(start 112.0261 83.3162)
		(end 119.8261 91.1162)
		(width 0.2032)
		(layer "In2.Cu")
		(net "SDA")
	)
	(segment
		(start 129.5261 91.1162)
		(end 129.9261 90.7162)
		(width 0.2032)
		(layer "In2.Cu")
		(net "SDA")
	)
	(segment
		(start 111.1261 88.2162)
		(end 111.1261 83.3162)
		(width 0.2032)
		(layer "In2.Cu")
		(net "SDA")
	)
	(segment
		(start 144.0261 83.6162)
		(end 144.62273 84.21283)
		(width 0.2032)
		(layer "In2.Cu")
		(net "SDA")
	)
	(segment
		(start 85.28867 92.27877)
		(end 85.28867 90.58188)
		(width 0.2032)
		(layer "In2.Cu")
		(net "SDA")
	)
	(segment
		(start 85.28867 90.58188)
		(end 86.55435 89.3162)
		(width 0.2032)
		(layer "In2.Cu")
		(net "SDA")
	)
	(segment
		(start 108.3261 91.0162)
		(end 111.1261 88.2162)
		(width 0.2032)
		(layer "In2.Cu")
		(net "SDA")
	)
	(segment
		(start 94.3261 93.1162)
		(end 96.4261 91.0162)
		(width 0.2032)
		(layer "In2.Cu")
		(net "SDA")
	)
	(segment
		(start 162.8261 89.0162)
		(end 164.48697 87.35533)
		(width 0.2032)
		(layer "In2.Cu")
		(net "SDA")
	)
	(segment
		(start 132.8261 83.6162)
		(end 144.0261 83.6162)
		(width 0.2032)
		(layer "In2.Cu")
		(net "SDA")
	)
	(segment
		(start 129.9261 86.5162)
		(end 132.8261 83.6162)
		(width 0.2032)
		(layer "In2.Cu")
		(net "SDA")
	)
	(segment
		(start 86.55435 89.3162)
		(end 97.8261 89.3162)
		(width 0.2032)
		(layer "In2.Cu")
		(net "SDA")
	)
	(segment
		(start 86.1261 93.1162)
		(end 94.3261 93.1162)
		(width 0.2032)
		(layer "In2.Cu")
		(net "SDA")
	)
	(segment
		(start 97.8261 89.3162)
		(end 101.5261 85.6162)
		(width 0.2032)
		(layer "In2.Cu")
		(net "SDA")
	)
	(segment
		(start 166.3512 84.5911)
		(end 179.1386 84.5911)
		(width 0.2032)
		(layer "In2.Cu")
		(net "SDA")
	)
	(segment
		(start 144.62273 87.11283)
		(end 146.5261 89.0162)
		(width 0.2032)
		(layer "In2.Cu")
		(net "SDA")
	)
	(segment
		(start 146.5261 89.0162)
		(end 162.8261 89.0162)
		(width 0.2032)
		(layer "In2.Cu")
		(net "SDA")
	)
	(segment
		(start 101.5261 85.6162)
		(end 101.6061 85.6162)
		(width 0.2032)
		(layer "In2.Cu")
		(net "SDA")
	)
	(segment
		(start 129.9261 90.7162)
		(end 129.9261 86.5162)
		(width 0.2032)
		(layer "In2.Cu")
		(net "SDA")
	)
	(segment
		(start 164.48697 87.35533)
		(end 164.48697 86.45533)
		(width 0.2032)
		(layer "In2.Cu")
		(net "SDA")
	)
	(segment
		(start 111.1261 83.3162)
		(end 112.0261 83.3162)
		(width 0.2032)
		(layer "In2.Cu")
		(net "SDA")
	)
	(segment
		(start 144.62273 87.11283)
		(end 144.62273 84.21283)
		(width 0.2032)
		(layer "In2.Cu")
		(net "SDA")
	)
	(segment
		(start 194.5261 124.0162)
		(end 194.5261 117.0162)
		(width 0.2032)
		(layer "In3.Cu")
		(net "SDA")
	)
	(segment
		(start 236.4261 111.0162)
		(end 237.5261 109.9162)
		(width 0.2032)
		(layer "In3.Cu")
		(net "SDA")
	)
	(segment
		(start 232.5261 111.6162)
		(end 233.63672 110.50558)
		(width 0.2032)
		(layer "In3.Cu")
		(net "SDA")
	)
	(segment
		(start 197.75296 99.05503)
		(end 202.36493 99.05503)
		(width 0.2032)
		(layer "In3.Cu")
		(net "SDA")
	)
	(segment
		(start 206.7424 103.4325)
		(end 219.2424 103.4325)
		(width 0.2032)
		(layer "In3.Cu")
		(net "SDA")
	)
	(segment
		(start 189.0261 111.5162)
		(end 194.5261 117.0162)
		(width 0.2032)
		(layer "In3.Cu")
		(net "SDA")
	)
	(segment
		(start 237.5261 109.9162)
		(end 237.5261 109.0162)
		(width 0.2032)
		(layer "In3.Cu")
		(net "SDA")
	)
	(segment
		(start 233.7261 108.1503)
		(end 234.092 108.1503)
		(width 0.2032)
		(layer "In3.Cu")
		(net "SDA")
	)
	(segment
		(start 227.4261 111.6162)
		(end 232.5261 111.6162)
		(width 0.2032)
		(layer "In3.Cu")
		(net "SDA")
	)
	(segment
		(start 233.7261 110.3162)
		(end 233.7261 108.5162)
		(width 0.2032)
		(layer "In3.Cu")
		(net "SDA")
	)
	(segment
		(start 234.092 108.1503)
		(end 236.6602 108.1503)
		(width 0.2032)
		(layer "In3.Cu")
		(net "SDA")
	)
	(segment
		(start 235.4261 130.6162)
		(end 236.4261 129.6162)
		(width 0.2032)
		(layer "In3.Cu")
		(net "SDA")
	)
	(segment
		(start 236.6602 108.1503)
		(end 237.5261 109.0162)
		(width 0.2032)
		(layer "In3.Cu")
		(net "SDA")
	)
	(segment
		(start 234.6261 131.4162)
		(end 235.4261 130.6162)
		(width 0.2032)
		(layer "In3.Cu")
		(net "SDA")
	)
	(segment
		(start 233.7261 108.5162)
		(end 233.7261 108.1503)
		(width 0.2032)
		(layer "In3.Cu")
		(net "SDA")
	)
	(segment
		(start 236.4261 129.6162)
		(end 236.4261 111.0162)
		(width 0.2032)
		(layer "In3.Cu")
		(net "SDA")
	)
	(segment
		(start 201.9261 131.4162)
		(end 234.6261 131.4162)
		(width 0.2032)
		(layer "In3.Cu")
		(net "SDA")
	)
	(segment
		(start 202.36493 99.05503)
		(end 206.7424 103.4325)
		(width 0.2032)
		(layer "In3.Cu")
		(net "SDA")
	)
	(segment
		(start 219.2424 103.4325)
		(end 227.4261 111.6162)
		(width 0.2032)
		(layer "In3.Cu")
		(net "SDA")
	)
	(segment
		(start 194.5261 124.0162)
		(end 201.9261 131.4162)
		(width 0.2032)
		(layer "In3.Cu")
		(net "SDA")
	)
	(segment
		(start 235.8261 110.4162)
		(end 236.0261 110.2162)
		(width 0.2032)
		(layer "F.Cu")
		(net "SCL")
	)
	(segment
		(start 195.1511 87.8036)
		(end 195.15735 87.80985)
		(width 0.2032)
		(layer "F.Cu")
		(net "SCL")
	)
	(segment
		(start 180.8681 84.63359)
		(end 180.8681 84.5866)
		(width 0.2032)
		(layer "F.Cu")
		(net "SCL")
	)
	(segment
		(start 181.0761 86.01239)
		(end 181.0761 84.84159)
		(width 0.2032)
		(layer "F.Cu")
		(net "SCL")
	)
	(segment
		(start 233.8261 129.4112)
		(end 235.42809 129.4112)
		(width 0.2032)
		(layer "F.Cu")
		(net "SCL")
	)
	(segment
		(start 85.8761 90.7448)
		(end 85.8761 88.8662)
		(width 0.2032)
		(layer "F.Cu")
		(net "SCL")
	)
	(segment
		(start 179.2761 99.6036)
		(end 179.30248 99.57722)
		(width 0.2032)
		(layer "F.Cu")
		(net "SCL")
	)
	(segment
		(start 235.8261 111.2112)
		(end 235.8261 110.4162)
		(width 0.2032)
		(layer "F.Cu")
		(net "SCL")
	)
	(segment
		(start 180.8681 84.63359)
		(end 181.0761 84.84159)
		(width 0.2032)
		(layer "F.Cu")
		(net "SCL")
	)
	(segment
		(start 235.42809 129.4112)
		(end 235.45002 129.43312)
		(width 0.2032)
		(layer "F.Cu")
		(net "SCL")
	)
	(segment
		(start 179.30248 97.94162)
		(end 179.32585 97.91825)
		(width 0.2032)
		(layer "F.Cu")
		(net "SCL")
	)
	(segment
		(start 200.09125 84.51138)
		(end 200.09607 84.5162)
		(width 0.2032)
		(layer "F.Cu")
		(net "SCL")
	)
	(segment
		(start 200.09607 84.5162)
		(end 201.2211 84.5162)
		(width 0.2032)
		(layer "F.Cu")
		(net "SCL")
	)
	(segment
		(start 184.0261 87.4162)
		(end 184.4761 86.9662)
		(width 0.2032)
		(layer "F.Cu")
		(net "SCL")
	)
	(segment
		(start 184.4761 86.9662)
		(end 185.0136 86.9662)
		(width 0.2032)
		(layer "F.Cu")
		(net "SCL")
	)
	(segment
		(start 104.6761 85.0862)
		(end 104.6761 82.9162)
		(width 0.2032)
		(layer "F.Cu")
		(net "SCL")
	)
	(segment
		(start 179.30248 99.57722)
		(end 179.30248 97.94162)
		(width 0.2032)
		(layer "F.Cu")
		(net "SCL")
	)
	(segment
		(start 85.8761 88.8662)
		(end 86.1261 88.6162)
		(width 0.2032)
		(layer "F.Cu")
		(net "SCL")
	)
	(segment
		(start 104.1461 85.6162)
		(end 104.6761 85.0862)
		(width 0.2032)
		(layer "F.Cu")
		(net "SCL")
	)
	(segment
		(start 196.35735 87.80985)
		(end 196.3636 87.8161)
		(width 0.2032)
		(layer "F.Cu")
		(net "SCL")
	)
	(segment
		(start 86.1261 88.6162)
		(end 87.0511 88.6162)
		(width 0.2032)
		(layer "F.Cu")
		(net "SCL")
	)
	(segment
		(start 195.15735 87.80985)
		(end 196.35735 87.80985)
		(width 0.2032)
		(layer "F.Cu")
		(net "SCL")
	)
	(via
		(at 235.45002 129.43312)
		(size 0.4064)
		(drill 0.2032)
		(layers "F.Cu" "B.Cu")
		(net "SCL")
	)
	(via
		(at 179.2761 99.6036)
		(size 0.4064)
		(drill 0.2032)
		(layers "F.Cu" "B.Cu")
		(tenting
			(front yes)
			(back yes)
		)
		(net "SCL")
	)
	(via
		(at 236.0261 110.2162)
		(size 0.4064)
		(drill 0.2032)
		(layers "F.Cu" "B.Cu")
		(net "SCL")
	)
	(via
		(at 190.2261 111.7162)
		(size 0.4064)
		(drill 0.2032)
		(layers "F.Cu" "B.Cu")
		(net "SCL")
	)
	(via
		(at 198.51925 99.87738)
		(size 0.4064)
		(drill 0.2032)
		(layers "F.Cu" "B.Cu")
		(net "SCL")
	)
	(via
		(at 85.8761 90.7448)
		(size 0.4064)
		(drill 0.2032)
		(layers "F.Cu" "B.Cu")
		(tenting
			(front yes)
			(back yes)
		)
		(net "SCL")
	)
	(via
		(at 196.3636 87.8161)
		(size 0.4064)
		(drill 0.2032)
		(layers "F.Cu" "B.Cu")
		(tenting
			(front yes)
			(back yes)
		)
		(net "SCL")
	)
	(via
		(at 180.8681 84.5866)
		(size 0.4064)
		(drill 0.2032)
		(layers "F.Cu" "B.Cu")
		(tenting
			(front yes)
			(back yes)
		)
		(net "SCL")
	)
	(via
		(at 200.09125 84.51138)
		(size 0.4064)
		(drill 0.2032)
		(layers "F.Cu" "B.Cu")
		(net "SCL")
	)
	(via
		(at 184.0261 87.4162)
		(size 0.4064)
		(drill 0.2032)
		(layers "F.Cu" "B.Cu")
		(net "SCL")
	)
	(segment
		(start 198.6261 80.6162)
		(end 200.6261 82.6162)
		(width 0.2032)
		(layer "B.Cu")
		(net "SCL")
	)
	(segment
		(start 195.4261 96.1162)
		(end 195.4261 89.7162)
		(width 0.2032)
		(layer "B.Cu")
		(net "SCL")
	)
	(segment
		(start 198.8261 88.3162)
		(end 200.09125 87.05105)
		(width 0.2032)
		(layer "B.Cu")
		(net "SCL")
	)
	(segment
		(start 195.4261 89.7162)
		(end 196.3636 88.7787)
		(width 0.2032)
		(layer "B.Cu")
		(net "SCL")
	)
	(segment
		(start 183.4261 85.8162)
		(end 183.7261 85.5162)
		(width 0.2032)
		(layer "B.Cu")
		(net "SCL")
	)
	(segment
		(start 197.526 87.8161)
		(end 198.0261 88.3162)
		(width 0.2032)
		(layer "B.Cu")
		(net "SCL")
	)
	(segment
		(start 182.2261 87.4162)
		(end 184.0261 87.4162)
		(width 0.2032)
		(layer "B.Cu")
		(net "SCL")
	)
	(segment
		(start 198.0261 88.3162)
		(end 198.8261 88.3162)
		(width 0.2032)
		(layer "B.Cu")
		(net "SCL")
	)
	(segment
		(start 185.1261 85.5162)
		(end 190.0261 80.6162)
		(width 0.2032)
		(layer "B.Cu")
		(net "SCL")
	)
	(segment
		(start 200.6261 83.97653)
		(end 200.6261 82.6162)
		(width 0.2032)
		(layer "B.Cu")
		(net "SCL")
	)
	(segment
		(start 183.7261 85.5162)
		(end 185.1261 85.5162)
		(width 0.2032)
		(layer "B.Cu")
		(net "SCL")
	)
	(segment
		(start 195.4261 96.1162)
		(end 196.1261 96.8162)
		(width 0.2032)
		(layer "B.Cu")
		(net "SCL")
	)
	(segment
		(start 183.4261 86.4162)
		(end 184.0261 87.0162)
		(width 0.2032)
		(layer "B.Cu")
		(net "SCL")
	)
	(segment
		(start 200.09125 84.51138)
		(end 200.6261 83.97653)
		(width 0.2032)
		(layer "B.Cu")
		(net "SCL")
	)
	(segment
		(start 196.3636 88.7787)
		(end 196.3636 87.8161)
		(width 0.2032)
		(layer "B.Cu")
		(net "SCL")
	)
	(segment
		(start 179.2761 100.7662)
		(end 179.2761 99.6036)
		(width 0.2032)
		(layer "B.Cu")
		(net "SCL")
	)
	(segment
		(start 198.51925 99.87738)
		(end 198.51925 98.60935)
		(width 0.2032)
		(layer "B.Cu")
		(net "SCL")
	)
	(segment
		(start 179.2761 100.7662)
		(end 190.2261 111.7162)
		(width 0.2032)
		(layer "B.Cu")
		(net "SCL")
	)
	(segment
		(start 190.0261 80.6162)
		(end 198.6261 80.6162)
		(width 0.2032)
		(layer "B.Cu")
		(net "SCL")
	)
	(segment
		(start 183.4261 86.4162)
		(end 183.4261 85.8162)
		(width 0.2032)
		(layer "B.Cu")
		(net "SCL")
	)
	(segment
		(start 196.1261 96.8162)
		(end 196.7261 96.8162)
		(width 0.2032)
		(layer "B.Cu")
		(net "SCL")
	)
	(segment
		(start 200.09125 87.05105)
		(end 200.09125 84.51138)
		(width 0.2032)
		(layer "B.Cu")
		(net "SCL")
	)
	(segment
		(start 180.8681 86.0582)
		(end 180.8681 84.5866)
		(width 0.2032)
		(layer "B.Cu")
		(net "SCL")
	)
	(segment
		(start 184.0261 87.4162)
		(end 184.0261 87.0162)
		(width 0.2032)
		(layer "B.Cu")
		(net "SCL")
	)
	(segment
		(start 180.8681 86.0582)
		(end 182.2261 87.4162)
		(width 0.2032)
		(layer "B.Cu")
		(net "SCL")
	)
	(segment
		(start 196.3636 87.8161)
		(end 197.526 87.8161)
		(width 0.2032)
		(layer "B.Cu")
		(net "SCL")
	)
	(segment
		(start 196.7261 96.8162)
		(end 198.51925 98.60935)
		(width 0.2032)
		(layer "B.Cu")
		(net "SCL")
	)
	(segment
		(start 145.0261 86.0162)
		(end 145.0261 83.6162)
		(width 0.2032)
		(layer "In2.Cu")
		(net "SCL")
	)
	(segment
		(start 145.0261 86.0162)
		(end 147.6261 88.6162)
		(width 0.2032)
		(layer "In2.Cu")
		(net "SCL")
	)
	(segment
		(start 129.3261 86.2162)
		(end 132.4261 83.1162)
		(width 0.2032)
		(layer "In2.Cu")
		(net "SCL")
	)
	(segment
		(start 165.56158 84.08071)
		(end 165.59547 84.08071)
		(width 0.2032)
		(layer "In2.Cu")
		(net "SCL")
	)
	(segment
		(start 87.0975 90.7448)
		(end 88.0261 89.8162)
		(width 0.2032)
		(layer "In2.Cu")
		(net "SCL")
	)
	(segment
		(start 88.0261 89.8162)
		(end 99.9461 89.8162)
		(width 0.2032)
		(layer "In2.Cu")
		(net "SCL")
	)
	(segment
		(start 164.63267 85.70963)
		(end 164.63267 85.00963)
		(width 0.2032)
		(layer "In2.Cu")
		(net "SCL")
	)
	(segment
		(start 147.6261 88.6162)
		(end 161.7261 88.6162)
		(width 0.2032)
		(layer "In2.Cu")
		(net "SCL")
	)
	(segment
		(start 164.63267 85.00963)
		(end 165.56158 84.08071)
		(width 0.2032)
		(layer "In2.Cu")
		(net "SCL")
	)
	(segment
		(start 85.8761 90.7448)
		(end 87.0975 90.7448)
		(width 0.2032)
		(layer "In2.Cu")
		(net "SCL")
	)
	(segment
		(start 107.0261 90.3162)
		(end 107.8261 89.5162)
		(width 0.2032)
		(layer "In2.Cu")
		(net "SCL")
	)
	(segment
		(start 119.9261 90.2162)
		(end 129.3261 90.2162)
		(width 0.2032)
		(layer "In2.Cu")
		(net "SCL")
	)
	(segment
		(start 165.59547 84.08071)
		(end 165.65998 84.0162)
		(width 0.2032)
		(layer "In2.Cu")
		(net "SCL")
	)
	(segment
		(start 85.8761 91.5662)
		(end 85.8761 90.7448)
		(width 0.2032)
		(layer "In2.Cu")
		(net "SCL")
	)
	(segment
		(start 112.0261 82.3162)
		(end 119.9261 90.2162)
		(width 0.2032)
		(layer "In2.Cu")
		(net "SCL")
	)
	(segment
		(start 180.2977 84.0162)
		(end 180.8681 84.5866)
		(width 0.2032)
		(layer "In2.Cu")
		(net "SCL")
	)
	(segment
		(start 85.8761 91.5662)
		(end 86.7261 92.4162)
		(width 0.2032)
		(layer "In2.Cu")
		(net "SCL")
	)
	(segment
		(start 96.2261 90.3162)
		(end 107.0261 90.3162)
		(width 0.2032)
		(layer "In2.Cu")
		(net "SCL")
	)
	(segment
		(start 99.9461 89.8162)
		(end 104.1461 85.6162)
		(width 0.2032)
		(layer "In2.Cu")
		(net "SCL")
	)
	(segment
		(start 161.7261 88.6162)
		(end 164.63267 85.70963)
		(width 0.2032)
		(layer "In2.Cu")
		(net "SCL")
	)
	(segment
		(start 132.4261 83.1162)
		(end 144.5261 83.1162)
		(width 0.2032)
		(layer "In2.Cu")
		(net "SCL")
	)
	(segment
		(start 107.8261 84.3162)
		(end 109.8261 82.3162)
		(width 0.2032)
		(layer "In2.Cu")
		(net "SCL")
	)
	(segment
		(start 107.8261 89.5162)
		(end 107.8261 84.3162)
		(width 0.2032)
		(layer "In2.Cu")
		(net "SCL")
	)
	(segment
		(start 144.5261 83.1162)
		(end 145.0261 83.6162)
		(width 0.2032)
		(layer "In2.Cu")
		(net "SCL")
	)
	(segment
		(start 129.3261 90.2162)
		(end 129.3261 86.2162)
		(width 0.2032)
		(layer "In2.Cu")
		(net "SCL")
	)
	(segment
		(start 109.8261 82.3162)
		(end 112.0261 82.3162)
		(width 0.2032)
		(layer "In2.Cu")
		(net "SCL")
	)
	(segment
		(start 165.65998 84.0162)
		(end 180.2977 84.0162)
		(width 0.2032)
		(layer "In2.Cu")
		(net "SCL")
	)
	(segment
		(start 94.1261 92.4162)
		(end 96.2261 90.3162)
		(width 0.2032)
		(layer "In2.Cu")
		(net "SCL")
	)
	(segment
		(start 86.7261 92.4162)
		(end 94.1261 92.4162)
		(width 0.2032)
		(layer "In2.Cu")
		(net "SCL")
	)
	(segment
		(start 206.56423 103.85433)
		(end 216.66424 103.85433)
		(width 0.2032)
		(layer "In3.Cu")
		(net "SCL")
	)
	(segment
		(start 235.9261 124.2162)
		(end 235.9261 110.3162)
		(width 0.2032)
		(layer "In3.Cu")
		(net "SCL")
	)
	(segment
		(start 225.3261 112.5162)
		(end 232.8261 112.5162)
		(width 0.2032)
		(layer "In3.Cu")
		(net "SCL")
	)
	(segment
		(start 235.45002 124.69228)
		(end 235.9261 124.2162)
		(width 0.2032)
		(layer "In3.Cu")
		(net "SCL")
	)
	(segment
		(start 198.51925 99.87738)
		(end 202.58728 99.87738)
		(width 0.2032)
		(layer "In3.Cu")
		(net "SCL")
	)
	(segment
		(start 195.8261 124.6162)
		(end 199.8261 128.6162)
		(width 0.2032)
		(layer "In3.Cu")
		(net "SCL")
	)
	(segment
		(start 234.63309 128.6162)
		(end 235.45002 129.43312)
		(width 0.2032)
		(layer "In3.Cu")
		(net "SCL")
	)
	(segment
		(start 235.4261 109.9162)
		(end 236.1261 109.9162)
		(width 0.2032)
		(layer "In3.Cu")
		(net "SCL")
	)
	(segment
		(start 236.1261 110.1162)
		(end 236.1261 109.9162)
		(width 0.2032)
		(layer "In3.Cu")
		(net "SCL")
	)
	(segment
		(start 235.45002 129.43312)
		(end 235.45002 124.69228)
		(width 0.2032)
		(layer "In3.Cu")
		(net "SCL")
	)
	(segment
		(start 216.66424 103.85433)
		(end 225.3261 112.5162)
		(width 0.2032)
		(layer "In3.Cu")
		(net "SCL")
	)
	(segment
		(start 202.58728 99.87738)
		(end 206.56423 103.85433)
		(width 0.2032)
		(layer "In3.Cu")
		(net "SCL")
	)
	(segment
		(start 235.9261 110.3162)
		(end 236.1261 110.1162)
		(width 0.2032)
		(layer "In3.Cu")
		(net "SCL")
	)
	(segment
		(start 232.8261 112.5162)
		(end 235.4261 109.9162)
		(width 0.2032)
		(layer "In3.Cu")
		(net "SCL")
	)
	(segment
		(start 195.8261 124.6162)
		(end 195.8261 117.3162)
		(width 0.2032)
		(layer "In3.Cu")
		(net "SCL")
	)
	(segment
		(start 199.8261 128.6162)
		(end 234.63309 128.6162)
		(width 0.2032)
		(layer "In3.Cu")
		(net "SCL")
	)
	(segment
		(start 190.2261 111.7162)
		(end 195.8261 117.3162)
		(width 0.2032)
		(layer "In3.Cu")
		(net "SCL")
	)
	(segment
		(start 210.2261 142.4162)
		(end 210.2661 142.3762)
		(width 0.2032)
		(layer "F.Cu")
		(net "NetR19_2")
	)
	(segment
		(start 200.31136 143.47763)
		(end 202.74993 145.9162)
		(width 0.2032)
		(layer "F.Cu")
		(net "NetR19_2")
	)
	(segment
		(start 209.5261 145.9162)
		(end 210.2661 145.1762)
		(width 0.2032)
		(layer "F.Cu")
		(net "NetR19_2")
	)
	(segment
		(start 202.74993 145.9162)
		(end 209.5261 145.9162)
		(width 0.2032)
		(layer "F.Cu")
		(net "NetR19_2")
	)
	(segment
		(start 210.2661 145.1762)
		(end 210.2661 142.3762)
		(width 0.2032)
		(layer "F.Cu")
		(net "NetR19_2")
	)
	(segment
		(start 236.72395 137.2162)
		(end 236.92395 137.0162)
		(width 0.2032)
		(layer "F.Cu")
		(net "NetD4_1")
	)
	(segment
		(start 234.7761 137.2162)
		(end 236.72395 137.2162)
		(width 0.2032)
		(layer "F.Cu")
		(net "NetD4_1")
	)
	(segment
		(start 124.54608 157.7576)
		(end 124.5791 157.72458)
		(width 0.2032)
		(layer "B.Cu")
		(net "NetC49_1")
	)
	(segment
		(start 124.5791 156.9506)
		(end 124.5791 152.2186)
		(width 0.127)
		(layer "B.Cu")
		(net "NetC49_1")
	)
	(arc
		(start 124.5791 157.67788)
		(mid 124.570518 157.721024)
		(end 124.546079 157.757599)
		(width 0.127)
		(layer "B.Cu")
		(net "NetC49_1")
	)
	(arc
		(start 124.5791 156.9506)
		(mid 124.565321 157.019873)
		(end 124.52608 157.0786)
		(width 0.127)
		(layer "B.Cu")
		(net "NetC49_1")
	)
	(segment
		(start 218.7761 114.1162)
		(end 219.0761 114.4162)
		(width 0.254)
		(layer "F.Cu")
		(net "NetC3_2")
	)
	(segment
		(start 217.7011 115.0912)
		(end 217.7011 114.1162)
		(width 0.254)
		(layer "F.Cu")
		(net "NetC3_2")
	)
	(segment
		(start 217.7011 114.1162)
		(end 218.7761 114.1162)
		(width 0.254)
		(layer "F.Cu")
		(net "NetC3_2")
	)
	(segment
		(start 209.3894 106.93006)
		(end 209.3894 106.1795)
		(width 0.254)
		(layer "F.Cu")
		(net "NetC3_2")
	)
	(segment
		(start 217.7011 115.0912)
		(end 217.7261 115.1162)
		(width 0.254)
		(layer "F.Cu")
		(net "NetC3_2")
	)
	(segment
		(start 208.8261 105.6162)
		(end 209.3894 106.1795)
		(width 0.254)
		(layer "F.Cu")
		(net "NetC3_2")
	)
	(via
		(at 217.7261 115.1162)
		(size 0.4064)
		(drill 0.2032)
		(layers "F.Cu" "B.Cu")
		(net "NetC3_2")
	)
	(via
		(at 208.8261 105.6162)
		(size 0.4064)
		(drill 0.2032)
		(layers "F.Cu" "B.Cu")
		(net "NetC3_2")
	)
	(segment
		(start 208.8261 107.4162)
		(end 212.2261 110.8162)
		(width 0.254)
		(layer "B.Cu")
		(net "NetC3_2")
	)
	(segment
		(start 215.5261 110.8162)
		(end 217.7261 113.0162)
		(width 0.254)
		(layer "B.Cu")
		(net "NetC3_2")
	)
	(segment
		(start 208.8261 107.4162)
		(end 208.8261 105.6162)
		(width 0.254)
		(layer "B.Cu")
		(net "NetC3_2")
	)
	(segment
		(start 212.2261 110.8162)
		(end 215.5261 110.8162)
		(width 0.254)
		(layer "B.Cu")
		(net "NetC3_2")
	)
	(segment
		(start 217.7261 115.1162)
		(end 217.7261 113.0162)
		(width 0.254)
		(layer "B.Cu")
		(net "NetC3_2")
	)
	(segment
		(start 220.3261 116.0162)
		(end 220.5761 115.7662)
		(width 0.254)
		(layer "F.Cu")
		(net "NetC3_1")
	)
	(segment
		(start 220.5761 114.4162)
		(end 222.1711 114.4162)
		(width 0.254)
		(layer "F.Cu")
		(net "NetC3_1")
	)
	(segment
		(start 220.5761 115.7662)
		(end 220.5761 114.4162)
		(width 0.254)
		(layer "F.Cu")
		(net "NetC3_1")
	)
	(segment
		(start 222.1711 114.4162)
		(end 222.2711 114.5162)
		(width 0.254)
		(layer "F.Cu")
		(net "NetC3_1")
	)
	(segment
		(start 164.32588 93.86847)
		(end 164.32588 92.00382)
		(width 0.2032)
		(layer "F.Cu")
		(net "MAC_USB_PWR")
	)
	(segment
		(start 164.32588 92.00382)
		(end 164.36242 91.96728)
		(width 0.2032)
		(layer "F.Cu")
		(net "MAC_USB_PWR")
	)
	(segment
		(start 143.04047 113.90183)
		(end 143.04047 113.88948)
		(width 0.2032)
		(layer "F.Cu")
		(net "MAC_USB_PWR")
	)
	(segment
		(start 143.00138 113.94092)
		(end 143.04047 113.90183)
		(width 0.2032)
		(layer "F.Cu")
		(net "MAC_USB_PWR")
	)
	(segment
		(start 141.66107 113.94092)
		(end 143.00138 113.94092)
		(width 0.2032)
		(layer "F.Cu")
		(net "MAC_USB_PWR")
	)
	(via
		(at 164.36242 91.96728)
		(size 0.4064)
		(drill 0.2032)
		(layers "F.Cu" "B.Cu")
		(tenting
			(front yes)
			(back yes)
		)
		(net "MAC_USB_PWR")
	)
	(via
		(at 157.6181 106.1162)
		(size 0.4064)
		(drill 0.2032)
		(layers "F.Cu" "B.Cu")
		(tenting
			(front yes)
			(back yes)
		)
		(net "MAC_USB_PWR")
	)
	(via
		(at 143.04047 113.88948)
		(size 0.4064)
		(drill 0.2032)
		(layers "F.Cu" "B.Cu")
		(net "MAC_USB_PWR")
	)
	(segment
		(start 141.2261 113.1162)
		(end 141.99938 113.88948)
		(width 0.2032)
		(layer "B.Cu")
		(net "MAC_USB_PWR")
	)
	(segment
		(start 141.99938 113.88948)
		(end 143.04047 113.88948)
		(width 0.2032)
		(layer "B.Cu")
		(net "MAC_USB_PWR")
	)
	(segment
		(start 157.4181 105.9162)
		(end 157.6181 106.1162)
		(width 0.2032)
		(layer "B.Cu")
		(net "MAC_USB_PWR")
	)
	(segment
		(start 141.2261 113.1162)
		(end 141.2261 109.6162)
		(width 0.2032)
		(layer "B.Cu")
		(net "MAC_USB_PWR")
	)
	(segment
		(start 141.2261 109.6162)
		(end 144.9261 105.9162)
		(width 0.2032)
		(layer "B.Cu")
		(net "MAC_USB_PWR")
	)
	(segment
		(start 144.9261 105.9162)
		(end 157.4181 105.9162)
		(width 0.2032)
		(layer "B.Cu")
		(net "MAC_USB_PWR")
	)
	(segment
		(start 162.23742 91.96728)
		(end 164.36242 91.96728)
		(width 0.2032)
		(layer "In2.Cu")
		(net "MAC_USB_PWR")
	)
	(segment
		(start 157.6261 96.5786)
		(end 162.23742 91.96728)
		(width 0.2032)
		(layer "In2.Cu")
		(net "MAC_USB_PWR")
	)
	(segment
		(start 157.6181 106.1162)
		(end 157.6261 106.1082)
		(width 0.2032)
		(layer "In2.Cu")
		(net "MAC_USB_PWR")
	)
	(segment
		(start 157.6261 106.1082)
		(end 157.6261 96.5786)
		(width 0.2032)
		(layer "In2.Cu")
		(net "MAC_USB_PWR")
	)
	(segment
		(start 180.82572 92.5958)
		(end 181.06552 92.35601)
		(width 0.2032)
		(layer "F.Cu")
		(net "MAC_USB-")
	)
	(segment
		(start 142.69631 113.43292)
		(end 142.98794 113.14128)
		(width 0.2032)
		(layer "F.Cu")
		(net "MAC_USB-")
	)
	(segment
		(start 181.06552 92.35601)
		(end 181.06552 92.30102)
		(width 0.2032)
		(layer "F.Cu")
		(net "MAC_USB-")
	)
	(segment
		(start 141.66107 113.43292)
		(end 142.69631 113.43292)
		(width 0.2032)
		(layer "F.Cu")
		(net "MAC_USB-")
	)
	(segment
		(start 180.82572 93.86847)
		(end 180.82572 92.5958)
		(width 0.2032)
		(layer "F.Cu")
		(net "MAC_USB-")
	)
	(segment
		(start 142.98794 113.14128)
		(end 142.98794 113.03647)
		(width 0.2032)
		(layer "F.Cu")
		(net "MAC_USB-")
	)
	(via
		(at 159.1181 106.8662)
		(size 0.4064)
		(drill 0.2032)
		(layers "F.Cu" "B.Cu")
		(tenting
			(front yes)
			(back yes)
		)
		(net "MAC_USB-")
	)
	(via
		(at 181.06552 92.30102)
		(size 0.4064)
		(drill 0.2032)
		(layers "F.Cu" "B.Cu")
		(tenting
			(front yes)
			(back yes)
		)
		(net "MAC_USB-")
	)
	(via
		(at 142.98794 113.03647)
		(size 0.4064)
		(drill 0.2032)
		(layers "F.Cu" "B.Cu")
		(net "MAC_USB-")
	)
	(segment
		(start 142.3261 112.37462)
		(end 142.98794 113.03647)
		(width 0.2032)
		(layer "B.Cu")
		(net "MAC_USB-")
	)
	(segment
		(start 144.8661 108.6162)
		(end 157.3681 108.6162)
		(width 0.2032)
		(layer "B.Cu")
		(net "MAC_USB-")
	)
	(segment
		(start 181.06552 92.30102)
		(end 181.09581 92.33131)
		(width 0.2032)
		(layer "B.Cu")
		(net "MAC_USB-")
	)
	(segment
		(start 142.3261 112.37462)
		(end 142.3261 111.1562)
		(width 0.2032)
		(layer "B.Cu")
		(net "MAC_USB-")
	)
	(arc
		(start 159.1181 106.8662)
		(mid 158.605537 108.103637)
		(end 157.3681 108.6162)
		(width 0.2032)
		(layer "B.Cu")
		(net "MAC_USB-")
	)
	(arc
		(start 142.3261 111.1562)
		(mid 143.070049 109.360149)
		(end 144.8661 108.6162)
		(width 0.2032)
		(layer "B.Cu")
		(net "MAC_USB-")
	)
	(segment
		(start 177.0885 106.8662)
		(end 181.06552 102.88918)
		(width 0.2032)
		(layer "In2.Cu")
		(net "MAC_USB-")
	)
	(segment
		(start 159.1181 106.8662)
		(end 177.0885 106.8662)
		(width 0.2032)
		(layer "In2.Cu")
		(net "MAC_USB-")
	)
	(segment
		(start 181.06552 102.88918)
		(end 181.06552 92.30102)
		(width 0.2032)
		(layer "In2.Cu")
		(net "MAC_USB-")
	)
	(segment
		(start 142.39667 112.92492)
		(end 143.00975 112.31184)
		(width 0.2032)
		(layer "F.Cu")
		(net "MAC_USB+")
	)
	(segment
		(start 180.31348 93.8561)
		(end 180.32585 93.86847)
		(width 0.2032)
		(layer "F.Cu")
		(net "MAC_USB+")
	)
	(segment
		(start 180.31348 93.8561)
		(end 180.31348 91.64098)
		(width 0.2032)
		(layer "F.Cu")
		(net "MAC_USB+")
	)
	(segment
		(start 180.3011 91.6286)
		(end 180.31348 91.64098)
		(width 0.2032)
		(layer "F.Cu")
		(net "MAC_USB+")
	)
	(segment
		(start 141.66107 112.92492)
		(end 142.39667 112.92492)
		(width 0.2032)
		(layer "F.Cu")
		(net "MAC_USB+")
	)
	(via
		(at 143.00975 112.31184)
		(size 0.4064)
		(drill 0.2032)
		(layers "F.Cu" "B.Cu")
		(net "MAC_USB+")
	)
	(via
		(at 180.3011 91.6286)
		(size 0.4064)
		(drill 0.2032)
		(layers "F.Cu" "B.Cu")
		(tenting
			(front yes)
			(back yes)
		)
		(net "MAC_USB+")
	)
	(via
		(at 159.6261 106.3582)
		(size 0.4064)
		(drill 0.2032)
		(layers "F.Cu" "B.Cu")
		(tenting
			(front yes)
			(back yes)
		)
		(net "MAC_USB+")
	)
	(segment
		(start 145.0261 109.1162)
		(end 157.0861 109.1162)
		(width 0.2032)
		(layer "B.Cu")
		(net "MAC_USB+")
	)
	(segment
		(start 143.00975 112.31184)
		(end 143.00975 111.13255)
		(width 0.2032)
		(layer "B.Cu")
		(net "MAC_USB+")
	)
	(segment
		(start 159.6261 106.5762)
		(end 159.6261 106.3582)
		(width 0.2032)
		(layer "B.Cu")
		(net "MAC_USB+")
	)
	(arc
		(start 159.6261 106.5762)
		(mid 158.882151 108.372251)
		(end 157.0861 109.1162)
		(width 0.2032)
		(layer "B.Cu")
		(net "MAC_USB+")
	)
	(arc
		(start 143.00975 111.13255)
		(mid 143.600325 109.706775)
		(end 145.0261 109.1162)
		(width 0.2032)
		(layer "B.Cu")
		(net "MAC_USB+")
	)
	(segment
		(start 180.5261 102.7286)
		(end 180.5261 91.8536)
		(width 0.2032)
		(layer "In2.Cu")
		(net "MAC_USB+")
	)
	(segment
		(start 180.3011 91.6286)
		(end 180.5261 91.8536)
		(width 0.2032)
		(layer "In2.Cu")
		(net "MAC_USB+")
	)
	(segment
		(start 176.8965 106.3582)
		(end 180.5261 102.7286)
		(width 0.2032)
		(layer "In2.Cu")
		(net "MAC_USB+")
	)
	(segment
		(start 159.6261 106.3582)
		(end 176.8965 106.3582)
		(width 0.2032)
		(layer "In2.Cu")
		(net "MAC_USB+")
	)
	(segment
		(start 168.81689 91.73781)
		(end 168.82132 91.74224)
		(width 0.2032)
		(layer "F.Cu")
		(net "MAC_TX")
	)
	(segment
		(start 168.82132 93.86405)
		(end 168.82575 93.86847)
		(width 0.2032)
		(layer "F.Cu")
		(net "MAC_TX")
	)
	(segment
		(start 168.82132 93.86405)
		(end 168.82132 91.74224)
		(width 0.2032)
		(layer "F.Cu")
		(net "MAC_TX")
	)
	(via
		(at 167.7261 105.1162)
		(size 0.4064)
		(drill 0.2032)
		(layers "F.Cu" "B.Cu")
		(net "MAC_TX")
	)
	(via
		(at 168.81689 91.73781)
		(size 0.4064)
		(drill 0.2032)
		(layers "F.Cu" "B.Cu")
		(tenting
			(front yes)
			(back yes)
		)
		(net "MAC_TX")
	)
	(segment
		(start 168.81689 92.90699)
		(end 168.81689 91.73781)
		(width 0.2032)
		(layer "In2.Cu")
		(net "MAC_TX")
	)
	(segment
		(start 170.7261 97.58634)
		(end 170.7261 94.8162)
		(width 0.2032)
		(layer "In2.Cu")
		(net "MAC_TX")
	)
	(segment
		(start 170.7261 97.58634)
		(end 172.0924 98.95264)
		(width 0.2032)
		(layer "In2.Cu")
		(net "MAC_TX")
	)
	(segment
		(start 168.81689 92.90699)
		(end 170.7261 94.8162)
		(width 0.2032)
		(layer "In2.Cu")
		(net "MAC_TX")
	)
	(segment
		(start 172.0924 100.7499)
		(end 172.0924 98.95264)
		(width 0.2032)
		(layer "In2.Cu")
		(net "MAC_TX")
	)
	(segment
		(start 167.7261 105.1162)
		(end 172.0924 100.7499)
		(width 0.2032)
		(layer "In2.Cu")
		(net "MAC_TX")
	)
	(segment
		(start 131.8261 131.8162)
		(end 137.1261 126.5162)
		(width 0.2032)
		(layer "In3.Cu")
		(net "MAC_TX")
	)
	(segment
		(start 131.8261 138.2162)
		(end 131.8261 131.8162)
		(width 0.2032)
		(layer "In3.Cu")
		(net "MAC_TX")
	)
	(segment
		(start 156.1261 126.5162)
		(end 167.7261 114.9162)
		(width 0.2032)
		(layer "In3.Cu")
		(net "MAC_TX")
	)
	(segment
		(start 167.7261 114.9162)
		(end 167.7261 105.1162)
		(width 0.2032)
		(layer "In3.Cu")
		(net "MAC_TX")
	)
	(segment
		(start 137.1261 126.5162)
		(end 156.1261 126.5162)
		(width 0.2032)
		(layer "In3.Cu")
		(net "MAC_TX")
	)
	(segment
		(start 169.5261 91.78359)
		(end 169.5261 91.7286)
		(width 0.2032)
		(layer "F.Cu")
		(net "MAC_RX")
	)
	(segment
		(start 169.32587 91.98382)
		(end 169.5261 91.78359)
		(width 0.2032)
		(layer "F.Cu")
		(net "MAC_RX")
	)
	(segment
		(start 169.32587 93.86847)
		(end 169.32587 91.98382)
		(width 0.2032)
		(layer "F.Cu")
		(net "MAC_RX")
	)
	(via
		(at 169.00212 105.04772)
		(size 0.4064)
		(drill 0.2032)
		(layers "F.Cu" "B.Cu")
		(net "MAC_RX")
	)
	(via
		(at 169.5261 91.7286)
		(size 0.4064)
		(drill 0.2032)
		(layers "F.Cu" "B.Cu")
		(tenting
			(front yes)
			(back yes)
		)
		(net "MAC_RX")
	)
	(segment
		(start 173.5261 96.4162)
		(end 173.5261 94.9536)
		(width 0.2032)
		(layer "In2.Cu")
		(net "MAC_RX")
	)
	(segment
		(start 169.5261 91.7286)
		(end 170.3011 91.7286)
		(width 0.2032)
		(layer "In2.Cu")
		(net "MAC_RX")
	)
	(segment
		(start 169.00212 105.04772)
		(end 173.43364 100.6162)
		(width 0.2032)
		(layer "In2.Cu")
		(net "MAC_RX")
	)
	(segment
		(start 173.43364 100.6162)
		(end 174.7261 100.6162)
		(width 0.2032)
		(layer "In2.Cu")
		(net "MAC_RX")
	)
	(segment
		(start 170.3011 91.7286)
		(end 173.5261 94.9536)
		(width 0.2032)
		(layer "In2.Cu")
		(net "MAC_RX")
	)
	(segment
		(start 174.7261 100.6162)
		(end 175.0261 100.3162)
		(width 0.2032)
		(layer "In2.Cu")
		(net "MAC_RX")
	)
	(segment
		(start 173.5261 96.4162)
		(end 175.0261 97.9162)
		(width 0.2032)
		(layer "In2.Cu")
		(net "MAC_RX")
	)
	(segment
		(start 175.0261 100.3162)
		(end 175.0261 97.9162)
		(width 0.2032)
		(layer "In2.Cu")
		(net "MAC_RX")
	)
	(segment
		(start 156.5261 127.8162)
		(end 169.0261 115.3162)
		(width 0.2032)
		(layer "In3.Cu")
		(net "MAC_RX")
	)
	(segment
		(start 169.0261 115.3162)
		(end 169.0261 105.07171)
		(width 0.2032)
		(layer "In3.Cu")
		(net "MAC_RX")
	)
	(segment
		(start 169.00212 105.04772)
		(end 169.0261 105.07171)
		(width 0.2032)
		(layer "In3.Cu")
		(net "MAC_RX")
	)
	(segment
		(start 145.2261 127.8162)
		(end 156.5261 127.8162)
		(width 0.2032)
		(layer "In3.Cu")
		(net "MAC_RX")
	)
	(segment
		(start 134.8261 138.2162)
		(end 145.2261 127.8162)
		(width 0.2032)
		(layer "In3.Cu")
		(net "MAC_RX")
	)
	(segment
		(start 136.84539 117.49692)
		(end 137.66107 117.49692)
		(width 0.2032)
		(layer "F.Cu")
		(net "MAC_PPS_OUT-")
	)
	(segment
		(start 136.3261 118.0162)
		(end 136.84539 117.49692)
		(width 0.2032)
		(layer "F.Cu")
		(net "MAC_PPS_OUT-")
	)
	(segment
		(start 113.94853 84.1736)
		(end 116.2761 84.1736)
		(width 0.2032)
		(layer "F.Cu")
		(net "MAC_PPS_OUT-")
	)
	(segment
		(start 112.3761 84.3286)
		(end 113.7511 84.3286)
		(width 0.2032)
		(layer "F.Cu")
		(net "MAC_PPS_OUT-")
	)
	(segment
		(start 113.7511 84.3286)
		(end 113.8761 84.2036)
		(width 0.2032)
		(layer "F.Cu")
		(net "MAC_PPS_OUT-")
	)
	(via
		(at 112.3761 84.3286)
		(size 0.4064)
		(drill 0.2032)
		(layers "F.Cu" "B.Cu")
		(tenting
			(front yes)
			(back yes)
		)
		(net "MAC_PPS_OUT-")
	)
	(via
		(at 136.3261 118.0162)
		(size 0.4064)
		(drill 0.2032)
		(layers "F.Cu" "B.Cu")
		(tenting
			(front yes)
			(back yes)
		)
		(net "MAC_PPS_OUT-")
	)
	(arc
		(start 113.876274 84.203419)
		(mid 113.909445 84.181341)
		(end 113.94853 84.17359)
		(width 0.2032)
		(layer "F.Cu")
		(net "MAC_PPS_OUT-")
	)
	(arc
		(start 113.876101 84.203591)
		(mid 113.876187 84.203505)
		(end 113.876274 84.203419)
		(width 0.2032)
		(layer "F.Cu")
		(net "MAC_PPS_OUT-")
	)
	(segment
		(start 112.67005 100.06015)
		(end 129.78215 117.17225)
		(width 0.2032)
		(layer "In2.Cu")
		(net "MAC_PPS_OUT-")
	)
	(segment
		(start 111.9261 98.26409)
		(end 111.9261 84.7786)
		(width 0.2032)
		(layer "In2.Cu")
		(net "MAC_PPS_OUT-")
	)
	(segment
		(start 131.5782 117.9162)
		(end 136.08467 117.9162)
		(width 0.2032)
		(layer "In2.Cu")
		(net "MAC_PPS_OUT-")
	)
	(arc
		(start 111.9261 84.7786)
		(mid 112.057902 84.460402)
		(end 112.3761 84.3286)
		(width 0.2032)
		(layer "In2.Cu")
		(net "MAC_PPS_OUT-")
	)
	(arc
		(start 136.08467 117.9162)
		(mid 136.21533 117.94219)
		(end 136.326097 118.016203)
		(width 0.2032)
		(layer "In2.Cu")
		(net "MAC_PPS_OUT-")
	)
	(arc
		(start 112.670049 100.060141)
		(mid 112.119446 99.236106)
		(end 111.9261 98.26409)
		(width 0.2032)
		(layer "In2.Cu")
		(net "MAC_PPS_OUT-")
	)
	(arc
		(start 131.5782 117.9162)
		(mid 130.606184 117.722854)
		(end 129.782149 117.172251)
		(width 0.2032)
		(layer "In2.Cu")
		(net "MAC_PPS_OUT-")
	)
	(segment
		(start 113.90024 85.4436)
		(end 116.2761 85.4436)
		(width 0.2032)
		(layer "F.Cu")
		(net "MAC_PPS_OUT+")
	)
	(segment
		(start 112.3761 85.5786)
		(end 113.7511 85.5786)
		(width 0.2032)
		(layer "F.Cu")
		(net "MAC_PPS_OUT+")
	)
	(segment
		(start 136.29263 117.37033)
		(end 136.67404 116.98892)
		(width 0.2032)
		(layer "F.Cu")
		(net "MAC_PPS_OUT+")
	)
	(segment
		(start 113.7511 85.5786)
		(end 113.8761 85.4536)
		(width 0.2032)
		(layer "F.Cu")
		(net "MAC_PPS_OUT+")
	)
	(segment
		(start 136.67404 116.98892)
		(end 137.66107 116.98892)
		(width 0.2032)
		(layer "F.Cu")
		(net "MAC_PPS_OUT+")
	)
	(via
		(at 136.29263 117.37033)
		(size 0.4064)
		(drill 0.2032)
		(layers "F.Cu" "B.Cu")
		(tenting
			(front yes)
			(back yes)
		)
		(net "MAC_PPS_OUT+")
	)
	(via
		(at 112.3761 85.5786)
		(size 0.4064)
		(drill 0.2032)
		(layers "F.Cu" "B.Cu")
		(tenting
			(front yes)
			(back yes)
		)
		(net "MAC_PPS_OUT+")
	)
	(arc
		(start 113.876099 85.453599)
		(mid 113.887175 85.446198)
		(end 113.90024 85.443599)
		(width 0.2032)
		(layer "F.Cu")
		(net "MAC_PPS_OUT+")
	)
	(segment
		(start 112.3761 98.1141)
		(end 112.3761 85.5786)
		(width 0.2032)
		(layer "In2.Cu")
		(net "MAC_PPS_OUT+")
	)
	(segment
		(start 113.12005 99.91015)
		(end 129.83628 116.62638)
		(width 0.2032)
		(layer "In2.Cu")
		(net "MAC_PPS_OUT+")
	)
	(segment
		(start 131.63233 117.37033)
		(end 136.29263 117.37033)
		(width 0.2032)
		(layer "In2.Cu")
		(net "MAC_PPS_OUT+")
	)
	(arc
		(start 131.63233 117.37033)
		(mid 130.660314 117.176984)
		(end 129.836279 116.626381)
		(width 0.2032)
		(layer "In2.Cu")
		(net "MAC_PPS_OUT+")
	)
	(arc
		(start 113.120049 99.910151)
		(mid 112.569446 99.086116)
		(end 112.3761 98.1141)
		(width 0.2032)
		(layer "In2.Cu")
		(net "MAC_PPS_OUT+")
	)
	(segment
		(start 136.4261 112.4162)
		(end 136.93482 112.92492)
		(width 0.2032)
		(layer "F.Cu")
		(net "MAC_PPS_IN1+")
	)
	(segment
		(start 138.9261 85.3286)
		(end 143.1261 85.3286)
		(width 0.2032)
		(layer "F.Cu")
		(net "MAC_PPS_IN1+")
	)
	(segment
		(start 136.93482 112.92492)
		(end 137.66107 112.92492)
		(width 0.2032)
		(layer "F.Cu")
		(net "MAC_PPS_IN1+")
	)
	(via
		(at 143.1261 85.3286)
		(size 0.4064)
		(drill 0.2032)
		(layers "F.Cu" "B.Cu")
		(tenting
			(front yes)
			(back yes)
		)
		(net "MAC_PPS_IN1+")
	)
	(via
		(at 136.4261 112.4162)
		(size 0.4064)
		(drill 0.2032)
		(layers "F.Cu" "B.Cu")
		(tenting
			(front yes)
			(back yes)
		)
		(net "MAC_PPS_IN1+")
	)
	(segment
		(start 136.4261 112.4162)
		(end 138.9861 112.4162)
		(width 0.2032)
		(layer "In2.Cu")
		(net "MAC_PPS_IN1+")
	)
	(segment
		(start 141.9261 109.4762)
		(end 141.9261 89.6162)
		(width 0.2032)
		(layer "In2.Cu")
		(net "MAC_PPS_IN1+")
	)
	(segment
		(start 143.1261 88.4162)
		(end 143.1261 85.3286)
		(width 0.2032)
		(layer "In2.Cu")
		(net "MAC_PPS_IN1+")
	)
	(arc
		(start 141.9261 109.4762)
		(mid 141.064994 111.555094)
		(end 138.9861 112.4162)
		(width 0.2032)
		(layer "In2.Cu")
		(net "MAC_PPS_IN1+")
	)
	(arc
		(start 143.1261 88.4162)
		(mid 142.862496 89.052596)
		(end 142.2261 89.3162)
		(width 0.2032)
		(layer "In2.Cu")
		(net "MAC_PPS_IN1+")
	)
	(arc
		(start 141.9261 89.6162)
		(mid 142.013968 89.404068)
		(end 142.2261 89.3162)
		(width 0.2032)
		(layer "In2.Cu")
		(net "MAC_PPS_IN1+")
	)
	(segment
		(start 138.9411 87.8536)
		(end 141.0065 87.8536)
		(width 0.2032)
		(layer "F.Cu")
		(net "MAC_PPS_IN0-")
	)
	(segment
		(start 136.29261 114.41957)
		(end 136.32195 114.44892)
		(width 0.2032)
		(layer "F.Cu")
		(net "MAC_PPS_IN0-")
	)
	(segment
		(start 141.0645 87.7956)
		(end 141.6161 87.7956)
		(width 0.2032)
		(layer "F.Cu")
		(net "MAC_PPS_IN0-")
	)
	(segment
		(start 141.0065 87.8536)
		(end 141.0645 87.7956)
		(width 0.2032)
		(layer "F.Cu")
		(net "MAC_PPS_IN0-")
	)
	(segment
		(start 138.9261 87.8686)
		(end 138.9411 87.8536)
		(width 0.2032)
		(layer "F.Cu")
		(net "MAC_PPS_IN0-")
	)
	(segment
		(start 136.32195 114.44892)
		(end 137.66107 114.44892)
		(width 0.2032)
		(layer "F.Cu")
		(net "MAC_PPS_IN0-")
	)
	(via
		(at 136.29261 114.41957)
		(size 0.4064)
		(drill 0.2032)
		(layers "F.Cu" "B.Cu")
		(tenting
			(front yes)
			(back yes)
		)
		(net "MAC_PPS_IN0-")
	)
	(via
		(at 141.6161 87.7956)
		(size 0.4064)
		(drill 0.2032)
		(layers "F.Cu" "B.Cu")
		(tenting
			(front yes)
			(back yes)
		)
		(net "MAC_PPS_IN0-")
	)
	(segment
		(start 135.22947 114.41957)
		(end 136.29261 114.41957)
		(width 0.2032)
		(layer "In2.Cu")
		(net "MAC_PPS_IN0-")
	)
	(segment
		(start 136.9661 87.7956)
		(end 141.6161 87.7956)
		(width 0.2032)
		(layer "In2.Cu")
		(net "MAC_PPS_IN0-")
	)
	(segment
		(start 132.3261 111.5162)
		(end 132.3261 92.4356)
		(width 0.2032)
		(layer "In2.Cu")
		(net "MAC_PPS_IN0-")
	)
	(arc
		(start 135.22947 114.41957)
		(mid 133.176477 113.569193)
		(end 132.3261 111.5162)
		(width 0.2032)
		(layer "In2.Cu")
		(net "MAC_PPS_IN0-")
	)
	(arc
		(start 132.3261 92.4356)
		(mid 133.685125 89.154625)
		(end 136.9661 87.7956)
		(width 0.2032)
		(layer "In2.Cu")
		(net "MAC_PPS_IN0-")
	)
	(segment
		(start 138.9361 86.5886)
		(end 141.6161 86.5886)
		(width 0.2032)
		(layer "F.Cu")
		(net "MAC_PPS_IN0+")
	)
	(segment
		(start 136.3261 113.8162)
		(end 136.45082 113.94092)
		(width 0.2032)
		(layer "F.Cu")
		(net "MAC_PPS_IN0+")
	)
	(segment
		(start 138.9261 86.5986)
		(end 138.9361 86.5886)
		(width 0.2032)
		(layer "F.Cu")
		(net "MAC_PPS_IN0+")
	)
	(segment
		(start 141.6161 86.5886)
		(end 141.6261 86.5786)
		(width 0.2032)
		(layer "F.Cu")
		(net "MAC_PPS_IN0+")
	)
	(segment
		(start 136.45082 113.94092)
		(end 137.66107 113.94092)
		(width 0.2032)
		(layer "F.Cu")
		(net "MAC_PPS_IN0+")
	)
	(via
		(at 141.6261 86.5786)
		(size 0.4064)
		(drill 0.2032)
		(layers "F.Cu" "B.Cu")
		(tenting
			(front yes)
			(back yes)
		)
		(net "MAC_PPS_IN0+")
	)
	(via
		(at 136.3261 113.8162)
		(size 0.4064)
		(drill 0.2032)
		(layers "F.Cu" "B.Cu")
		(tenting
			(front yes)
			(back yes)
		)
		(net "MAC_PPS_IN0+")
	)
	(segment
		(start 132.6563 111.5162)
		(end 132.6563 92.4356)
		(width 0.2032)
		(layer "In2.Cu")
		(net "MAC_PPS_IN0+")
	)
	(segment
		(start 136.5261 88.4162)
		(end 142.1261 88.4162)
		(width 0.2032)
		(layer "In2.Cu")
		(net "MAC_PPS_IN0+")
	)
	(segment
		(start 142.4261 88.1162)
		(end 142.4261 87.37859)
		(width 0.2032)
		(layer "In2.Cu")
		(net "MAC_PPS_IN0+")
	)
	(segment
		(start 132.6563 92.4356)
		(end 132.6563 92.4356)
		(width 0.2032)
		(layer "In2.Cu")
		(net "MAC_PPS_IN0+")
	)
	(segment
		(start 136.15453 113.98777)
		(end 136.3261 113.8162)
		(width 0.2032)
		(layer "In2.Cu")
		(net "MAC_PPS_IN0+")
	)
	(segment
		(start 135.22947 114.08938)
		(end 136.01214 114.08938)
		(width 0.2032)
		(layer "In2.Cu")
		(net "MAC_PPS_IN0+")
	)
	(segment
		(start 132.6563 92.4356)
		(end 132.6563 92.4356)
		(width 0.2032)
		(layer "In2.Cu")
		(net "MAC_PPS_IN0+")
	)
	(segment
		(start 136.11375 113.98777)
		(end 136.15453 113.98777)
		(width 0.2032)
		(layer "In2.Cu")
		(net "MAC_PPS_IN0+")
	)
	(segment
		(start 136.01214 114.08938)
		(end 136.11375 113.98777)
		(width 0.2032)
		(layer "In2.Cu")
		(net "MAC_PPS_IN0+")
	)
	(arc
		(start 141.6261 86.57859)
		(mid 142.191785 86.812905)
		(end 142.4261 87.37859)
		(width 0.2032)
		(layer "In2.Cu")
		(net "MAC_PPS_IN0+")
	)
	(arc
		(start 142.4261 88.1162)
		(mid 142.338232 88.328332)
		(end 142.1261 88.4162)
		(width 0.2032)
		(layer "In2.Cu")
		(net "MAC_PPS_IN0+")
	)
	(arc
		(start 135.22947 114.08938)
		(mid 133.416127 113.341862)
		(end 132.656349 111.533622)
		(width 0.2032)
		(layer "In2.Cu")
		(net "MAC_PPS_IN0+")
	)
	(arc
		(start 132.656341 111.533617)
		(mid 132.656302 111.524906)
		(end 132.65629 111.516195)
		(width 0.2032)
		(layer "In2.Cu")
		(net "MAC_PPS_IN0+")
	)
	(arc
		(start 132.65629 92.4356)
		(mid 133.031218 90.679895)
		(end 134.090594 89.230484)
		(width 0.2032)
		(layer "In2.Cu")
		(net "MAC_PPS_IN0+")
	)
	(arc
		(start 134.090597 89.230478)
		(mid 135.242089 88.625154)
		(end 136.5261 88.41619)
		(width 0.2032)
		(layer "In2.Cu")
		(net "MAC_PPS_IN0+")
	)
	(segment
		(start 171.84911 98.95161)
		(end 171.84911 97.94162)
		(width 0.2032)
		(layer "F.Cu")
		(net "MAC_BITE")
	)
	(segment
		(start 171.82574 97.91825)
		(end 171.84911 97.94162)
		(width 0.2032)
		(layer "F.Cu")
		(net "MAC_BITE")
	)
	(segment
		(start 171.84911 98.95161)
		(end 172.5511 99.6536)
		(width 0.2032)
		(layer "F.Cu")
		(net "MAC_BITE")
	)
	(via
		(at 172.5511 99.6536)
		(size 0.4064)
		(drill 0.2032)
		(layers "F.Cu" "B.Cu")
		(tenting
			(front yes)
			(back yes)
		)
		(net "MAC_BITE")
	)
	(segment
		(start 151.5261 138.2162)
		(end 172.5511 117.1912)
		(width 0.2032)
		(layer "In3.Cu")
		(net "MAC_BITE")
	)
	(segment
		(start 172.5511 117.1912)
		(end 172.5511 99.6536)
		(width 0.2032)
		(layer "In3.Cu")
		(net "MAC_BITE")
	)
	(segment
		(start 137.8261 138.2162)
		(end 151.5261 138.2162)
		(width 0.2032)
		(layer "In3.Cu")
		(net "MAC_BITE")
	)
	(segment
		(start 141.66107 117.49692)
		(end 142.84126 117.49692)
		(width 0.2032)
		(layer "F.Cu")
		(net "MAC_ALARM")
	)
	(segment
		(start 171.32587 99.27338)
		(end 171.6261 99.57361)
		(width 0.2032)
		(layer "F.Cu")
		(net "MAC_ALARM")
	)
	(segment
		(start 171.6261 99.6286)
		(end 171.6261 99.57361)
		(width 0.2032)
		(layer "F.Cu")
		(net "MAC_ALARM")
	)
	(segment
		(start 142.84126 117.49692)
		(end 143.04919 117.28899)
		(width 0.2032)
		(layer "F.Cu")
		(net "MAC_ALARM")
	)
	(segment
		(start 171.32587 99.27338)
		(end 171.32587 97.91825)
		(width 0.2032)
		(layer "F.Cu")
		(net "MAC_ALARM")
	)
	(via
		(at 143.04919 117.28899)
		(size 0.4064)
		(drill 0.2032)
		(layers "F.Cu" "B.Cu")
		(net "MAC_ALARM")
	)
	(via
		(at 171.6261 99.6286)
		(size 0.4064)
		(drill 0.2032)
		(layers "F.Cu" "B.Cu")
		(tenting
			(front yes)
			(back yes)
		)
		(net "MAC_ALARM")
	)
	(segment
		(start 143.04919 117.28899)
		(end 144.43019 117.28899)
		(width 0.2032)
		(layer "In2.Cu")
		(net "MAC_ALARM")
	)
	(segment
		(start 171.6261 100.4162)
		(end 171.6261 99.6286)
		(width 0.2032)
		(layer "In2.Cu")
		(net "MAC_ALARM")
	)
	(segment
		(start 153.1261 118.8662)
		(end 158.3761 113.6162)
		(width 0.2032)
		(layer "In2.Cu")
		(net "MAC_ALARM")
	)
	(segment
		(start 146.0074 118.8662)
		(end 153.1261 118.8662)
		(width 0.2032)
		(layer "In2.Cu")
		(net "MAC_ALARM")
	)
	(segment
		(start 144.43019 117.28899)
		(end 146.0074 118.8662)
		(width 0.2032)
		(layer "In2.Cu")
		(net "MAC_ALARM")
	)
	(segment
		(start 167.6261 104.4162)
		(end 171.6261 100.4162)
		(width 0.2032)
		(layer "In2.Cu")
		(net "MAC_ALARM")
	)
	(segment
		(start 158.3761 113.6162)
		(end 158.3761 104.4162)
		(width 0.2032)
		(layer "In2.Cu")
		(net "MAC_ALARM")
	)
	(segment
		(start 158.3761 104.4162)
		(end 167.6261 104.4162)
		(width 0.2032)
		(layer "In2.Cu")
		(net "MAC_ALARM")
	)
	(segment
		(start 199.3634 112.81332)
		(end 200.92008 112.81332)
		(width 0.2032)
		(layer "F.Cu")
		(net "GPS1_TP2")
	)
	(segment
		(start 200.92008 112.81332)
		(end 201.06311 112.67029)
		(width 0.2032)
		(layer "F.Cu")
		(net "GPS1_TP2")
	)
	(segment
		(start 201.06311 112.67029)
		(end 201.1181 112.67029)
		(width 0.2032)
		(layer "F.Cu")
		(net "GPS1_TP2")
	)
	(segment
		(start 79.8761 67.8286)
		(end 81.9311 67.8286)
		(width 0.2032)
		(layer "F.Cu")
		(net "GPS1_TP2")
	)
	(via
		(at 79.8761 67.8286)
		(size 0.4064)
		(drill 0.2032)
		(layers "F.Cu" "B.Cu")
		(tenting
			(front yes)
			(back yes)
		)
		(net "GPS1_TP2")
	)
	(via
		(at 201.1181 112.67029)
		(size 0.4064)
		(drill 0.2032)
		(layers "F.Cu" "B.Cu")
		(tenting
			(front yes)
			(back yes)
		)
		(net "GPS1_TP2")
	)
	(segment
		(start 79.8761 66.3286)
		(end 81.3761 64.8286)
		(width 0.2032)
		(layer "B.Cu")
		(net "GPS1_TP2")
	)
	(segment
		(start 130.5261 99.50496)
		(end 130.5261 83.4162)
		(width 0.2032)
		(layer "B.Cu")
		(net "GPS1_TP2")
	)
	(segment
		(start 103.09307 64.8286)
		(end 114.17748 75.91301)
		(width 0.2032)
		(layer "B.Cu")
		(net "GPS1_TP2")
	)
	(segment
		(start 158.1619 100.8886)
		(end 169.94359 112.67029)
		(width 0.2032)
		(layer "B.Cu")
		(net "GPS1_TP2")
	)
	(segment
		(start 81.3761 64.8286)
		(end 103.09307 64.8286)
		(width 0.2032)
		(layer "B.Cu")
		(net "GPS1_TP2")
	)
	(segment
		(start 114.17748 75.91301)
		(end 123.0229 75.91301)
		(width 0.2032)
		(layer "B.Cu")
		(net "GPS1_TP2")
	)
	(segment
		(start 131.90974 100.8886)
		(end 158.1619 100.8886)
		(width 0.2032)
		(layer "B.Cu")
		(net "GPS1_TP2")
	)
	(segment
		(start 130.5261 99.50496)
		(end 131.90974 100.8886)
		(width 0.2032)
		(layer "B.Cu")
		(net "GPS1_TP2")
	)
	(segment
		(start 79.8761 67.8286)
		(end 79.8761 66.3286)
		(width 0.2032)
		(layer "B.Cu")
		(net "GPS1_TP2")
	)
	(segment
		(start 169.94359 112.67029)
		(end 201.1181 112.67029)
		(width 0.2032)
		(layer "B.Cu")
		(net "GPS1_TP2")
	)
	(segment
		(start 123.0229 75.91301)
		(end 130.5261 83.4162)
		(width 0.2032)
		(layer "B.Cu")
		(net "GPS1_TP2")
	)
	(segment
		(start 86.3761 71.8286)
		(end 88.3761 71.8286)
		(width 0.2032)
		(layer "F.Cu")
		(net "GPS1_RST")
	)
	(segment
		(start 201.36846 109.82096)
		(end 201.3761 109.8286)
		(width 0.2032)
		(layer "F.Cu")
		(net "GPS1_RST")
	)
	(segment
		(start 199.37104 109.82096)
		(end 201.36846 109.82096)
		(width 0.2032)
		(layer "F.Cu")
		(net "GPS1_RST")
	)
	(segment
		(start 199.3634 109.81332)
		(end 199.37104 109.82096)
		(width 0.2032)
		(layer "F.Cu")
		(net "GPS1_RST")
	)
	(via
		(at 201.3761 109.8286)
		(size 0.4064)
		(drill 0.2032)
		(layers "F.Cu" "B.Cu")
		(tenting
			(front yes)
			(back yes)
		)
		(net "GPS1_RST")
	)
	(via
		(at 88.3761 71.8286)
		(size 0.4064)
		(drill 0.2032)
		(layers "F.Cu" "B.Cu")
		(tenting
			(front yes)
			(back yes)
		)
		(net "GPS1_RST")
	)
	(segment
		(start 201.6029 113.6394)
		(end 202.2959 112.9464)
		(width 0.2032)
		(layer "B.Cu")
		(net "GPS1_RST")
	)
	(segment
		(start 130.94816 101.549)
		(end 157.8825 101.549)
		(width 0.2032)
		(layer "B.Cu")
		(net "GPS1_RST")
	)
	(segment
		(start 169.9729 113.6394)
		(end 201.6029 113.6394)
		(width 0.2032)
		(layer "B.Cu")
		(net "GPS1_RST")
	)
	(segment
		(start 129.1261 99.72694)
		(end 129.1261 83.4162)
		(width 0.2032)
		(layer "B.Cu")
		(net "GPS1_RST")
	)
	(segment
		(start 201.3761 109.8286)
		(end 202.2959 110.7484)
		(width 0.2032)
		(layer "B.Cu")
		(net "GPS1_RST")
	)
	(segment
		(start 129.1261 99.72694)
		(end 130.94816 101.549)
		(width 0.2032)
		(layer "B.Cu")
		(net "GPS1_RST")
	)
	(segment
		(start 109.15913 71.8286)
		(end 114.36385 77.03332)
		(width 0.2032)
		(layer "B.Cu")
		(net "GPS1_RST")
	)
	(segment
		(start 157.8825 101.549)
		(end 169.9729 113.6394)
		(width 0.2032)
		(layer "B.Cu")
		(net "GPS1_RST")
	)
	(segment
		(start 202.2959 112.9464)
		(end 202.2959 110.7484)
		(width 0.2032)
		(layer "B.Cu")
		(net "GPS1_RST")
	)
	(segment
		(start 122.74322 77.03332)
		(end 129.1261 83.4162)
		(width 0.2032)
		(layer "B.Cu")
		(net "GPS1_RST")
	)
	(segment
		(start 88.3761 71.8286)
		(end 109.15913 71.8286)
		(width 0.2032)
		(layer "B.Cu")
		(net "GPS1_RST")
	)
	(segment
		(start 114.36385 77.03332)
		(end 122.74322 77.03332)
		(width 0.2032)
		(layer "B.Cu")
		(net "GPS1_RST")
	)
	(segment
		(start 60.9761 135.5786)
		(end 72.8135 135.5786)
		(width 0.2032)
		(layer "F.Cu")
		(net "NetAN4_1")
	)
	(segment
		(start 72.8261 135.5912)
		(end 72.8511 135.6162)
		(width 0.2032)
		(layer "F.Cu")
		(net "NetAN4_1")
	)
	(segment
		(start 72.8261 135.5912)
		(end 72.8261 129.2162)
		(width 0.2032)
		(layer "F.Cu")
		(net "NetAN4_1")
	)
	(segment
		(start 72.8135 135.5786)
		(end 72.8261 135.5912)
		(width 0.2032)
		(layer "F.Cu")
		(net "NetAN4_1")
	)
	(segment
		(start 72.8511 135.6162)
		(end 76.8761 135.6162)
		(width 0.2032)
		(layer "F.Cu")
		(net "NetAN4_1")
	)
	(segment
		(start 72.8131 108.5782)
		(end 72.8511 108.6162)
		(width 0.2032)
		(layer "F.Cu")
		(net "NetAN2_1")
	)
	(segment
		(start 72.8261 108.5652)
		(end 72.8261 101.8662)
		(width 0.2032)
		(layer "F.Cu")
		(net "NetAN2_1")
	)
	(segment
		(start 72.8131 108.5782)
		(end 72.8261 108.5652)
		(width 0.2032)
		(layer "F.Cu")
		(net "NetAN2_1")
	)
	(segment
		(start 60.9761 108.5782)
		(end 72.8131 108.5782)
		(width 0.2032)
		(layer "F.Cu")
		(net "NetAN2_1")
	)
	(segment
		(start 72.8511 108.6162)
		(end 77.1761 108.6162)
		(width 0.2032)
		(layer "F.Cu")
		(net "NetAN2_1")
	)
	(segment
		(start 72.8261 121.8912)
		(end 72.8511 121.8662)
		(width 0.2032)
		(layer "F.Cu")
		(net "NetAN3_1")
	)
	(segment
		(start 60.9761 122.0782)
		(end 72.8261 122.0782)
		(width 0.2032)
		(layer "F.Cu")
		(net "NetAN3_1")
	)
	(segment
		(start 72.9761 121.9912)
		(end 73.1011 121.8662)
		(width 0.2032)
		(layer "F.Cu")
		(net "NetAN3_1")
	)
	(segment
		(start 72.8261 122.0782)
		(end 72.8261 121.8912)
		(width 0.2032)
		(layer "F.Cu")
		(net "NetAN3_1")
	)
	(segment
		(start 72.8261 127.0162)
		(end 72.8261 122.0782)
		(width 0.2032)
		(layer "F.Cu")
		(net "NetAN3_1")
	)
	(segment
		(start 73.1011 121.8662)
		(end 77.1761 121.8662)
		(width 0.2032)
		(layer "F.Cu")
		(net "NetAN3_1")
	)
	(segment
		(start 72.8261 99.6662)
		(end 72.8511 99.6412)
		(width 0.2032)
		(layer "F.Cu")
		(net "NetAN1_1")
	)
	(segment
		(start 60.9761 95.0786)
		(end 72.8135 95.0786)
		(width 0.2032)
		(layer "F.Cu")
		(net "NetAN1_1")
	)
	(segment
		(start 72.8511 95.1162)
		(end 76.9261 95.1162)
		(width 0.2032)
		(layer "F.Cu")
		(net "NetAN1_1")
	)
	(segment
		(start 72.8135 95.0786)
		(end 72.8511 95.1162)
		(width 0.2032)
		(layer "F.Cu")
		(net "NetAN1_1")
	)
	(segment
		(start 72.8511 99.6412)
		(end 72.8511 95.1162)
		(width 0.2032)
		(layer "F.Cu")
		(net "NetAN1_1")
	)
	(segment
		(start 75.1261 57.3662)
		(end 75.1261 56.2912)
		(width 0.2032)
		(layer "F.Cu")
		(net "LED4")
	)
	(segment
		(start 193.93593 122.31343)
		(end 195.31363 122.31343)
		(width 0.2032)
		(layer "F.Cu")
		(net "LED4")
	)
	(segment
		(start 193.2761 121.6536)
		(end 193.93593 122.31343)
		(width 0.2032)
		(layer "F.Cu")
		(net "LED4")
	)
	(via
		(at 75.1261 57.3662)
		(size 0.4064)
		(drill 0.2032)
		(layers "F.Cu" "B.Cu")
		(tenting
			(front yes)
			(back yes)
		)
		(net "LED4")
	)
	(via
		(at 193.2761 121.6536)
		(size 0.4064)
		(drill 0.2032)
		(layers "F.Cu" "B.Cu")
		(tenting
			(front yes)
			(back yes)
		)
		(net "LED4")
	)
	(segment
		(start 75.1261 84.11619)
		(end 75.1261 57.3662)
		(width 0.2032)
		(layer "In2.Cu")
		(net "LED4")
	)
	(segment
		(start 90.6761 115.01163)
		(end 103.48067 127.8162)
		(width 0.2032)
		(layer "In2.Cu")
		(net "LED4")
	)
	(segment
		(start 75.1261 84.11619)
		(end 90.6761 99.6662)
		(width 0.2032)
		(layer "In2.Cu")
		(net "LED4")
	)
	(segment
		(start 90.6761 115.01163)
		(end 90.6761 99.6662)
		(width 0.2032)
		(layer "In2.Cu")
		(net "LED4")
	)
	(segment
		(start 189.7135 125.2162)
		(end 193.2761 121.6536)
		(width 0.2032)
		(layer "In2.Cu")
		(net "LED4")
	)
	(segment
		(start 103.48067 127.8162)
		(end 153.7385 127.8162)
		(width 0.2032)
		(layer "In2.Cu")
		(net "LED4")
	)
	(segment
		(start 153.7385 127.8162)
		(end 156.3385 125.2162)
		(width 0.2032)
		(layer "In2.Cu")
		(net "LED4")
	)
	(segment
		(start 156.3385 125.2162)
		(end 189.7135 125.2162)
		(width 0.2032)
		(layer "In2.Cu")
		(net "LED4")
	)
	(segment
		(start 193.2761 122.4536)
		(end 193.6358 122.8133)
		(width 0.2032)
		(layer "F.Cu")
		(net "LED3")
	)
	(segment
		(start 193.6358 122.8133)
		(end 195.31363 122.8133)
		(width 0.2032)
		(layer "F.Cu")
		(net "LED3")
	)
	(segment
		(start 73.3761 57.3662)
		(end 73.3761 56.2912)
		(width 0.2032)
		(layer "F.Cu")
		(net "LED3")
	)
	(via
		(at 73.3761 57.3662)
		(size 0.4064)
		(drill 0.2032)
		(layers "F.Cu" "B.Cu")
		(tenting
			(front yes)
			(back yes)
		)
		(net "LED3")
	)
	(via
		(at 193.2761 122.4536)
		(size 0.4064)
		(drill 0.2032)
		(layers "F.Cu" "B.Cu")
		(tenting
			(front yes)
			(back yes)
		)
		(net "LED3")
	)
	(segment
		(start 103.5137 128.3162)
		(end 153.8385 128.3162)
		(width 0.2032)
		(layer "In2.Cu")
		(net "LED3")
	)
	(segment
		(start 73.1261 82.58317)
		(end 73.1261 57.6162)
		(width 0.2032)
		(layer "In2.Cu")
		(net "LED3")
	)
	(segment
		(start 153.8385 128.3162)
		(end 156.1385 126.0162)
		(width 0.2032)
		(layer "In2.Cu")
		(net "LED3")
	)
	(segment
		(start 156.1385 126.0162)
		(end 189.7135 126.0162)
		(width 0.2032)
		(layer "In2.Cu")
		(net "LED3")
	)
	(segment
		(start 90.3459 115.1484)
		(end 90.3459 99.80297)
		(width 0.2032)
		(layer "In2.Cu")
		(net "LED3")
	)
	(segment
		(start 90.3459 115.1484)
		(end 103.5137 128.3162)
		(width 0.2032)
		(layer "In2.Cu")
		(net "LED3")
	)
	(segment
		(start 189.7135 126.0162)
		(end 193.2761 122.4536)
		(width 0.2032)
		(layer "In2.Cu")
		(net "LED3")
	)
	(segment
		(start 73.1261 82.58317)
		(end 90.3459 99.80297)
		(width 0.2032)
		(layer "In2.Cu")
		(net "LED3")
	)
	(segment
		(start 73.1261 57.6162)
		(end 73.3761 57.3662)
		(width 0.2032)
		(layer "In2.Cu")
		(net "LED3")
	)
	(segment
		(start 103.54612 157.7576)
		(end 103.54612 154.4601)
		(width 0.508)
		(layer "F.Cu")
		(net "+12V_PCIE")
	)
	(segment
		(start 102.77962 153.77608)
		(end 102.8621 153.77608)
		(width 0.508)
		(layer "F.Cu")
		(net "+12V_PCIE")
	)
	(segment
		(start 101.54613 154.48357)
		(end 101.97888 154.05081)
		(width 0.508)
		(layer "F.Cu")
		(net "+12V_PCIE")
	)
	(segment
		(start 102.50489 154.05081)
		(end 102.77962 153.77608)
		(width 0.508)
		(layer "F.Cu")
		(net "+12V_PCIE")
	)
	(segment
		(start 102.54612 157.7576)
		(end 102.54612 154.09205)
		(width 0.508)
		(layer "F.Cu")
		(net "+12V_PCIE")
	)
	(segment
		(start 102.54612 154.09205)
		(end 102.8621 153.77608)
		(width 0.508)
		(layer "F.Cu")
		(net "+12V_PCIE")
	)
	(segment
		(start 101.97888 154.05081)
		(end 102.50489 154.05081)
		(width 0.508)
		(layer "F.Cu")
		(net "+12V_PCIE")
	)
	(segment
		(start 101.54613 157.7576)
		(end 101.54613 154.48357)
		(width 0.508)
		(layer "F.Cu")
		(net "+12V_PCIE")
	)
	(via
		(at 226.85933 97.3525)
		(size 0.4064)
		(drill 0.2032)
		(layers "F.Cu" "B.Cu")
		(net "+12V_PCIE")
	)
	(via
		(at 102.4261 154.0786)
		(size 0.4064)
		(drill 0.2032)
		(layers "F.Cu" "B.Cu")
		(tenting
			(front yes)
			(back yes)
		)
		(net "+12V_PCIE")
	)
	(via
		(at 102.1261 147.0162)
		(size 0.4064)
		(drill 0.2032)
		(layers "F.Cu" "B.Cu")
		(tenting
			(front yes)
			(back yes)
		)
		(net "+12V_PCIE")
	)
	(via
		(at 102.4261 153.2786)
		(size 0.4064)
		(drill 0.2032)
		(layers "F.Cu" "B.Cu")
		(tenting
			(front yes)
			(back yes)
		)
		(net "+12V_PCIE")
	)
	(via
		(at 102.9261 153.2786)
		(size 0.4064)
		(drill 0.2032)
		(layers "F.Cu" "B.Cu")
		(tenting
			(front yes)
			(back yes)
		)
		(net "+12V_PCIE")
	)
	(via
		(at 226.8261 95.7162)
		(size 0.4064)
		(drill 0.2032)
		(layers "F.Cu" "B.Cu")
		(net "+12V_PCIE")
	)
	(via
		(at 102.6261 146.2162)
		(size 0.4064)
		(drill 0.2032)
		(layers "F.Cu" "B.Cu")
		(tenting
			(front yes)
			(back yes)
		)
		(net "+12V_PCIE")
	)
	(via
		(at 103.4261 153.2786)
		(size 0.4064)
		(drill 0.2032)
		(layers "F.Cu" "B.Cu")
		(tenting
			(front yes)
			(back yes)
		)
		(net "+12V_PCIE")
	)
	(via
		(at 102.1261 146.2162)
		(size 0.4064)
		(drill 0.2032)
		(layers "F.Cu" "B.Cu")
		(tenting
			(front yes)
			(back yes)
		)
		(net "+12V_PCIE")
	)
	(via
		(at 103.4261 154.0786)
		(size 0.4064)
		(drill 0.2032)
		(layers "F.Cu" "B.Cu")
		(tenting
			(front yes)
			(back yes)
		)
		(net "+12V_PCIE")
	)
	(via
		(at 227.3261 94.9162)
		(size 0.4064)
		(drill 0.2032)
		(layers "F.Cu" "B.Cu")
		(net "+12V_PCIE")
	)
	(via
		(at 226.84653 96.4954)
		(size 0.4064)
		(drill 0.2032)
		(layers "F.Cu" "B.Cu")
		(net "+12V_PCIE")
	)
	(via
		(at 102.9261 154.0786)
		(size 0.4064)
		(drill 0.2032)
		(layers "F.Cu" "B.Cu")
		(tenting
			(front yes)
			(back yes)
		)
		(net "+12V_PCIE")
	)
	(via
		(at 226.8261 98.4162)
		(size 0.4064)
		(drill 0.2032)
		(layers "F.Cu" "B.Cu")
		(net "+12V_PCIE")
	)
	(via
		(at 226.3261 94.9162)
		(size 0.4064)
		(drill 0.2032)
		(layers "F.Cu" "B.Cu")
		(net "+12V_PCIE")
	)
	(via
		(at 102.6261 147.0162)
		(size 0.4064)
		(drill 0.2032)
		(layers "F.Cu" "B.Cu")
		(tenting
			(front yes)
			(back yes)
		)
		(net "+12V_PCIE")
	)
	(via
		(at 103.1261 146.2162)
		(size 0.4064)
		(drill 0.2032)
		(layers "F.Cu" "B.Cu")
		(tenting
			(front yes)
			(back yes)
		)
		(net "+12V_PCIE")
	)
	(via
		(at 103.1261 147.0162)
		(size 0.4064)
		(drill 0.2032)
		(layers "F.Cu" "B.Cu")
		(tenting
			(front yes)
			(back yes)
		)
		(net "+12V_PCIE")
	)
	(segment
		(start 157.3261 136.7162)
		(end 157.3261 132.3162)
		(width 2.032)
		(layer "B.Cu")
		(net "+12V_PCIE")
	)
	(segment
		(start 227.3261 134.4162)
		(end 231.8261 129.9162)
		(width 2.032)
		(layer "B.Cu")
		(net "+12V_PCIE")
	)
	(segment
		(start 231.8261 129.9162)
		(end 231.8261 111.3162)
		(width 2.032)
		(layer "B.Cu")
		(net "+12V_PCIE")
	)
	(segment
		(start 223.2261 141.7162)
		(end 227.3261 137.6162)
		(width 2.032)
		(layer "B.Cu")
		(net "+12V_PCIE")
	)
	(segment
		(start 226.8261 95.7162)
		(end 226.8261 95.1162)
		(width 2.032)
		(layer "B.Cu")
		(net "+12V_PCIE")
	)
	(segment
		(start 157.3261 132.3162)
		(end 164.4261 125.2162)
		(width 2.032)
		(layer "B.Cu")
		(net "+12V_PCIE")
	)
	(segment
		(start 102.4761 146.6662)
		(end 105.6261 143.5162)
		(width 2.032)
		(layer "B.Cu")
		(net "+12V_PCIE")
	)
	(segment
		(start 227.3261 137.6162)
		(end 227.3261 134.4162)
		(width 2.032)
		(layer "B.Cu")
		(net "+12V_PCIE")
	)
	(segment
		(start 102.54612 157.7576)
		(end 102.54612 154.03707)
		(width 0.508)
		(layer "B.Cu")
		(net "+12V_PCIE")
	)
	(segment
		(start 226.8261 106.3162)
		(end 231.8261 111.3162)
		(width 2.032)
		(layer "B.Cu")
		(net "+12V_PCIE")
	)
	(segment
		(start 103.54612 157.7576)
		(end 103.54612 154.40511)
		(width 0.508)
		(layer "B.Cu")
		(net "+12V_PCIE")
	)
	(segment
		(start 182.9261 125.2162)
		(end 199.4261 141.7162)
		(width 2.032)
		(layer "B.Cu")
		(net "+12V_PCIE")
	)
	(segment
		(start 102.8621 153.72109)
		(end 103.54612 154.40511)
		(width 0.508)
		(layer "B.Cu")
		(net "+12V_PCIE")
	)
	(segment
		(start 150.5261 143.5162)
		(end 157.3261 136.7162)
		(width 2.032)
		(layer "B.Cu")
		(net "+12V_PCIE")
	)
	(segment
		(start 226.8261 106.3162)
		(end 226.8261 98.4162)
		(width 2.032)
		(layer "B.Cu")
		(net "+12V_PCIE")
	)
	(segment
		(start 164.4261 125.2162)
		(end 182.9261 125.2162)
		(width 2.032)
		(layer "B.Cu")
		(net "+12V_PCIE")
	)
	(segment
		(start 199.4261 141.7162)
		(end 223.2261 141.7162)
		(width 2.032)
		(layer "B.Cu")
		(net "+12V_PCIE")
	)
	(segment
		(start 226.8261 98.4162)
		(end 226.8261 95.7162)
		(width 2.032)
		(layer "B.Cu")
		(net "+12V_PCIE")
	)
	(segment
		(start 102.54612 154.03707)
		(end 102.8621 153.72109)
		(width 0.508)
		(layer "B.Cu")
		(net "+12V_PCIE")
	)
	(segment
		(start 105.6261 143.5162)
		(end 150.5261 143.5162)
		(width 2.032)
		(layer "B.Cu")
		(net "+12V_PCIE")
	)
	(segment
		(start 108.54611 157.7576)
		(end 108.62417 157.67954)
		(width 0.508)
		(layer "F.Cu")
		(net "+3.3V_PCIE")
	)
	(segment
		(start 108.52611 157.0786)
		(end 108.52611 153.97858)
		(width 0.508)
		(layer "F.Cu")
		(net "+3.3V_PCIE")
	)
	(segment
		(start 108.52611 153.97858)
		(end 108.8261 153.6786)
		(width 0.508)
		(layer "F.Cu")
		(net "+3.3V_PCIE")
	)
	(segment
		(start 108.8261 153.6786)
		(end 109.5261 153.6786)
		(width 0.508)
		(layer "F.Cu")
		(net "+3.3V_PCIE")
	)
	(via
		(at 110.5261 154.0786)
		(size 0.4064)
		(drill 0.2032)
		(layers "F.Cu" "B.Cu")
		(tenting
			(front yes)
			(back yes)
		)
		(net "+3.3V_PCIE")
	)
	(via
		(at 109.5261 154.0786)
		(size 0.4064)
		(drill 0.2032)
		(layers "F.Cu" "B.Cu")
		(tenting
			(front yes)
			(back yes)
		)
		(net "+3.3V_PCIE")
	)
	(via
		(at 110.5261 153.2786)
		(size 0.4064)
		(drill 0.2032)
		(layers "F.Cu" "B.Cu")
		(tenting
			(front yes)
			(back yes)
		)
		(net "+3.3V_PCIE")
	)
	(via
		(at 108.6261 154.0786)
		(size 0.4064)
		(drill 0.2032)
		(layers "F.Cu" "B.Cu")
		(tenting
			(front yes)
			(back yes)
		)
		(net "+3.3V_PCIE")
	)
	(via
		(at 109.5261 153.2786)
		(size 0.4064)
		(drill 0.2032)
		(layers "F.Cu" "B.Cu")
		(tenting
			(front yes)
			(back yes)
		)
		(net "+3.3V_PCIE")
	)
	(via
		(at 108.6261 153.2786)
		(size 0.4064)
		(drill 0.2032)
		(layers "F.Cu" "B.Cu")
		(tenting
			(front yes)
			(back yes)
		)
		(net "+3.3V_PCIE")
	)
	(segment
		(start 109.52611 157.0786)
		(end 109.52611 154.07861)
		(width 0.508)
		(layer "B.Cu")
		(net "+3.3V_PCIE")
	)
	(segment
		(start 109.5931 153.2456)
		(end 110.51504 154.16754)
		(width 0.508)
		(layer "B.Cu")
		(net "+3.3V_PCIE")
	)
	(segment
		(start 110.51504 157.72653)
		(end 110.54611 157.7576)
		(width 0.508)
		(layer "B.Cu")
		(net "+3.3V_PCIE")
	)
	(segment
		(start 109.5261 154.0786)
		(end 109.52611 154.07861)
		(width 0.508)
		(layer "B.Cu")
		(net "+3.3V_PCIE")
	)
	(segment
		(start 110.51504 157.72653)
		(end 110.51504 154.16754)
		(width 0.508)
		(layer "B.Cu")
		(net "+3.3V_PCIE")
	)
	(segment
		(start 96.5011 143.6912)
		(end 96.5011 143.3162)
		(width 0.2032)
		(layer "F.Cu")
		(net "PRSNT")
	)
	(segment
		(start 107.1885 150.9786)
		(end 108.4761 150.9786)
		(width 0.2032)
		(layer "F.Cu")
		(net "PRSNT")
	)
	(segment
		(start 97.0261 144.2162)
		(end 103.8261 144.2162)
		(width 0.2032)
		(layer "F.Cu")
		(net "PRSNT")
	)
	(segment
		(start 103.8261 144.2162)
		(end 105.5261 145.9162)
		(width 0.2032)
		(layer "F.Cu")
		(net "PRSNT")
	)
	(segment
		(start 105.5261 149.3162)
		(end 107.1885 150.9786)
		(width 0.2032)
		(layer "F.Cu")
		(net "PRSNT")
	)
	(segment
		(start 96.5011 143.3162)
		(end 96.5011 142.2162)
		(width 0.2032)
		(layer "F.Cu")
		(net "PRSNT")
	)
	(segment
		(start 96.5011 143.6912)
		(end 97.0261 144.2162)
		(width 0.2032)
		(layer "F.Cu")
		(net "PRSNT")
	)
	(segment
		(start 105.5261 149.3162)
		(end 105.5261 145.9162)
		(width 0.2032)
		(layer "F.Cu")
		(net "PRSNT")
	)
	(via
		(at 108.4761 150.9786)
		(size 0.4064)
		(drill 0.2032)
		(layers "F.Cu" "B.Cu")
		(tenting
			(front yes)
			(back yes)
		)
		(net "PRSNT")
	)
	(segment
		(start 103.44505 150.9786)
		(end 108.4761 150.9786)
		(width 0.2032)
		(layer "B.Cu")
		(net "PRSNT")
	)
	(segment
		(start 101.6713 157.13713)
		(end 101.6713 152.75235)
		(width 0.2032)
		(layer "B.Cu")
		(net "PRSNT")
	)
	(segment
		(start 101.6713 152.75235)
		(end 103.44505 150.9786)
		(width 0.2032)
		(layer "B.Cu")
		(net "PRSNT")
	)
	(segment
		(start 101.54613 157.2623)
		(end 101.6713 157.13713)
		(width 0.2032)
		(layer "B.Cu")
		(net "PRSNT")
	)
	(segment
		(start 177.83583 131.45545)
		(end 177.8437 131.46332)
		(width 0.127)
		(layer "F.Cu")
		(net "PCIE_TX3_N")
	)
	(segment
		(start 177.83583 132.91887)
		(end 177.83583 131.45545)
		(width 0.127)
		(layer "F.Cu")
		(net "PCIE_TX3_N")
	)
	(via
		(at 132.5761 150.2786)
		(size 0.4064)
		(drill 0.2032)
		(layers "F.Cu" "B.Cu")
		(tenting
			(front yes)
			(back yes)
		)
		(net "PCIE_TX3_N")
	)
	(via
		(at 177.7261 133.0286)
		(size 0.4064)
		(drill 0.2032)
		(layers "F.Cu" "B.Cu")
		(tenting
			(front yes)
			(back yes)
		)
		(net "PCIE_TX3_N")
	)
	(arc
		(start 177.83583 132.91887)
		(mid 177.803691 132.996461)
		(end 177.7261 133.0286)
		(width 0.127)
		(layer "F.Cu")
		(net "PCIE_TX3_N")
	)
	(segment
		(start 132.5761 151.3546)
		(end 132.5801 151.3586)
		(width 0.127)
		(layer "B.Cu")
		(net "PCIE_TX3_N")
	)
	(segment
		(start 132.5761 151.3546)
		(end 132.5761 150.2786)
		(width 0.127)
		(layer "B.Cu")
		(net "PCIE_TX3_N")
	)
	(segment
		(start 132.2176 147.77919)
		(end 132.2176 147.74558)
		(width 0.127)
		(layer "In3.Cu")
		(net "PCIE_TX3_N")
	)
	(segment
		(start 177.7261 133.0286)
		(end 177.81629 133.11879)
		(width 0.127)
		(layer "In3.Cu")
		(net "PCIE_TX3_N")
	)
	(segment
		(start 132.2176 149.41311)
		(end 132.2176 149.38072)
		(width 0.127)
		(layer "In3.Cu")
		(net "PCIE_TX3_N")
	)
	(segment
		(start 132.2176 149.38072)
		(end 132.2176 147.77919)
		(width 0.127)
		(layer "In3.Cu")
		(net "PCIE_TX3_N")
	)
	(segment
		(start 178.71776 134.31274)
		(end 181.05333 136.6483)
		(width 0.127)
		(layer "In3.Cu")
		(net "PCIE_TX3_N")
	)
	(segment
		(start 178.6801 134.22247)
		(end 178.6801 133.38272)
		(width 0.127)
		(layer "In3.Cu")
		(net "PCIE_TX3_N")
	)
	(segment
		(start 135.0532 145.0662)
		(end 151.6761 145.0662)
		(width 0.127)
		(layer "In3.Cu")
		(net "PCIE_TX3_N")
	)
	(segment
		(start 132.8511 146.2162)
		(end 133.25715 145.81015)
		(width 0.127)
		(layer "In3.Cu")
		(net "PCIE_TX3_N")
	)
	(segment
		(start 180.51093 144.0265)
		(end 181.47957 143.05786)
		(width 0.127)
		(layer "In3.Cu")
		(net "PCIE_TX3_N")
	)
	(segment
		(start 151.6761 145.0662)
		(end 177.66559 145.0662)
		(width 0.127)
		(layer "In3.Cu")
		(net "PCIE_TX3_N")
	)
	(segment
		(start 181.48049 143.05694)
		(end 181.51239 143.02504)
		(width 0.127)
		(layer "In3.Cu")
		(net "PCIE_TX3_N")
	)
	(segment
		(start 181.6305 142.73859)
		(end 181.6305 137.94509)
		(width 0.127)
		(layer "In3.Cu")
		(net "PCIE_TX3_N")
	)
	(arc
		(start 178.680103 133.382717)
		(mid 178.688949 133.336945)
		(end 178.713716 133.297449)
		(width 0.127)
		(layer "In3.Cu")
		(net "PCIE_TX3_N")
	)
	(arc
		(start 178.0324 133.029062)
		(mid 178.570395 132.662296)
		(end 178.713714 133.297446)
		(width 0.127)
		(layer "In3.Cu")
		(net "PCIE_TX3_N")
	)
	(arc
		(start 181.6305 142.73859)
		(mid 181.599814 142.893509)
		(end 181.51239 143.025033)
		(width 0.127)
		(layer "In3.Cu")
		(net "PCIE_TX3_N")
	)
	(arc
		(start 178.717761 134.312734)
		(mid 178.689893 134.271373)
		(end 178.6801 134.22247)
		(width 0.127)
		(layer "In3.Cu")
		(net "PCIE_TX3_N")
	)
	(arc
		(start 178.032398 133.029062)
		(mid 177.954101 133.145591)
		(end 177.816292 133.118792)
		(width 0.127)
		(layer "In3.Cu")
		(net "PCIE_TX3_N")
	)
	(arc
		(start 133.257149 145.810149)
		(mid 134.081184 145.259546)
		(end 135.0532 145.0662)
		(width 0.127)
		(layer "In3.Cu")
		(net "PCIE_TX3_N")
	)
	(arc
		(start 132.543393 150.199638)
		(mid 132.5676 150.235867)
		(end 132.5761 150.278601)
		(width 0.127)
		(layer "In3.Cu")
		(net "PCIE_TX3_N")
	)
	(arc
		(start 132.21761 147.74558)
		(mid 132.382249 146.917885)
		(end 132.8511 146.2162)
		(width 0.127)
		(layer "In3.Cu")
		(net "PCIE_TX3_N")
	)
	(arc
		(start 181.053326 136.648307)
		(mid 181.479691 137.235376)
		(end 181.6305 137.94509)
		(width 0.127)
		(layer "In3.Cu")
		(net "PCIE_TX3_N")
	)
	(arc
		(start 181.480496 143.056938)
		(mid 181.480038 143.057401)
		(end 181.479577 143.057861)
		(width 0.127)
		(layer "In3.Cu")
		(net "PCIE_TX3_N")
	)
	(arc
		(start 180.510927 144.026495)
		(mid 179.203159 144.8608)
		(end 177.665585 145.066196)
		(width 0.127)
		(layer "In3.Cu")
		(net "PCIE_TX3_N")
	)
	(arc
		(start 132.54339 150.199638)
		(mid 132.30227 149.838776)
		(end 132.2176 149.41311)
		(width 0.127)
		(layer "In3.Cu")
		(net "PCIE_TX3_N")
	)
	(segment
		(start 178.33595 132.93845)
		(end 178.33595 131.45545)
		(width 0.127)
		(layer "F.Cu")
		(net "PCIE_TX3_P")
	)
	(via
		(at 131.57971 150.18609)
		(size 0.4064)
		(drill 0.2032)
		(layers "F.Cu" "B.Cu")
		(tenting
			(front yes)
			(back yes)
		)
		(net "PCIE_TX3_P")
	)
	(via
		(at 178.4261 133.0286)
		(size 0.4064)
		(drill 0.2032)
		(layers "F.Cu" "B.Cu")
		(tenting
			(front yes)
			(back yes)
		)
		(net "PCIE_TX3_P")
	)
	(arc
		(start 178.4261 133.0286)
		(mid 178.362354 133.002196)
		(end 178.33595 132.93845)
		(width 0.127)
		(layer "F.Cu")
		(net "PCIE_TX3_P")
	)
	(segment
		(start 131.5761 151.32962)
		(end 131.5761 150.21614)
		(width 0.127)
		(layer "B.Cu")
		(net "PCIE_TX3_P")
	)
	(segment
		(start 131.57809 150.19377)
		(end 131.57941 150.18639)
		(width 0.127)
		(layer "B.Cu")
		(net "PCIE_TX3_P")
	)
	(segment
		(start 131.57941 150.18639)
		(end 131.57971 150.18609)
		(width 0.127)
		(layer "B.Cu")
		(net "PCIE_TX3_P")
	)
	(arc
		(start 131.5761 150.21614)
		(mid 131.576597 150.20491)
		(end 131.578086 150.193768)
		(width 0.127)
		(layer "B.Cu")
		(net "PCIE_TX3_P")
	)
	(arc
		(start 131.57611 151.32962)
		(mid 131.572991 151.345302)
		(end 131.564107 151.358597)
		(width 0.127)
		(layer "B.Cu")
		(net "PCIE_TX3_P")
	)
	(segment
		(start 178.63291 134.62301)
		(end 180.95715 136.94725)
		(width 0.127)
		(layer "In3.Cu")
		(net "PCIE_TX3_P")
	)
	(segment
		(start 131.9382 147.77919)
		(end 131.9382 147.74173)
		(width 0.127)
		(layer "In3.Cu")
		(net "PCIE_TX3_P")
	)
	(segment
		(start 142.02043 144.7868)
		(end 142.08394 144.7868)
		(width 0.127)
		(layer "In3.Cu")
		(net "PCIE_TX3_P")
	)
	(segment
		(start 142.71894 144.6852)
		(end 142.71894 144.59689)
		(width 0.127)
		(layer "In3.Cu")
		(net "PCIE_TX3_P")
	)
	(segment
		(start 143.48094 144.6852)
		(end 143.48094 144.60366)
		(width 0.127)
		(layer "In3.Cu")
		(net "PCIE_TX3_P")
	)
	(segment
		(start 178.50115 134.45533)
		(end 178.50703 134.46121)
		(width 0.127)
		(layer "In3.Cu")
		(net "PCIE_TX3_P")
	)
	(segment
		(start 143.22694 144.6852)
		(end 143.22694 144.60366)
		(width 0.127)
		(layer "In3.Cu")
		(net "PCIE_TX3_P")
	)
	(segment
		(start 131.9382 149.38072)
		(end 131.9382 147.77919)
		(width 0.127)
		(layer "In3.Cu")
		(net "PCIE_TX3_P")
	)
	(segment
		(start 142.97294 144.6852)
		(end 142.97294 144.59689)
		(width 0.127)
		(layer "In3.Cu")
		(net "PCIE_TX3_P")
	)
	(segment
		(start 144.11594 144.7868)
		(end 144.85887 144.7868)
		(width 0.127)
		(layer "In3.Cu")
		(net "PCIE_TX3_P")
	)
	(segment
		(start 143.98894 144.6598)
		(end 143.98894 144.65977)
		(width 0.127)
		(layer "In3.Cu")
		(net "PCIE_TX3_P")
	)
	(segment
		(start 181.3511 142.73859)
		(end 181.3511 137.89834)
		(width 0.127)
		(layer "In3.Cu")
		(net "PCIE_TX3_P")
	)
	(segment
		(start 131.9382 149.47852)
		(end 131.9382 149.38072)
		(width 0.127)
		(layer "In3.Cu")
		(net "PCIE_TX3_P")
	)
	(segment
		(start 180.30825 143.83405)
		(end 181.20017 142.94213)
		(width 0.127)
		(layer "In3.Cu")
		(net "PCIE_TX3_P")
	)
	(segment
		(start 142.21094 144.6598)
		(end 142.21094 144.59689)
		(width 0.127)
		(layer "In3.Cu")
		(net "PCIE_TX3_P")
	)
	(segment
		(start 142.46494 144.6852)
		(end 142.46494 144.59689)
		(width 0.127)
		(layer "In3.Cu")
		(net "PCIE_TX3_P")
	)
	(segment
		(start 181.20099 142.94131)
		(end 181.31429 142.82801)
		(width 0.127)
		(layer "In3.Cu")
		(net "PCIE_TX3_P")
	)
	(segment
		(start 132.6508 146.02136)
		(end 133.06056 145.61161)
		(width 0.127)
		(layer "In3.Cu")
		(net "PCIE_TX3_P")
	)
	(segment
		(start 178.4261 134.27508)
		(end 178.4261 133.0286)
		(width 0.127)
		(layer "In3.Cu")
		(net "PCIE_TX3_P")
	)
	(segment
		(start 135.05181 144.7868)
		(end 142.02043 144.7868)
		(width 0.127)
		(layer "In3.Cu")
		(net "PCIE_TX3_P")
	)
	(segment
		(start 144.85887 144.7868)
		(end 177.66559 144.7868)
		(width 0.127)
		(layer "In3.Cu")
		(net "PCIE_TX3_P")
	)
	(segment
		(start 143.73494 144.6852)
		(end 143.73494 144.65977)
		(width 0.127)
		(layer "In3.Cu")
		(net "PCIE_TX3_P")
	)
	(arc
		(start 142.21094 144.6598)
		(mid 142.173743 144.749603)
		(end 142.08394 144.7868)
		(width 0.127)
		(layer "In3.Cu")
		(net "PCIE_TX3_P")
	)
	(arc
		(start 131.658673 150.153383)
		(mid 131.622444 150.17759)
		(end 131.57971 150.186091)
		(width 0.127)
		(layer "In3.Cu")
		(net "PCIE_TX3_P")
	)
	(arc
		(start 143.22694 144.6852)
		(mid 143.09994 144.8122)
		(end 142.97294 144.6852)
		(width 0.127)
		(layer "In3.Cu")
		(net "PCIE_TX3_P")
	)
	(arc
		(start 133.060555 145.611605)
		(mid 133.974151 145.00116)
		(end 135.05181 144.7868)
		(width 0.127)
		(layer "In3.Cu")
		(net "PCIE_TX3_P")
	)
	(arc
		(start 180.308258 143.834047)
		(mid 179.093296 144.605469)
		(end 177.665591 144.786802)
		(width 0.127)
		(layer "In3.Cu")
		(net "PCIE_TX3_P")
	)
	(arc
		(start 144.11594 144.7868)
		(mid 144.026137 144.749603)
		(end 143.98894 144.6598)
		(width 0.127)
		(layer "In3.Cu")
		(net "PCIE_TX3_P")
	)
	(arc
		(start 178.537421 134.504254)
		(mid 178.53142 134.494708)
		(end 178.525573 134.485067)
		(width 0.127)
		(layer "In3.Cu")
		(net "PCIE_TX3_P")
	)
	(arc
		(start 143.22694 144.60366)
		(mid 143.35394 144.47666)
		(end 143.48094 144.60366)
		(width 0.127)
		(layer "In3.Cu")
		(net "PCIE_TX3_P")
	)
	(arc
		(start 143.73494 144.6852)
		(mid 143.60794 144.8122)
		(end 143.48094 144.6852)
		(width 0.127)
		(layer "In3.Cu")
		(net "PCIE_TX3_P")
	)
	(arc
		(start 181.200992 142.941313)
		(mid 181.200585 142.94172)
		(end 181.200176 142.942125)
		(width 0.127)
		(layer "In3.Cu")
		(net "PCIE_TX3_P")
	)
	(arc
		(start 131.93821 147.74173)
		(mid 132.123408 146.810677)
		(end 132.650807 146.021367)
		(width 0.127)
		(layer "In3.Cu")
		(net "PCIE_TX3_P")
	)
	(arc
		(start 142.71894 144.59689)
		(mid 142.84594 144.46989)
		(end 142.97294 144.59689)
		(width 0.127)
		(layer "In3.Cu")
		(net "PCIE_TX3_P")
	)
	(arc
		(start 178.632916 134.623004)
		(mid 178.581955 134.566213)
		(end 178.537421 134.504254)
		(width 0.127)
		(layer "In3.Cu")
		(net "PCIE_TX3_P")
	)
	(arc
		(start 178.507022 134.461219)
		(mid 178.517002 134.472593)
		(end 178.525559 134.485074)
		(width 0.127)
		(layer "In3.Cu")
		(net "PCIE_TX3_P")
	)
	(arc
		(start 142.21094 144.59689)
		(mid 142.33794 144.46989)
		(end 142.46494 144.59689)
		(width 0.127)
		(layer "In3.Cu")
		(net "PCIE_TX3_P")
	)
	(arc
		(start 178.50115 134.455338)
		(mid 178.445612 134.372709)
		(end 178.4261 134.27508)
		(width 0.127)
		(layer "In3.Cu")
		(net "PCIE_TX3_P")
	)
	(arc
		(start 180.957146 136.947256)
		(mid 181.248714 137.383615)
		(end 181.3511 137.898337)
		(width 0.127)
		(layer "In3.Cu")
		(net "PCIE_TX3_P")
	)
	(arc
		(start 131.9382 149.47852)
		(mid 131.865551 149.843752)
		(end 131.658664 150.153381)
		(width 0.127)
		(layer "In3.Cu")
		(net "PCIE_TX3_P")
	)
	(arc
		(start 142.71894 144.6852)
		(mid 142.59194 144.8122)
		(end 142.46494 144.6852)
		(width 0.127)
		(layer "In3.Cu")
		(net "PCIE_TX3_P")
	)
	(arc
		(start 143.73494 144.65977)
		(mid 143.86194 144.53277)
		(end 143.98894 144.65977)
		(width 0.127)
		(layer "In3.Cu")
		(net "PCIE_TX3_P")
	)
	(arc
		(start 181.3511 142.73859)
		(mid 181.341538 142.786935)
		(end 181.314293 142.828001)
		(width 0.127)
		(layer "In3.Cu")
		(net "PCIE_TX3_P")
	)
	(segment
		(start 179.33595 137.60482)
		(end 179.33595 135.50523)
		(width 0.127)
		(layer "F.Cu")
		(net "PCIE_TX2_N")
	)
	(via
		(at 179.3261 137.6286)
		(size 0.4064)
		(drill 0.2032)
		(layers "F.Cu" "B.Cu")
		(tenting
			(front yes)
			(back yes)
		)
		(net "PCIE_TX2_N")
	)
	(via
		(at 128.3761 150.2786)
		(size 0.4064)
		(drill 0.2032)
		(layers "F.Cu" "B.Cu")
		(tenting
			(front yes)
			(back yes)
		)
		(net "PCIE_TX2_N")
	)
	(arc
		(start 179.33595 137.60482)
		(mid 179.33339 137.61769)
		(end 179.3261 137.6286)
		(width 0.127)
		(layer "F.Cu")
		(net "PCIE_TX2_N")
	)
	(segment
		(start 128.3761 151.32721)
		(end 128.3761 150.2786)
		(width 0.127)
		(layer "B.Cu")
		(net "PCIE_TX2_N")
	)
	(arc
		(start 128.389099 151.358591)
		(mid 128.379479 151.344193)
		(end 128.376101 151.32721)
		(width 0.127)
		(layer "B.Cu")
		(net "PCIE_TX2_N")
	)
	(segment
		(start 179.5864 139.8038)
		(end 179.5864 138.25702)
		(width 0.127)
		(layer "In3.Cu")
		(net "PCIE_TX2_N")
	)
	(segment
		(start 128.0658 150.50319)
		(end 128.0658 150.48196)
		(width 0.127)
		(layer "In3.Cu")
		(net "PCIE_TX2_N")
	)
	(segment
		(start 128.81773 148.11058)
		(end 128.81773 147.26009)
		(width 0.127)
		(layer "In3.Cu")
		(net "PCIE_TX2_N")
	)
	(segment
		(start 128.2157 150.33206)
		(end 128.24704 150.33206)
		(width 0.127)
		(layer "In3.Cu")
		(net "PCIE_TX2_N")
	)
	(segment
		(start 127.29916 149.65553)
		(end 127.29972 149.65497)
		(width 0.127)
		(layer "In3.Cu")
		(net "PCIE_TX2_N")
	)
	(segment
		(start 178.00665 142.43565)
		(end 178.84245 141.59985)
		(width 0.127)
		(layer "In3.Cu")
		(net "PCIE_TX2_N")
	)
	(segment
		(start 127.24235 150.58482)
		(end 127.24303 150.58549)
		(width 0.127)
		(layer "In3.Cu")
		(net "PCIE_TX2_N")
	)
	(segment
		(start 127.29972 149.65497)
		(end 128.79906 148.15566)
		(width 0.127)
		(layer "In3.Cu")
		(net "PCIE_TX2_N")
	)
	(segment
		(start 129.64254 145.26883)
		(end 130.90697 144.00441)
		(width 0.127)
		(layer "In3.Cu")
		(net "PCIE_TX2_N")
	)
	(segment
		(start 128.79906 148.15566)
		(end 128.79906 148.15565)
		(width 0.127)
		(layer "In3.Cu")
		(net "PCIE_TX2_N")
	)
	(segment
		(start 132.89822 143.1796)
		(end 176.2106 143.1796)
		(width 0.127)
		(layer "In3.Cu")
		(net "PCIE_TX2_N")
	)
	(segment
		(start 127.08161 150.22666)
		(end 127.08166 150.22751)
		(width 0.127)
		(layer "In3.Cu")
		(net "PCIE_TX2_N")
	)
	(arc
		(start 128.109705 150.375965)
		(mid 128.158336 150.343471)
		(end 128.2157 150.33206)
		(width 0.127)
		(layer "In3.Cu")
		(net "PCIE_TX2_N")
	)
	(arc
		(start 128.025146 150.596325)
		(mid 127.631909 150.747996)
		(end 127.243025 150.585491)
		(width 0.127)
		(layer "In3.Cu")
		(net "PCIE_TX2_N")
	)
	(arc
		(start 128.81773 148.11058)
		(mid 128.812877 148.134976)
		(end 128.799058 148.155658)
		(width 0.127)
		(layer "In3.Cu")
		(net "PCIE_TX2_N")
	)
	(arc
		(start 128.376101 150.278601)
		(mid 128.316887 150.318166)
		(end 128.24704 150.33206)
		(width 0.127)
		(layer "In3.Cu")
		(net "PCIE_TX2_N")
	)
	(arc
		(start 128.0658 150.50319)
		(mid 128.055193 150.553999)
		(end 128.025145 150.596322)
		(width 0.127)
		(layer "In3.Cu")
		(net "PCIE_TX2_N")
	)
	(arc
		(start 127.081603 150.226667)
		(mid 127.130115 149.918146)
		(end 127.299151 149.655534)
		(width 0.127)
		(layer "In3.Cu")
		(net "PCIE_TX2_N")
	)
	(arc
		(start 178.006651 142.435651)
		(mid 177.182616 142.986254)
		(end 176.2106 143.1796)
		(width 0.127)
		(layer "In3.Cu")
		(net "PCIE_TX2_N")
	)
	(arc
		(start 130.906965 144.004405)
		(mid 131.820561 143.39396)
		(end 132.89822 143.1796)
		(width 0.127)
		(layer "In3.Cu")
		(net "PCIE_TX2_N")
	)
	(arc
		(start 128.81773 147.26009)
		(mid 129.032091 146.182427)
		(end 129.642538 145.268828)
		(width 0.127)
		(layer "In3.Cu")
		(net "PCIE_TX2_N")
	)
	(arc
		(start 127.242342 150.584826)
		(mid 127.129342 150.420854)
		(end 127.081659 150.227509)
		(width 0.127)
		(layer "In3.Cu")
		(net "PCIE_TX2_N")
	)
	(arc
		(start 179.326107 137.628593)
		(mid 179.518759 137.916918)
		(end 179.58641 138.25702)
		(width 0.127)
		(layer "In3.Cu")
		(net "PCIE_TX2_N")
	)
	(arc
		(start 179.5864 139.8038)
		(mid 179.393054 140.775816)
		(end 178.842451 141.599851)
		(width 0.127)
		(layer "In3.Cu")
		(net "PCIE_TX2_N")
	)
	(arc
		(start 128.0658 150.48196)
		(mid 128.07721 150.424597)
		(end 128.109703 150.375966)
		(width 0.127)
		(layer "In3.Cu")
		(net "PCIE_TX2_N")
	)
	(segment
		(start 179.83582 136.9278)
		(end 179.83582 135.50523)
		(width 0.127)
		(layer "F.Cu")
		(net "PCIE_TX2_P")
	)
	(via
		(at 180.1261 137.6286)
		(size 0.4064)
		(drill 0.2032)
		(layers "F.Cu" "B.Cu")
		(tenting
			(front yes)
			(back yes)
		)
		(net "PCIE_TX2_P")
	)
	(via
		(at 127.55447 150.21916)
		(size 0.4064)
		(drill 0.2032)
		(layers "F.Cu" "B.Cu")
		(tenting
			(front yes)
			(back yes)
		)
		(net "PCIE_TX2_P")
	)
	(arc
		(start 180.126101 137.628599)
		(mid 179.911262 137.30707)
		(end 179.835821 136.9278)
		(width 0.127)
		(layer "F.Cu")
		(net "PCIE_TX2_P")
	)
	(segment
		(start 127.4761 151.30066)
		(end 127.4761 150.33546)
		(width 0.127)
		(layer "B.Cu")
		(net "PCIE_TX2_P")
	)
	(arc
		(start 127.5001 151.3586)
		(mid 127.482338 151.332017)
		(end 127.4761 151.30066)
		(width 0.127)
		(layer "B.Cu")
		(net "PCIE_TX2_P")
	)
	(arc
		(start 127.476104 150.335451)
		(mid 127.497783 150.265506)
		(end 127.554475 150.219157)
		(width 0.127)
		(layer "B.Cu")
		(net "PCIE_TX2_P")
	)
	(segment
		(start 179.8658 139.80759)
		(end 179.8658 138.25702)
		(width 0.127)
		(layer "In3.Cu")
		(net "PCIE_TX2_P")
	)
	(segment
		(start 128.69139 148.89193)
		(end 128.84354 149.04408)
		(width 0.127)
		(layer "In3.Cu")
		(net "PCIE_TX2_P")
	)
	(segment
		(start 127.41061 150.11074)
		(end 127.41865 150.13135)
		(width 0.127)
		(layer "In3.Cu")
		(net "PCIE_TX2_P")
	)
	(segment
		(start 129.01081 148.40311)
		(end 129.05571 148.35821)
		(width 0.127)
		(layer "In3.Cu")
		(net "PCIE_TX2_P")
	)
	(segment
		(start 129.05571 148.35821)
		(end 129.05571 148.35821)
		(width 0.127)
		(layer "In3.Cu")
		(net "PCIE_TX2_P")
	)
	(segment
		(start 127.43912 149.97478)
		(end 127.93317 149.48074)
		(width 0.127)
		(layer "In3.Cu")
		(net "PCIE_TX2_P")
	)
	(segment
		(start 129.84108 145.46542)
		(end 131.10356 144.20295)
		(width 0.127)
		(layer "In3.Cu")
		(net "PCIE_TX2_P")
	)
	(segment
		(start 129.0108 148.67252)
		(end 129.11295 148.77468)
		(width 0.127)
		(layer "In3.Cu")
		(net "PCIE_TX2_P")
	)
	(segment
		(start 129.09713 147.60044)
		(end 129.09713 147.26147)
		(width 0.127)
		(layer "In3.Cu")
		(net "PCIE_TX2_P")
	)
	(segment
		(start 127.54687 150.22158)
		(end 127.54929 150.21916)
		(width 0.127)
		(layer "In3.Cu")
		(net "PCIE_TX2_P")
	)
	(segment
		(start 129.05571 148.35821)
		(end 129.07805 148.33587)
		(width 0.127)
		(layer "In3.Cu")
		(net "PCIE_TX2_P")
	)
	(segment
		(start 132.89961 143.459)
		(end 176.21198 143.459)
		(width 0.127)
		(layer "In3.Cu")
		(net "PCIE_TX2_P")
	)
	(segment
		(start 128.42198 149.16134)
		(end 128.57413 149.31349)
		(width 0.127)
		(layer "In3.Cu")
		(net "PCIE_TX2_P")
	)
	(segment
		(start 129.1158 148.24551)
		(end 129.1158 147.64552)
		(width 0.127)
		(layer "In3.Cu")
		(net "PCIE_TX2_P")
	)
	(segment
		(start 178.20324 142.63419)
		(end 179.04269 141.79474)
		(width 0.127)
		(layer "In3.Cu")
		(net "PCIE_TX2_P")
	)
	(segment
		(start 180.1261 137.6286)
		(end 180.1261 137.6286)
		(width 0.127)
		(layer "In3.Cu")
		(net "PCIE_TX2_P")
	)
	(segment
		(start 127.54929 150.21916)
		(end 127.55447 150.21916)
		(width 0.127)
		(layer "In3.Cu")
		(net "PCIE_TX2_P")
	)
	(segment
		(start 129.0108 148.40311)
		(end 129.01081 148.40311)
		(width 0.127)
		(layer "In3.Cu")
		(net "PCIE_TX2_P")
	)
	(segment
		(start 127.41865 150.13135)
		(end 127.46614 150.25308)
		(width 0.127)
		(layer "In3.Cu")
		(net "PCIE_TX2_P")
	)
	(segment
		(start 127.41061 150.11074)
		(end 127.43912 149.97478)
		(width 0.127)
		(layer "In3.Cu")
		(net "PCIE_TX2_P")
	)
	(segment
		(start 127.46614 150.25308)
		(end 127.49764 150.22158)
		(width 0.127)
		(layer "In3.Cu")
		(net "PCIE_TX2_P")
	)
	(segment
		(start 128.20257 149.48075)
		(end 128.30472 149.5829)
		(width 0.127)
		(layer "In3.Cu")
		(net "PCIE_TX2_P")
	)
	(segment
		(start 127.49764 150.22158)
		(end 127.54687 150.22158)
		(width 0.127)
		(layer "In3.Cu")
		(net "PCIE_TX2_P")
	)
	(arc
		(start 131.103559 144.202949)
		(mid 131.927594 143.652346)
		(end 132.89961 143.459)
		(width 0.127)
		(layer "In3.Cu")
		(net "PCIE_TX2_P")
	)
	(arc
		(start 129.1158 148.24551)
		(mid 129.106132 148.294112)
		(end 129.0786 148.335315)
		(width 0.127)
		(layer "In3.Cu")
		(net "PCIE_TX2_P")
	)
	(arc
		(start 128.574134 149.313486)
		(mid 128.62993 149.44819)
		(end 128.574134 149.582894)
		(width 0.127)
		(layer "In3.Cu")
		(net "PCIE_TX2_P")
	)
	(arc
		(start 127.933167 149.480745)
		(mid 128.067871 149.42495)
		(end 128.202574 149.480746)
		(width 0.127)
		(layer "In3.Cu")
		(net "PCIE_TX2_P")
	)
	(arc
		(start 129.09713 147.26147)
		(mid 129.290476 146.289454)
		(end 129.841079 145.465419)
		(width 0.127)
		(layer "In3.Cu")
		(net "PCIE_TX2_P")
	)
	(arc
		(start 129.078049 148.335872)
		(mid 129.078328 148.335594)
		(end 129.078607 148.335317)
		(width 0.127)
		(layer "In3.Cu")
		(net "PCIE_TX2_P")
	)
	(arc
		(start 128.421986 149.161334)
		(mid 128.36619 149.026632)
		(end 128.421983 148.891929)
		(width 0.127)
		(layer "In3.Cu")
		(net "PCIE_TX2_P")
	)
	(arc
		(start 129.115802 147.645518)
		(mid 129.101983 147.624836)
		(end 129.09713 147.60044)
		(width 0.127)
		(layer "In3.Cu")
		(net "PCIE_TX2_P")
	)
	(arc
		(start 178.203242 142.634192)
		(mid 177.289643 143.244639)
		(end 176.21198 143.459)
		(width 0.127)
		(layer "In3.Cu")
		(net "PCIE_TX2_P")
	)
	(arc
		(start 129.112951 149.044086)
		(mid 128.978249 149.09988)
		(end 128.843547 149.044084)
		(width 0.127)
		(layer "In3.Cu")
		(net "PCIE_TX2_P")
	)
	(arc
		(start 128.421986 148.891936)
		(mid 128.55669 148.83614)
		(end 128.691394 148.891936)
		(width 0.127)
		(layer "In3.Cu")
		(net "PCIE_TX2_P")
	)
	(arc
		(start 129.112954 148.774676)
		(mid 129.16875 148.90938)
		(end 129.112954 149.044084)
		(width 0.127)
		(layer "In3.Cu")
		(net "PCIE_TX2_P")
	)
	(arc
		(start 128.574131 149.582896)
		(mid 128.439429 149.63869)
		(end 128.304727 149.582894)
		(width 0.127)
		(layer "In3.Cu")
		(net "PCIE_TX2_P")
	)
	(arc
		(start 179.8658 139.807583)
		(mid 179.651881 140.883018)
		(end 179.042695 141.794728)
		(width 0.127)
		(layer "In3.Cu")
		(net "PCIE_TX2_P")
	)
	(arc
		(start 129.010797 148.672525)
		(mid 128.955 148.537821)
		(end 129.010796 148.403116)
		(width 0.127)
		(layer "In3.Cu")
		(net "PCIE_TX2_P")
	)
	(arc
		(start 179.8658 138.25702)
		(mid 179.93345 137.916922)
		(end 180.126099 137.628601)
		(width 0.127)
		(layer "In3.Cu")
		(net "PCIE_TX2_P")
	)
	(segment
		(start 176.33596 136.76772)
		(end 176.33596 135.50523)
		(width 0.127)
		(layer "F.Cu")
		(net "PCIE_TX1_N")
	)
	(segment
		(start 176.0261 137.51578)
		(end 176.0261 137.51658)
		(width 0.127)
		(layer "F.Cu")
		(net "PCIE_TX1_N")
	)
	(segment
		(start 176.0261 137.6286)
		(end 176.0261 137.51658)
		(width 0.127)
		(layer "F.Cu")
		(net "PCIE_TX1_N")
	)
	(via
		(at 176.0261 137.6286)
		(size 0.4064)
		(drill 0.2032)
		(layers "F.Cu" "B.Cu")
		(tenting
			(front yes)
			(back yes)
		)
		(net "PCIE_TX1_N")
	)
	(via
		(at 124.5761 150.2786)
		(size 0.4064)
		(drill 0.2032)
		(layers "F.Cu" "B.Cu")
		(tenting
			(front yes)
			(back yes)
		)
		(net "PCIE_TX1_N")
	)
	(arc
		(start 176.0261 137.51578)
		(mid 176.078875 137.250465)
		(end 176.229164 137.025542)
		(width 0.127)
		(layer "F.Cu")
		(net "PCIE_TX1_N")
	)
	(arc
		(start 176.33596 136.76772)
		(mid 176.308206 136.90725)
		(end 176.229168 137.025538)
		(width 0.127)
		(layer "F.Cu")
		(net "PCIE_TX1_N")
	)
	(segment
		(start 124.5761 151.3556)
		(end 124.5791 151.3586)
		(width 0.127)
		(layer "B.Cu")
		(net "PCIE_TX1_N")
	)
	(segment
		(start 124.5761 151.3556)
		(end 124.5761 150.2786)
		(width 0.127)
		(layer "B.Cu")
		(net "PCIE_TX1_N")
	)
	(segment
		(start 125.27436 148.17196)
		(end 125.3213 148.17196)
		(width 0.127)
		(layer "In3.Cu")
		(net "PCIE_TX1_N")
	)
	(segment
		(start 125.4864 147.21946)
		(end 125.4864 146.77495)
		(width 0.127)
		(layer "In3.Cu")
		(net "PCIE_TX1_N")
	)
	(segment
		(start 125.27436 148.55296)
		(end 125.3213 148.55296)
		(width 0.127)
		(layer "In3.Cu")
		(net "PCIE_TX1_N")
	)
	(segment
		(start 125.29588 148.93396)
		(end 125.3213 148.93396)
		(width 0.127)
		(layer "In3.Cu")
		(net "PCIE_TX1_N")
	)
	(segment
		(start 125.29588 149.31496)
		(end 125.2959 149.31496)
		(width 0.127)
		(layer "In3.Cu")
		(net "PCIE_TX1_N")
	)
	(segment
		(start 125.37172 150.19983)
		(end 125.4864 149.82947)
		(width 0.127)
		(layer "In3.Cu")
		(net "PCIE_TX1_N")
	)
	(segment
		(start 125.4864 146.77495)
		(end 125.4864 146.36419)
		(width 0.127)
		(layer "In3.Cu")
		(net "PCIE_TX1_N")
	)
	(segment
		(start 176.0261 137.6324)
		(end 176.0261 137.6286)
		(width 0.127)
		(layer "In3.Cu")
		(net "PCIE_TX1_N")
	)
	(segment
		(start 124.5761 150.27861)
		(end 124.5761 150.2786)
		(width 0.127)
		(layer "In3.Cu")
		(net "PCIE_TX1_N")
	)
	(segment
		(start 126.31151 144.37219)
		(end 127.9239 142.75981)
		(width 0.127)
		(layer "In3.Cu")
		(net "PCIE_TX1_N")
	)
	(segment
		(start 125.3542 150.2242)
		(end 125.35461 150.22366)
		(width 0.127)
		(layer "In3.Cu")
		(net "PCIE_TX1_N")
	)
	(segment
		(start 125.24464 147.40996)
		(end 125.2959 147.40996)
		(width 0.127)
		(layer "In3.Cu")
		(net "PCIE_TX1_N")
	)
	(segment
		(start 129.91515 141.935)
		(end 174.26264 141.935)
		(width 0.127)
		(layer "In3.Cu")
		(net "PCIE_TX1_N")
	)
	(segment
		(start 125.24464 147.79096)
		(end 125.3213 147.79096)
		(width 0.127)
		(layer "In3.Cu")
		(net "PCIE_TX1_N")
	)
	(segment
		(start 176.2364 139.86805)
		(end 176.2364 138.14011)
		(width 0.127)
		(layer "In3.Cu")
		(net "PCIE_TX1_N")
	)
	(segment
		(start 125.4864 149.82947)
		(end 125.4864 149.50546)
		(width 0.127)
		(layer "In3.Cu")
		(net "PCIE_TX1_N")
	)
	(arc
		(start 176.2364 139.86805)
		(mid 176.074046 140.684256)
		(end 175.611703 141.376203)
		(width 0.127)
		(layer "In3.Cu")
		(net "PCIE_TX1_N")
	)
	(arc
		(start 127.923895 142.759805)
		(mid 128.837491 142.14936)
		(end 129.91515 141.935)
		(width 0.127)
		(layer "In3.Cu")
		(net "PCIE_TX1_N")
	)
	(arc
		(start 125.4864 146.36419)
		(mid 125.700839 145.286133)
		(end 126.311509 144.372199)
		(width 0.127)
		(layer "In3.Cu")
		(net "PCIE_TX1_N")
	)
	(arc
		(start 125.321158 150.263333)
		(mid 124.951856 150.42845)
		(end 124.576097 150.278605)
		(width 0.127)
		(layer "In3.Cu")
		(net "PCIE_TX1_N")
	)
	(arc
		(start 176.0261 137.6324)
		(mid 176.181745 137.865339)
		(end 176.2364 138.14011)
		(width 0.127)
		(layer "In3.Cu")
		(net "PCIE_TX1_N")
	)
	(arc
		(start 175.611701 141.376201)
		(mid 174.992747 141.789773)
		(end 174.26264 141.935)
		(width 0.127)
		(layer "In3.Cu")
		(net "PCIE_TX1_N")
	)
	(arc
		(start 125.2959 149.31496)
		(mid 125.430604 149.370756)
		(end 125.4864 149.50546)
		(width 0.127)
		(layer "In3.Cu")
		(net "PCIE_TX1_N")
	)
	(arc
		(start 125.4864 147.21946)
		(mid 125.430604 147.354164)
		(end 125.2959 147.40996)
		(width 0.127)
		(layer "In3.Cu")
		(net "PCIE_TX1_N")
	)
	(arc
		(start 125.3213 148.55296)
		(mid 125.5118 148.74346)
		(end 125.3213 148.93396)
		(width 0.127)
		(layer "In3.Cu")
		(net "PCIE_TX1_N")
	)
	(arc
		(start 125.371719 150.199831)
		(mid 125.363295 150.211839)
		(end 125.354604 150.223656)
		(width 0.127)
		(layer "In3.Cu")
		(net "PCIE_TX1_N")
	)
	(arc
		(start 125.24464 147.79096)
		(mid 125.05414 147.60046)
		(end 125.24464 147.40996)
		(width 0.127)
		(layer "In3.Cu")
		(net "PCIE_TX1_N")
	)
	(arc
		(start 125.354195 150.224197)
		(mid 125.338159 150.244173)
		(end 125.321158 150.263334)
		(width 0.127)
		(layer "In3.Cu")
		(net "PCIE_TX1_N")
	)
	(arc
		(start 125.3213 147.79096)
		(mid 125.5118 147.98146)
		(end 125.3213 148.17196)
		(width 0.127)
		(layer "In3.Cu")
		(net "PCIE_TX1_N")
	)
	(arc
		(start 125.27436 148.55296)
		(mid 125.08386 148.36246)
		(end 125.27436 148.17196)
		(width 0.127)
		(layer "In3.Cu")
		(net "PCIE_TX1_N")
	)
	(arc
		(start 125.29588 149.31496)
		(mid 125.10538 149.12446)
		(end 125.29588 148.93396)
		(width 0.127)
		(layer "In3.Cu")
		(net "PCIE_TX1_N")
	)
	(segment
		(start 176.83583 137.36369)
		(end 176.83583 135.50523)
		(width 0.127)
		(layer "F.Cu")
		(net "PCIE_TX1_P")
	)
	(via
		(at 176.7261 137.6286)
		(size 0.4064)
		(drill 0.2032)
		(layers "F.Cu" "B.Cu")
		(tenting
			(front yes)
			(back yes)
		)
		(net "PCIE_TX1_P")
	)
	(via
		(at 123.5761 150.2786)
		(size 0.4064)
		(drill 0.2032)
		(layers "F.Cu" "B.Cu")
		(tenting
			(front yes)
			(back yes)
		)
		(net "PCIE_TX1_P")
	)
	(arc
		(start 176.83583 137.36369)
		(mid 176.807312 137.507059)
		(end 176.7261 137.6286)
		(width 0.127)
		(layer "F.Cu")
		(net "PCIE_TX1_P")
	)
	(segment
		(start 123.5761 151.32721)
		(end 123.5761 150.2786)
		(width 0.127)
		(layer "B.Cu")
		(net "PCIE_TX1_P")
	)
	(arc
		(start 123.5761 151.32721)
		(mid 123.572722 151.344193)
		(end 123.563101 151.358591)
		(width 0.127)
		(layer "B.Cu")
		(net "PCIE_TX1_P")
	)
	(segment
		(start 129.91654 142.2144)
		(end 174.2636 142.2144)
		(width 0.127)
		(layer "In3.Cu")
		(net "PCIE_TX1_P")
	)
	(segment
		(start 176.5158 139.87187)
		(end 176.5158 138.14011)
		(width 0.127)
		(layer "In3.Cu")
		(net "PCIE_TX1_P")
	)
	(segment
		(start 125.7658 149.8509)
		(end 125.7658 149.84976)
		(width 0.127)
		(layer "In3.Cu")
		(net "PCIE_TX1_P")
	)
	(segment
		(start 175.80859 141.57444)
		(end 175.81197 141.57106)
		(width 0.127)
		(layer "In3.Cu")
		(net "PCIE_TX1_P")
	)
	(segment
		(start 123.73229 150.4348)
		(end 123.73229 150.4348)
		(width 0.127)
		(layer "In3.Cu")
		(net "PCIE_TX1_P")
	)
	(segment
		(start 123.5761 150.2786)
		(end 123.73229 150.4348)
		(width 0.127)
		(layer "In3.Cu")
		(net "PCIE_TX1_P")
	)
	(segment
		(start 126.50975 144.56908)
		(end 128.12049 142.95835)
		(width 0.127)
		(layer "In3.Cu")
		(net "PCIE_TX1_P")
	)
	(segment
		(start 125.7658 149.84976)
		(end 125.7658 146.36514)
		(width 0.127)
		(layer "In3.Cu")
		(net "PCIE_TX1_P")
	)
	(segment
		(start 176.7261 137.6324)
		(end 176.7261 137.6286)
		(width 0.127)
		(layer "In3.Cu")
		(net "PCIE_TX1_P")
	)
	(arc
		(start 175.808593 141.574443)
		(mid 175.099744 142.048081)
		(end 174.2636 142.2144)
		(width 0.127)
		(layer "In3.Cu")
		(net "PCIE_TX1_P")
	)
	(arc
		(start 125.347413 150.613118)
		(mid 124.508485 150.808083)
		(end 123.732297 150.434794)
		(width 0.127)
		(layer "In3.Cu")
		(net "PCIE_TX1_P")
	)
	(arc
		(start 128.120489 142.958349)
		(mid 128.944524 142.407746)
		(end 129.91654 142.2144)
		(width 0.127)
		(layer "In3.Cu")
		(net "PCIE_TX1_P")
	)
	(arc
		(start 125.7658 146.36514)
		(mid 125.959146 145.393124)
		(end 126.509749 144.569089)
		(width 0.127)
		(layer "In3.Cu")
		(net "PCIE_TX1_P")
	)
	(arc
		(start 176.5158 139.871873)
		(mid 176.33288 140.791468)
		(end 175.811971 141.571062)
		(width 0.127)
		(layer "In3.Cu")
		(net "PCIE_TX1_P")
	)
	(arc
		(start 125.76579 149.850895)
		(mid 125.654316 150.285644)
		(end 125.347406 150.613118)
		(width 0.127)
		(layer "In3.Cu")
		(net "PCIE_TX1_P")
	)
	(arc
		(start 176.5158 138.14011)
		(mid 176.570455 137.865341)
		(end 176.726098 137.632403)
		(width 0.127)
		(layer "In3.Cu")
		(net "PCIE_TX1_P")
	)
	(segment
		(start 174.83583 132.91887)
		(end 174.83583 131.45545)
		(width 0.127)
		(layer "F.Cu")
		(net "PCIE_TX0_N")
	)
	(via
		(at 174.7261 133.0286)
		(size 0.4064)
		(drill 0.2032)
		(layers "F.Cu" "B.Cu")
		(tenting
			(front yes)
			(back yes)
		)
		(net "PCIE_TX0_N")
	)
	(via
		(at 119.6761 150.2786)
		(size 0.4064)
		(drill 0.2032)
		(layers "F.Cu" "B.Cu")
		(tenting
			(front yes)
			(back yes)
		)
		(net "PCIE_TX0_N")
	)
	(arc
		(start 174.83583 132.91887)
		(mid 174.803691 132.996461)
		(end 174.7261 133.0286)
		(width 0.127)
		(layer "F.Cu")
		(net "PCIE_TX0_N")
	)
	(segment
		(start 119.6761 151.3578)
		(end 119.6761 150.2786)
		(width 0.127)
		(layer "B.Cu")
		(net "PCIE_TX0_N")
	)
	(segment
		(start 119.6761 151.3578)
		(end 119.6769 151.3586)
		(width 0.127)
		(layer "B.Cu")
		(net "PCIE_TX0_N")
	)
	(segment
		(start 174.7261 133.0324)
		(end 174.7261 133.0286)
		(width 0.127)
		(layer "In3.Cu")
		(net "PCIE_TX0_N")
	)
	(segment
		(start 118.04191 146.96346)
		(end 118.04289 146.96248)
		(width 0.127)
		(layer "In3.Cu")
		(net "PCIE_TX0_N")
	)
	(segment
		(start 117.37514 149.90496)
		(end 117.37514 149.90496)
		(width 0.127)
		(layer "In3.Cu")
		(net "PCIE_TX0_N")
	)
	(segment
		(start 174.7261 133.0324)
		(end 174.80361 133.1099)
		(width 0.127)
		(layer "In3.Cu")
		(net "PCIE_TX0_N")
	)
	(segment
		(start 174.04244 136.23085)
		(end 174.04256 136.23073)
		(width 0.127)
		(layer "In3.Cu")
		(net "PCIE_TX0_N")
	)
	(segment
		(start 118.8233 150.66721)
		(end 118.82444 150.66721)
		(width 0.127)
		(layer "In3.Cu")
		(net "PCIE_TX0_N")
	)
	(segment
		(start 117.2171 149.52344)
		(end 117.2171 148.95472)
		(width 0.127)
		(layer "In3.Cu")
		(net "PCIE_TX0_N")
	)
	(segment
		(start 174.9364 133.4305)
		(end 174.9364 133.4305)
		(width 0.127)
		(layer "In3.Cu")
		(net "PCIE_TX0_N")
	)
	(segment
		(start 172.62851 136.2962)
		(end 173.8845 136.2962)
		(width 0.127)
		(layer "In3.Cu")
		(net "PCIE_TX0_N")
	)
	(segment
		(start 126.01482 140.157)
		(end 169.7189 140.157)
		(width 0.127)
		(layer "In3.Cu")
		(net "PCIE_TX0_N")
	)
	(segment
		(start 171.43229 137.36001)
		(end 172.45911 136.33319)
		(width 0.127)
		(layer "In3.Cu")
		(net "PCIE_TX0_N")
	)
	(segment
		(start 118.82444 150.66721)
		(end 119.28749 150.66721)
		(width 0.127)
		(layer "In3.Cu")
		(net "PCIE_TX0_N")
	)
	(segment
		(start 117.60374 150.13357)
		(end 117.91813 150.44796)
		(width 0.127)
		(layer "In3.Cu")
		(net "PCIE_TX0_N")
	)
	(segment
		(start 171.3953 138.03093)
		(end 171.3953 137.52941)
		(width 0.127)
		(layer "In3.Cu")
		(net "PCIE_TX0_N")
	)
	(segment
		(start 174.68829 135.585)
		(end 174.68829 134.02948)
		(width 0.127)
		(layer "In3.Cu")
		(net "PCIE_TX0_N")
	)
	(segment
		(start 124.00764 140.99773)
		(end 124.02356 140.98181)
		(width 0.127)
		(layer "In3.Cu")
		(net "PCIE_TX0_N")
	)
	(segment
		(start 118.54299 150.66721)
		(end 118.8233 150.66721)
		(width 0.127)
		(layer "In3.Cu")
		(net "PCIE_TX0_N")
	)
	(segment
		(start 174.04256 136.23073)
		(end 174.68829 135.585)
		(width 0.127)
		(layer "In3.Cu")
		(net "PCIE_TX0_N")
	)
	(segment
		(start 117.37514 149.90496)
		(end 117.60374 150.13357)
		(width 0.127)
		(layer "In3.Cu")
		(net "PCIE_TX0_N")
	)
	(segment
		(start 118.04289 146.96248)
		(end 124.00764 140.99773)
		(width 0.127)
		(layer "In3.Cu")
		(net "PCIE_TX0_N")
	)
	(segment
		(start 118.32225 150.6162)
		(end 118.3761 150.6162)
		(width 0.127)
		(layer "In3.Cu")
		(net "PCIE_TX0_N")
	)
	(segment
		(start 170.36931 139.88759)
		(end 170.80685 139.45005)
		(width 0.127)
		(layer "In3.Cu")
		(net "PCIE_TX0_N")
	)
	(arc
		(start 172.459104 136.333192)
		(mid 172.541811 136.305556)
		(end 172.62851 136.2962)
		(width 0.127)
		(layer "In3.Cu")
		(net "PCIE_TX0_N")
	)
	(arc
		(start 119.6761 150.2786)
		(mid 119.562279 150.553389)
		(end 119.28749 150.66721)
		(width 0.127)
		(layer "In3.Cu")
		(net "PCIE_TX0_N")
	)
	(arc
		(start 171.3953 137.52941)
		(mid 171.404655 137.442713)
		(end 171.43229 137.360007)
		(width 0.127)
		(layer "In3.Cu")
		(net "PCIE_TX0_N")
	)
	(arc
		(start 118.322245 150.61621)
		(mid 118.103346 150.57253)
		(end 117.918122 150.447962)
		(width 0.127)
		(layer "In3.Cu")
		(net "PCIE_TX0_N")
	)
	(arc
		(start 170.369311 139.887591)
		(mid 170.0709 140.086983)
		(end 169.7189 140.157)
		(width 0.127)
		(layer "In3.Cu")
		(net "PCIE_TX0_N")
	)
	(arc
		(start 174.9364 133.4305)
		(mid 174.901888 133.604005)
		(end 174.803605 133.751095)
		(width 0.127)
		(layer "In3.Cu")
		(net "PCIE_TX0_N")
	)
	(arc
		(start 174.803612 133.109898)
		(mid 174.901897 133.256991)
		(end 174.93641 133.4305)
		(width 0.127)
		(layer "In3.Cu")
		(net "PCIE_TX0_N")
	)
	(arc
		(start 174.68829 134.02948)
		(mid 174.718259 133.878818)
		(end 174.803602 133.751092)
		(width 0.127)
		(layer "In3.Cu")
		(net "PCIE_TX0_N")
	)
	(arc
		(start 174.042439 136.23085)
		(mid 173.969962 136.279217)
		(end 173.8845 136.2962)
		(width 0.127)
		(layer "In3.Cu")
		(net "PCIE_TX0_N")
	)
	(arc
		(start 118.3761 150.6162)
		(mid 118.427146 150.623849)
		(end 118.473709 150.646123)
		(width 0.127)
		(layer "In3.Cu")
		(net "PCIE_TX0_N")
	)
	(arc
		(start 171.3953 138.03093)
		(mid 171.242356 138.799071)
		(end 170.806852 139.450046)
		(width 0.127)
		(layer "In3.Cu")
		(net "PCIE_TX0_N")
	)
	(arc
		(start 124.023565 140.981805)
		(mid 124.937161 140.37136)
		(end 126.01482 140.157)
		(width 0.127)
		(layer "In3.Cu")
		(net "PCIE_TX0_N")
	)
	(arc
		(start 118.542985 150.667207)
		(mid 118.50681 150.661706)
		(end 118.473705 150.64612)
		(width 0.127)
		(layer "In3.Cu")
		(net "PCIE_TX0_N")
	)
	(arc
		(start 117.2171 148.95472)
		(mid 117.431461 147.877057)
		(end 118.041908 146.963458)
		(width 0.127)
		(layer "In3.Cu")
		(net "PCIE_TX0_N")
	)
	(arc
		(start 117.375133 149.904967)
		(mid 117.258171 149.729921)
		(end 117.217099 149.52344)
		(width 0.127)
		(layer "In3.Cu")
		(net "PCIE_TX0_N")
	)
	(segment
		(start 175.33596 132.93846)
		(end 175.33596 131.45545)
		(width 0.127)
		(layer "F.Cu")
		(net "PCIE_TX0_P")
	)
	(via
		(at 175.4261 133.0286)
		(size 0.4064)
		(drill 0.2032)
		(layers "F.Cu" "B.Cu")
		(tenting
			(front yes)
			(back yes)
		)
		(net "PCIE_TX0_P")
	)
	(via
		(at 118.61112 150.1395)
		(size 0.4064)
		(drill 0.2032)
		(layers "F.Cu" "B.Cu")
		(tenting
			(front yes)
			(back yes)
		)
		(net "PCIE_TX0_P")
	)
	(arc
		(start 175.4261 133.0286)
		(mid 175.362361 133.002199)
		(end 175.33596 132.93846)
		(width 0.127)
		(layer "F.Cu")
		(net "PCIE_TX0_P")
	)
	(segment
		(start 118.5761 151.35)
		(end 118.5761 150.29143)
		(width 0.127)
		(layer "B.Cu")
		(net "PCIE_TX0_P")
	)
	(segment
		(start 118.61082 150.1398)
		(end 118.61112 150.1395)
		(width 0.127)
		(layer "B.Cu")
		(net "PCIE_TX0_P")
	)
	(segment
		(start 118.5761 150.29143)
		(end 118.57679 150.22501)
		(width 0.127)
		(layer "B.Cu")
		(net "PCIE_TX0_P")
	)
	(segment
		(start 118.6095 150.14126)
		(end 118.61082 150.1398)
		(width 0.127)
		(layer "B.Cu")
		(net "PCIE_TX0_P")
	)
	(segment
		(start 118.5761 151.35)
		(end 118.5847 151.3586)
		(width 0.127)
		(layer "B.Cu")
		(net "PCIE_TX0_P")
	)
	(arc
		(start 118.576797 150.225012)
		(mid 118.585489 150.180146)
		(end 118.6095 150.141261)
		(width 0.127)
		(layer "B.Cu")
		(net "PCIE_TX0_P")
	)
	(segment
		(start 175.4261 133.0324)
		(end 175.4261 133.0286)
		(width 0.127)
		(layer "In3.Cu")
		(net "PCIE_TX0_P")
	)
	(segment
		(start 120.6016 145.05252)
		(end 120.6348 145.08572)
		(width 0.127)
		(layer "In3.Cu")
		(net "PCIE_TX0_P")
	)
	(segment
		(start 174.96769 135.58571)
		(end 174.96769 134.08735)
		(width 0.127)
		(layer "In3.Cu")
		(net "PCIE_TX0_P")
	)
	(segment
		(start 120.33219 145.32193)
		(end 120.36539 145.35513)
		(width 0.127)
		(layer "In3.Cu")
		(net "PCIE_TX0_P")
	)
	(segment
		(start 171.71149 137.44002)
		(end 172.5391 136.61241)
		(width 0.127)
		(layer "In3.Cu")
		(net "PCIE_TX0_P")
	)
	(segment
		(start 126.0162 140.4364)
		(end 169.71986 140.4364)
		(width 0.127)
		(layer "In3.Cu")
		(net "PCIE_TX0_P")
	)
	(segment
		(start 171.6747 137.92765)
		(end 171.6747 137.52941)
		(width 0.127)
		(layer "In3.Cu")
		(net "PCIE_TX0_P")
	)
	(segment
		(start 174.23914 136.42928)
		(end 174.88635 135.78207)
		(width 0.127)
		(layer "In3.Cu")
		(net "PCIE_TX0_P")
	)
	(segment
		(start 119.53186 146.13805)
		(end 119.55717 146.16335)
		(width 0.127)
		(layer "In3.Cu")
		(net "PCIE_TX0_P")
	)
	(segment
		(start 120.8789 144.79101)
		(end 120.8789 144.79101)
		(width 0.127)
		(layer "In3.Cu")
		(net "PCIE_TX0_P")
	)
	(segment
		(start 175.38951 133.06898)
		(end 175.4261 133.0324)
		(width 0.127)
		(layer "In3.Cu")
		(net "PCIE_TX0_P")
	)
	(segment
		(start 120.06278 145.59134)
		(end 120.09598 145.62454)
		(width 0.127)
		(layer "In3.Cu")
		(net "PCIE_TX0_P")
	)
	(segment
		(start 118.94813 146.45237)
		(end 119.26245 146.13805)
		(width 0.127)
		(layer "In3.Cu")
		(net "PCIE_TX0_P")
	)
	(segment
		(start 118.24045 147.16005)
		(end 118.94813 146.45237)
		(width 0.127)
		(layer "In3.Cu")
		(net "PCIE_TX0_P")
	)
	(segment
		(start 118.61082 150.13979)
		(end 118.61112 150.1395)
		(width 0.127)
		(layer "In3.Cu")
		(net "PCIE_TX0_P")
	)
	(segment
		(start 117.57271 149.7074)
		(end 118.00438 150.13908)
		(width 0.127)
		(layer "In3.Cu")
		(net "PCIE_TX0_P")
	)
	(segment
		(start 170.5662 140.08583)
		(end 170.93247 139.71957)
		(width 0.127)
		(layer "In3.Cu")
		(net "PCIE_TX0_P")
	)
	(segment
		(start 172.62851 136.5756)
		(end 173.88589 136.5756)
		(width 0.127)
		(layer "In3.Cu")
		(net "PCIE_TX0_P")
	)
	(segment
		(start 122.18671 143.21379)
		(end 124.22015 141.18035)
		(width 0.127)
		(layer "In3.Cu")
		(net "PCIE_TX0_P")
	)
	(segment
		(start 117.4965 149.52343)
		(end 117.4965 148.9561)
		(width 0.127)
		(layer "In3.Cu")
		(net "PCIE_TX0_P")
	)
	(segment
		(start 118.60487 150.1417)
		(end 118.61082 150.13979)
		(width 0.127)
		(layer "In3.Cu")
		(net "PCIE_TX0_P")
	)
	(segment
		(start 119.79338 145.86075)
		(end 119.82658 145.89395)
		(width 0.127)
		(layer "In3.Cu")
		(net "PCIE_TX0_P")
	)
	(segment
		(start 120.8789 144.79101)
		(end 120.90421 144.81631)
		(width 0.127)
		(layer "In3.Cu")
		(net "PCIE_TX0_P")
	)
	(segment
		(start 120.8789 144.5216)
		(end 122.18671 143.21379)
		(width 0.127)
		(layer "In3.Cu")
		(net "PCIE_TX0_P")
	)
	(arc
		(start 174.239146 136.429276)
		(mid 174.077071 136.537571)
		(end 173.88589 136.575599)
		(width 0.127)
		(layer "In3.Cu")
		(net "PCIE_TX0_P")
	)
	(arc
		(start 119.826574 145.893946)
		(mid 119.88237 146.02865)
		(end 119.826574 146.163354)
		(width 0.127)
		(layer "In3.Cu")
		(net "PCIE_TX0_P")
	)
	(arc
		(start 171.6747 137.92765)
		(mid 171.481799 138.897427)
		(end 170.932465 139.719565)
		(width 0.127)
		(layer "In3.Cu")
		(net "PCIE_TX0_P")
	)
	(arc
		(start 174.96769 135.58571)
		(mid 174.946551 135.691981)
		(end 174.886354 135.782074)
		(width 0.127)
		(layer "In3.Cu")
		(net "PCIE_TX0_P")
	)
	(arc
		(start 120.904204 144.816316)
		(mid 120.96 144.95102)
		(end 120.904204 145.085724)
		(width 0.127)
		(layer "In3.Cu")
		(net "PCIE_TX0_P")
	)
	(arc
		(start 120.332196 145.321934)
		(mid 120.2764 145.187232)
		(end 120.332193 145.052529)
		(width 0.127)
		(layer "In3.Cu")
		(net "PCIE_TX0_P")
	)
	(arc
		(start 120.904201 145.085726)
		(mid 120.769499 145.14152)
		(end 120.634797 145.085724)
		(width 0.127)
		(layer "In3.Cu")
		(net "PCIE_TX0_P")
	)
	(arc
		(start 119.262456 146.138046)
		(mid 119.39716 146.08225)
		(end 119.531864 146.138046)
		(width 0.127)
		(layer "In3.Cu")
		(net "PCIE_TX0_P")
	)
	(arc
		(start 120.878896 144.791004)
		(mid 120.8231 144.6563)
		(end 120.878896 144.521596)
		(width 0.127)
		(layer "In3.Cu")
		(net "PCIE_TX0_P")
	)
	(arc
		(start 118.30779 150.26476)
		(mid 118.143584 150.232097)
		(end 118.004378 150.139082)
		(width 0.127)
		(layer "In3.Cu")
		(net "PCIE_TX0_P")
	)
	(arc
		(start 120.365394 145.355126)
		(mid 120.42119 145.48983)
		(end 120.365394 145.624534)
		(width 0.127)
		(layer "In3.Cu")
		(net "PCIE_TX0_P")
	)
	(arc
		(start 124.220149 141.180349)
		(mid 125.044184 140.629746)
		(end 126.0162 140.4364)
		(width 0.127)
		(layer "In3.Cu")
		(net "PCIE_TX0_P")
	)
	(arc
		(start 172.539099 136.612407)
		(mid 172.580165 136.585161)
		(end 172.62851 136.5756)
		(width 0.127)
		(layer "In3.Cu")
		(net "PCIE_TX0_P")
	)
	(arc
		(start 120.332196 145.052526)
		(mid 120.4669 144.99673)
		(end 120.601604 145.052526)
		(width 0.127)
		(layer "In3.Cu")
		(net "PCIE_TX0_P")
	)
	(arc
		(start 119.793376 145.591336)
		(mid 119.92808 145.53554)
		(end 120.062784 145.591336)
		(width 0.127)
		(layer "In3.Cu")
		(net "PCIE_TX0_P")
	)
	(arc
		(start 119.793376 145.860744)
		(mid 119.73758 145.726042)
		(end 119.793373 145.591339)
		(width 0.127)
		(layer "In3.Cu")
		(net "PCIE_TX0_P")
	)
	(arc
		(start 171.6747 137.52941)
		(mid 171.684256 137.48108)
		(end 171.711484 137.440022)
		(width 0.127)
		(layer "In3.Cu")
		(net "PCIE_TX0_P")
	)
	(arc
		(start 117.613627 148.193678)
		(mid 117.864651 147.63903)
		(end 118.240449 147.160048)
		(width 0.127)
		(layer "In3.Cu")
		(net "PCIE_TX0_P")
	)
	(arc
		(start 117.572712 149.707398)
		(mid 117.516314 149.622993)
		(end 117.49651 149.52343)
		(width 0.127)
		(layer "In3.Cu")
		(net "PCIE_TX0_P")
	)
	(arc
		(start 174.96769 134.08735)
		(mid 174.987025 133.990145)
		(end 175.042088 133.907738)
		(width 0.127)
		(layer "In3.Cu")
		(net "PCIE_TX0_P")
	)
	(arc
		(start 175.2158 133.48836)
		(mid 175.170653 133.71533)
		(end 175.042085 133.907745)
		(width 0.127)
		(layer "In3.Cu")
		(net "PCIE_TX0_P")
	)
	(arc
		(start 175.2158 133.48836)
		(mid 175.260946 133.261394)
		(end 175.389512 133.068982)
		(width 0.127)
		(layer "In3.Cu")
		(net "PCIE_TX0_P")
	)
	(arc
		(start 117.4965 148.9561)
		(mid 117.525953 148.570417)
		(end 117.613627 148.193678)
		(width 0.127)
		(layer "In3.Cu")
		(net "PCIE_TX0_P")
	)
	(arc
		(start 119.826571 146.163356)
		(mid 119.691869 146.21915)
		(end 119.557167 146.163354)
		(width 0.127)
		(layer "In3.Cu")
		(net "PCIE_TX0_P")
	)
	(arc
		(start 120.365391 145.624536)
		(mid 120.230689 145.68033)
		(end 120.095987 145.624534)
		(width 0.127)
		(layer "In3.Cu")
		(net "PCIE_TX0_P")
	)
	(arc
		(start 118.604874 150.141704)
		(mid 118.468571 150.232779)
		(end 118.30779 150.26476)
		(width 0.127)
		(layer "In3.Cu")
		(net "PCIE_TX0_P")
	)
	(arc
		(start 170.566203 140.085833)
		(mid 170.177898 140.34529)
		(end 169.71986 140.4364)
		(width 0.127)
		(layer "In3.Cu")
		(net "PCIE_TX0_P")
	)
	(segment
		(start 173.83583 136.03942)
		(end 173.83583 135.50523)
		(width 0.127)
		(layer "F.Cu")
		(net "PCIE_CLK_P")
	)
	(segment
		(start 173.3261 137.6286)
		(end 173.3261 137.27002)
		(width 0.127)
		(layer "F.Cu")
		(net "PCIE_CLK_P")
	)
	(via
		(at 115.5761 150.2786)
		(size 0.4064)
		(drill 0.2032)
		(layers "F.Cu" "B.Cu")
		(tenting
			(front yes)
			(back yes)
		)
		(net "PCIE_CLK_P")
	)
	(via
		(at 173.3261 137.6286)
		(size 0.4064)
		(drill 0.2032)
		(layers "F.Cu" "B.Cu")
		(tenting
			(front yes)
			(back yes)
		)
		(net "PCIE_CLK_P")
	)
	(arc
		(start 173.3261 137.27002)
		(mid 173.352089 137.139364)
		(end 173.4261 137.0286)
		(width 0.127)
		(layer "F.Cu")
		(net "PCIE_CLK_P")
	)
	(arc
		(start 173.83584 136.03942)
		(mid 173.729354 136.574764)
		(end 173.426106 137.028606)
		(width 0.127)
		(layer "F.Cu")
		(net "PCIE_CLK_P")
	)
	(segment
		(start 115.5761 151.3248)
		(end 115.5761 150.2786)
		(width 0.127)
		(layer "B.Cu")
		(net "PCIE_CLK_P")
	)
	(arc
		(start 115.5761 151.3248)
		(mid 115.572461 151.343092)
		(end 115.5621 151.3586)
		(width 0.127)
		(layer "B.Cu")
		(net "PCIE_CLK_P")
	)
	(segment
		(start 115.9364 150.48033)
		(end 115.9364 150.42247)
		(width 0.127)
		(layer "In3.Cu")
		(net "PCIE_CLK_P")
	)
	(segment
		(start 122.3658 148.71758)
		(end 122.3658 146.16004)
		(width 0.127)
		(layer "In3.Cu")
		(net "PCIE_CLK_P")
	)
	(segment
		(start 118.09567 151.858)
		(end 120.27732 151.858)
		(width 0.127)
		(layer "In3.Cu")
		(net "PCIE_CLK_P")
	)
	(segment
		(start 173.11581 138.14081)
		(end 173.11581 138.14011)
		(width 0.127)
		(layer "In3.Cu")
		(net "PCIE_CLK_P")
	)
	(segment
		(start 122.7797 145.1608)
		(end 126.07435 141.86615)
		(width 0.127)
		(layer "In3.Cu")
		(net "PCIE_CLK_P")
	)
	(segment
		(start 173.3261 137.6324)
		(end 173.3261 137.6324)
		(width 0.127)
		(layer "In3.Cu")
		(net "PCIE_CLK_P")
	)
	(segment
		(start 173.3261 137.6324)
		(end 173.3261 137.6324)
		(width 0.127)
		(layer "In3.Cu")
		(net "PCIE_CLK_P")
	)
	(segment
		(start 120.4728 151.77703)
		(end 121.541 150.70883)
		(width 0.127)
		(layer "In3.Cu")
		(net "PCIE_CLK_P")
	)
	(segment
		(start 115.61682 150.29547)
		(end 115.8094 150.29547)
		(width 0.127)
		(layer "In3.Cu")
		(net "PCIE_CLK_P")
	)
	(segment
		(start 127.8704 141.1222)
		(end 169.1882 141.1222)
		(width 0.127)
		(layer "In3.Cu")
		(net "PCIE_CLK_P")
	)
	(segment
		(start 173.3261 137.6324)
		(end 173.3261 137.6286)
		(width 0.127)
		(layer "In3.Cu")
		(net "PCIE_CLK_P")
	)
	(segment
		(start 116.01451 150.66891)
		(end 116.5728 151.2272)
		(width 0.127)
		(layer "In3.Cu")
		(net "PCIE_CLK_P")
	)
	(segment
		(start 171.17946 140.29739)
		(end 172.96007 138.51678)
		(width 0.127)
		(layer "In3.Cu")
		(net "PCIE_CLK_P")
	)
	(arc
		(start 173.1158 138.140816)
		(mid 173.075325 138.344289)
		(end 172.960066 138.516786)
		(width 0.127)
		(layer "In3.Cu")
		(net "PCIE_CLK_P")
	)
	(arc
		(start 115.61682 150.29547)
		(mid 115.594781 150.291086)
		(end 115.576098 150.278602)
		(width 0.127)
		(layer "In3.Cu")
		(net "PCIE_CLK_P")
	)
	(arc
		(start 118.09567 151.858)
		(mid 117.271496 151.694062)
		(end 116.572795 151.227205)
		(width 0.127)
		(layer "In3.Cu")
		(net "PCIE_CLK_P")
	)
	(arc
		(start 116.014512 150.668908)
		(mid 115.956701 150.582388)
		(end 115.9364 150.48033)
		(width 0.127)
		(layer "In3.Cu")
		(net "PCIE_CLK_P")
	)
	(arc
		(start 122.3658 146.160037)
		(mid 122.47337 145.61925)
		(end 122.779702 145.160792)
		(width 0.127)
		(layer "In3.Cu")
		(net "PCIE_CLK_P")
	)
	(arc
		(start 120.4728 151.77703)
		(mid 120.383113 151.836957)
		(end 120.27732 151.858)
		(width 0.127)
		(layer "In3.Cu")
		(net "PCIE_CLK_P")
	)
	(arc
		(start 171.179462 140.297392)
		(mid 170.265863 140.907839)
		(end 169.1882 141.1222)
		(width 0.127)
		(layer "In3.Cu")
		(net "PCIE_CLK_P")
	)
	(arc
		(start 115.8094 150.29547)
		(mid 115.858001 150.305137)
		(end 115.899203 150.332667)
		(width 0.127)
		(layer "In3.Cu")
		(net "PCIE_CLK_P")
	)
	(arc
		(start 122.36581 148.71758)
		(mid 122.15145 149.79524)
		(end 121.541005 150.708835)
		(width 0.127)
		(layer "In3.Cu")
		(net "PCIE_CLK_P")
	)
	(arc
		(start 115.899203 150.332667)
		(mid 115.926733 150.373869)
		(end 115.936401 150.42247)
		(width 0.127)
		(layer "In3.Cu")
		(net "PCIE_CLK_P")
	)
	(arc
		(start 126.074349 141.866149)
		(mid 126.898384 141.315546)
		(end 127.8704 141.1222)
		(width 0.127)
		(layer "In3.Cu")
		(net "PCIE_CLK_P")
	)
	(arc
		(start 173.1158 138.14011)
		(mid 173.170455 137.865341)
		(end 173.326098 137.632403)
		(width 0.127)
		(layer "In3.Cu")
		(net "PCIE_CLK_P")
	)
	(segment
		(start 172.83823 137.11646)
		(end 173.1261 136.8286)
		(width 0.127)
		(layer "F.Cu")
		(net "PCIE_CLK_N")
	)
	(segment
		(start 173.33596 136.32195)
		(end 173.33596 135.50523)
		(width 0.127)
		(layer "F.Cu")
		(net "PCIE_CLK_N")
	)
	(via
		(at 116.5761 150.2786)
		(size 0.4064)
		(drill 0.2032)
		(layers "F.Cu" "B.Cu")
		(tenting
			(front yes)
			(back yes)
		)
		(net "PCIE_CLK_N")
	)
	(via
		(at 172.6261 137.6286)
		(size 0.4064)
		(drill 0.2032)
		(layers "F.Cu" "B.Cu")
		(tenting
			(front yes)
			(back yes)
		)
		(net "PCIE_CLK_N")
	)
	(arc
		(start 173.33597 136.32195)
		(mid 173.281428 136.59615)
		(end 173.126106 136.828606)
		(width 0.127)
		(layer "F.Cu")
		(net "PCIE_CLK_N")
	)
	(arc
		(start 172.6261 137.6286)
		(mid 172.681232 137.351434)
		(end 172.838234 137.116464)
		(width 0.127)
		(layer "F.Cu")
		(net "PCIE_CLK_N")
	)
	(segment
		(start 116.5761 151.3566)
		(end 116.5761 150.2786)
		(width 0.127)
		(layer "B.Cu")
		(net "PCIE_CLK_N")
	)
	(segment
		(start 116.5761 151.3566)
		(end 116.5781 151.3586)
		(width 0.127)
		(layer "B.Cu")
		(net "PCIE_CLK_N")
	)
	(segment
		(start 172.6261 137.63239)
		(end 172.6261 137.6286)
		(width 0.127)
		(layer "In3.Cu")
		(net "PCIE_CLK_N")
	)
	(segment
		(start 118.80454 151.5786)
		(end 118.80455 151.5786)
		(width 0.127)
		(layer "In3.Cu")
		(net "PCIE_CLK_N")
	)
	(segment
		(start 118.80454 151.5786)
		(end 120.2761 151.5786)
		(width 0.127)
		(layer "In3.Cu")
		(net "PCIE_CLK_N")
	)
	(segment
		(start 122.58129 144.96408)
		(end 125.87776 141.66761)
		(width 0.127)
		(layer "In3.Cu")
		(net "PCIE_CLK_N")
	)
	(segment
		(start 120.2761 151.5786)
		(end 121.34245 150.51224)
		(width 0.127)
		(layer "In3.Cu")
		(net "PCIE_CLK_N")
	)
	(segment
		(start 118.36003 151.5786)
		(end 118.80454 151.5786)
		(width 0.127)
		(layer "In3.Cu")
		(net "PCIE_CLK_N")
	)
	(segment
		(start 116.253 150.51227)
		(end 116.76756 151.02684)
		(width 0.127)
		(layer "In3.Cu")
		(net "PCIE_CLK_N")
	)
	(segment
		(start 170.98287 140.09885)
		(end 172.76201 138.31971)
		(width 0.127)
		(layer "In3.Cu")
		(net "PCIE_CLK_N")
	)
	(segment
		(start 117.78853 151.24368)
		(end 117.78853 151.12243)
		(width 0.127)
		(layer "In3.Cu")
		(net "PCIE_CLK_N")
	)
	(segment
		(start 127.86902 140.8428)
		(end 169.18682 140.8428)
		(width 0.127)
		(layer "In3.Cu")
		(net "PCIE_CLK_N")
	)
	(segment
		(start 117.5477 151.42741)
		(end 117.5477 151.42741)
		(width 0.127)
		(layer "In3.Cu")
		(net "PCIE_CLK_N")
	)
	(segment
		(start 118.16953 151.3881)
		(end 118.16953 151.12243)
		(width 0.127)
		(layer "In3.Cu")
		(net "PCIE_CLK_N")
	)
	(segment
		(start 116.34281 150.29547)
		(end 116.53538 150.29547)
		(width 0.127)
		(layer "In3.Cu")
		(net "PCIE_CLK_N")
	)
	(segment
		(start 117.1396 151.31562)
		(end 117.5477 151.42741)
		(width 0.127)
		(layer "In3.Cu")
		(net "PCIE_CLK_N")
	)
	(segment
		(start 122.0864 148.71619)
		(end 122.0864 146.15885)
		(width 0.127)
		(layer "In3.Cu")
		(net "PCIE_CLK_N")
	)
	(segment
		(start 117.0761 151.27629)
		(end 117.07611 151.27629)
		(width 0.127)
		(layer "In3.Cu")
		(net "PCIE_CLK_N")
	)
	(segment
		(start 116.2158 150.42247)
		(end 116.2158 150.42247)
		(width 0.127)
		(layer "In3.Cu")
		(net "PCIE_CLK_N")
	)
	(arc
		(start 116.252987 150.512273)
		(mid 116.225457 150.471071)
		(end 116.215789 150.42247)
		(width 0.127)
		(layer "In3.Cu")
		(net "PCIE_CLK_N")
	)
	(arc
		(start 117.139607 151.315625)
		(mid 117.107661 151.296273)
		(end 117.076105 151.276292)
		(width 0.127)
		(layer "In3.Cu")
		(net "PCIE_CLK_N")
	)
	(arc
		(start 125.877765 141.667605)
		(mid 126.791361 141.05716)
		(end 127.86902 140.8428)
		(width 0.127)
		(layer "In3.Cu")
		(net "PCIE_CLK_N")
	)
	(arc
		(start 117.78853 151.24368)
		(mid 117.713577 151.395137)
		(end 117.547698 151.427411)
		(width 0.127)
		(layer "In3.Cu")
		(net "PCIE_CLK_N")
	)
	(arc
		(start 117.076098 151.276288)
		(mid 116.915244 151.159709)
		(end 116.767561 151.026839)
		(width 0.127)
		(layer "In3.Cu")
		(net "PCIE_CLK_N")
	)
	(arc
		(start 170.982871 140.098851)
		(mid 170.158836 140.649454)
		(end 169.18682 140.8428)
		(width 0.127)
		(layer "In3.Cu")
		(net "PCIE_CLK_N")
	)
	(arc
		(start 122.0864 148.71619)
		(mid 121.893054 149.688206)
		(end 121.342451 150.512241)
		(width 0.127)
		(layer "In3.Cu")
		(net "PCIE_CLK_N")
	)
	(arc
		(start 172.83641 138.14011)
		(mid 172.817075 138.237312)
		(end 172.762015 138.319715)
		(width 0.127)
		(layer "In3.Cu")
		(net "PCIE_CLK_N")
	)
	(arc
		(start 116.576102 150.278602)
		(mid 116.557419 150.291086)
		(end 116.53538 150.29547)
		(width 0.127)
		(layer "In3.Cu")
		(net "PCIE_CLK_N")
	)
	(arc
		(start 117.78853 151.12243)
		(mid 117.97903 150.93193)
		(end 118.16953 151.12243)
		(width 0.127)
		(layer "In3.Cu")
		(net "PCIE_CLK_N")
	)
	(arc
		(start 172.626107 137.632393)
		(mid 172.781754 137.865336)
		(end 172.83641 138.14011)
		(width 0.127)
		(layer "In3.Cu")
		(net "PCIE_CLK_N")
	)
	(arc
		(start 116.253 150.33267)
		(mid 116.294205 150.305138)
		(end 116.34281 150.295469)
		(width 0.127)
		(layer "In3.Cu")
		(net "PCIE_CLK_N")
	)
	(arc
		(start 116.2158 150.42247)
		(mid 116.225467 150.373873)
		(end 116.252995 150.332675)
		(width 0.127)
		(layer "In3.Cu")
		(net "PCIE_CLK_N")
	)
	(arc
		(start 118.36003 151.5786)
		(mid 118.225326 151.522804)
		(end 118.16953 151.3881)
		(width 0.127)
		(layer "In3.Cu")
		(net "PCIE_CLK_N")
	)
	(arc
		(start 122.0864 146.15885)
		(mid 122.215018 145.512241)
		(end 122.581293 144.964073)
		(width 0.127)
		(layer "In3.Cu")
		(net "PCIE_CLK_N")
	)
	(segment
		(start 183.3261 82.0162)
		(end 183.4261 82.0162)
		(width 0.2032)
		(layer "F.Cu")
		(net "PCIE_PERST")
	)
	(segment
		(start 87.4261 138.6162)
		(end 92.6261 133.4162)
		(width 0.2032)
		(layer "F.Cu")
		(net "PCIE_PERST")
	)
	(segment
		(start 154.06614 119.3742)
		(end 154.61801 119.3742)
		(width 0.2032)
		(layer "F.Cu")
		(net "PCIE_PERST")
	)
	(segment
		(start 92.6261 133.4162)
		(end 92.6261 122.0786)
		(width 0.2032)
		(layer "F.Cu")
		(net "PCIE_PERST")
	)
	(segment
		(start 107.2261 151.7162)
		(end 109.9261 151.7162)
		(width 0.2032)
		(layer "F.Cu")
		(net "PCIE_PERST")
	)
	(segment
		(start 151.75808 119.31646)
		(end 154.0084 119.31646)
		(width 0.2032)
		(layer "F.Cu")
		(net "PCIE_PERST")
	)
	(segment
		(start 109.9261 151.7162)
		(end 110.6637 150.9786)
		(width 0.2032)
		(layer "F.Cu")
		(net "PCIE_PERST")
	)
	(segment
		(start 92.6261 122.0786)
		(end 93.5637 122.0786)
		(width 0.2032)
		(layer "F.Cu")
		(net "PCIE_PERST")
	)
	(segment
		(start 103.9261 144.8162)
		(end 105.0261 145.9162)
		(width 0.2032)
		(layer "F.Cu")
		(net "PCIE_PERST")
	)
	(segment
		(start 89.3261 143.9162)
		(end 93.5261 143.9162)
		(width 0.2032)
		(layer "F.Cu")
		(net "PCIE_PERST")
	)
	(segment
		(start 93.5261 143.9162)
		(end 94.4261 144.8162)
		(width 0.2032)
		(layer "F.Cu")
		(net "PCIE_PERST")
	)
	(segment
		(start 87.4261 142.0162)
		(end 89.3261 143.9162)
		(width 0.2032)
		(layer "F.Cu")
		(net "PCIE_PERST")
	)
	(segment
		(start 151.75053 119.30892)
		(end 151.75808 119.31646)
		(width 0.2032)
		(layer "F.Cu")
		(net "PCIE_PERST")
	)
	(segment
		(start 94.4261 144.8162)
		(end 103.9261 144.8162)
		(width 0.2032)
		(layer "F.Cu")
		(net "PCIE_PERST")
	)
	(segment
		(start 154.0084 119.31646)
		(end 154.06614 119.3742)
		(width 0.2032)
		(layer "F.Cu")
		(net "PCIE_PERST")
	)
	(segment
		(start 87.4261 142.0162)
		(end 87.4261 138.6162)
		(width 0.2032)
		(layer "F.Cu")
		(net "PCIE_PERST")
	)
	(segment
		(start 105.0261 149.5162)
		(end 105.0261 145.9162)
		(width 0.2032)
		(layer "F.Cu")
		(net "PCIE_PERST")
	)
	(segment
		(start 183.4261 82.0162)
		(end 184.2261 82.8162)
		(width 0.2032)
		(layer "F.Cu")
		(net "PCIE_PERST")
	)
	(segment
		(start 105.0261 149.5162)
		(end 107.2261 151.7162)
		(width 0.2032)
		(layer "F.Cu")
		(net "PCIE_PERST")
	)
	(segment
		(start 92.6261 122.0786)
		(end 92.6261 122.0786)
		(width 0.2032)
		(layer "F.Cu")
		(net "PCIE_PERST")
	)
	(segment
		(start 110.6637 150.9786)
		(end 111.4761 150.9786)
		(width 0.2032)
		(layer "F.Cu")
		(net "PCIE_PERST")
	)
	(segment
		(start 93.5637 122.0786)
		(end 93.6261 122.0162)
		(width 0.2032)
		(layer "F.Cu")
		(net "PCIE_PERST")
	)
	(via
		(at 183.3261 82.0162)
		(size 0.4064)
		(drill 0.2032)
		(layers "F.Cu" "B.Cu")
		(net "PCIE_PERST")
	)
	(via
		(at 111.4761 150.9786)
		(size 0.4064)
		(drill 0.2032)
		(layers "F.Cu" "B.Cu")
		(tenting
			(front yes)
			(back yes)
		)
		(net "PCIE_PERST")
	)
	(via
		(at 93.6261 122.0162)
		(size 0.4064)
		(drill 0.2032)
		(layers "F.Cu" "B.Cu")
		(tenting
			(front yes)
			(back yes)
		)
		(net "PCIE_PERST")
	)
	(via
		(at 154.61801 119.3742)
		(size 0.4064)
		(drill 0.2032)
		(layers "F.Cu" "B.Cu")
		(tenting
			(front yes)
			(back yes)
		)
		(net "PCIE_PERST")
	)
	(segment
		(start 111.4761 157.02859)
		(end 111.52611 157.0786)
		(width 0.2032)
		(layer "B.Cu")
		(net "PCIE_PERST")
	)
	(segment
		(start 111.4761 157.02859)
		(end 111.4761 150.9786)
		(width 0.2032)
		(layer "B.Cu")
		(net "PCIE_PERST")
	)
	(segment
		(start 156.0681 119.3742)
		(end 167.0261 108.4162)
		(width 0.2032)
		(layer "In2.Cu")
		(net "PCIE_PERST")
	)
	(segment
		(start 185.5261 80.5162)
		(end 193.9658 80.5162)
		(width 0.2032)
		(layer "In2.Cu")
		(net "PCIE_PERST")
	)
	(segment
		(start 193.9658 80.5162)
		(end 193.99474 80.54513)
		(width 0.2032)
		(layer "In2.Cu")
		(net "PCIE_PERST")
	)
	(segment
		(start 177.4261 108.4162)
		(end 193.99474 91.84756)
		(width 0.2032)
		(layer "In2.Cu")
		(net "PCIE_PERST")
	)
	(segment
		(start 167.0261 108.4162)
		(end 177.4261 108.4162)
		(width 0.2032)
		(layer "In2.Cu")
		(net "PCIE_PERST")
	)
	(segment
		(start 184.0261 82.0162)
		(end 185.5261 80.5162)
		(width 0.2032)
		(layer "In2.Cu")
		(net "PCIE_PERST")
	)
	(segment
		(start 183.3261 82.0162)
		(end 184.0261 82.0162)
		(width 0.2032)
		(layer "In2.Cu")
		(net "PCIE_PERST")
	)
	(segment
		(start 154.61801 119.3742)
		(end 156.0681 119.3742)
		(width 0.2032)
		(layer "In2.Cu")
		(net "PCIE_PERST")
	)
	(segment
		(start 193.99474 91.84756)
		(end 193.99474 80.54513)
		(width 0.2032)
		(layer "In2.Cu")
		(net "PCIE_PERST")
	)
	(segment
		(start 154.56432 119.3742)
		(end 154.61801 119.3742)
		(width 0.2032)
		(layer "In3.Cu")
		(net "PCIE_PERST")
	)
	(segment
		(start 93.6261 122.0162)
		(end 94.5557 121.0866)
		(width 0.2032)
		(layer "In3.Cu")
		(net "PCIE_PERST")
	)
	(segment
		(start 152.85192 121.0866)
		(end 154.56432 119.3742)
		(width 0.2032)
		(layer "In3.Cu")
		(net "PCIE_PERST")
	)
	(segment
		(start 94.5557 121.0866)
		(end 152.85192 121.0866)
		(width 0.2032)
		(layer "In3.Cu")
		(net "PCIE_PERST")
	)
	(segment
		(start 130.52607 157.0786)
		(end 130.52607 153.59923)
		(width 0.127)
		(layer "F.Cu")
		(net "PCIE_RX3_N")
	)
	(segment
		(start 176.33596 132.91874)
		(end 176.33596 131.45545)
		(width 0.127)
		(layer "F.Cu")
		(net "PCIE_RX3_N")
	)
	(segment
		(start 130.3449 157.55643)
		(end 130.54607 157.7576)
		(width 0.127)
		(layer "F.Cu")
		(net "PCIE_RX3_N")
	)
	(via
		(at 130.4761 153.4786)
		(size 0.4064)
		(drill 0.2032)
		(layers "F.Cu" "B.Cu")
		(tenting
			(front yes)
			(back yes)
		)
		(net "PCIE_RX3_N")
	)
	(via
		(at 176.2261 133.0286)
		(size 0.4064)
		(drill 0.2032)
		(layers "F.Cu" "B.Cu")
		(tenting
			(front yes)
			(back yes)
		)
		(net "PCIE_RX3_N")
	)
	(arc
		(start 176.33596 132.91874)
		(mid 176.303783 132.996423)
		(end 176.2261 133.0286)
		(width 0.127)
		(layer "F.Cu")
		(net "PCIE_RX3_N")
	)
	(arc
		(start 130.52607 157.0786)
		(mid 130.338083 156.797257)
		(end 130.27207 156.46539)
		(width 0.2032)
		(layer "F.Cu")
		(net "PCIE_RX3_N")
	)
	(arc
		(start 130.476102 153.478598)
		(mid 130.513083 153.533944)
		(end 130.526069 153.59923)
		(width 0.127)
		(layer "F.Cu")
		(net "PCIE_RX3_N")
	)
	(segment
		(start 129.1761 153.56468)
		(end 129.1761 151.62556)
		(width 0.127)
		(layer "In2.Cu")
		(net "PCIE_RX3_N")
	)
	(segment
		(start 176.4364 133.92998)
		(end 176.4364 133.5401)
		(width 0.127)
		(layer "In2.Cu")
		(net "PCIE_RX3_N")
	)
	(segment
		(start 176.79282 134.79045)
		(end 177.28526 135.28289)
		(width 0.127)
		(layer "In2.Cu")
		(net "PCIE_RX3_N")
	)
	(segment
		(start 179.8261 136.108)
		(end 179.8261 136.108)
		(width 0.127)
		(layer "In2.Cu")
		(net "PCIE_RX3_N")
	)
	(segment
		(start 130.25979 153.4786)
		(end 130.4761 153.4786)
		(width 0.127)
		(layer "In2.Cu")
		(net "PCIE_RX3_N")
	)
	(segment
		(start 180.9965 139.16697)
		(end 180.9965 137.63824)
		(width 0.127)
		(layer "In2.Cu")
		(net "PCIE_RX3_N")
	)
	(segment
		(start 179.96808 141.24749)
		(end 180.25255 140.96302)
		(width 0.127)
		(layer "In2.Cu")
		(net "PCIE_RX3_N")
	)
	(segment
		(start 129.77262 150.45646)
		(end 129.79298 150.4244)
		(width 0.127)
		(layer "In2.Cu")
		(net "PCIE_RX3_N")
	)
	(segment
		(start 131.08311 143.86862)
		(end 131.08508 143.86663)
		(width 0.127)
		(layer "In2.Cu")
		(net "PCIE_RX3_N")
	)
	(segment
		(start 131.374 143.74518)
		(end 173.93958 143.74518)
		(width 0.127)
		(layer "In2.Cu")
		(net "PCIE_RX3_N")
	)
	(segment
		(start 130.13487 153.57867)
		(end 130.13488 153.57867)
		(width 0.127)
		(layer "In2.Cu")
		(net "PCIE_RX3_N")
	)
	(segment
		(start 130.2981 149.86668)
		(end 130.2981 145.81968)
		(width 0.127)
		(layer "In2.Cu")
		(net "PCIE_RX3_N")
	)
	(segment
		(start 129.79298 150.4244)
		(end 130.2613 149.95609)
		(width 0.127)
		(layer "In2.Cu")
		(net "PCIE_RX3_N")
	)
	(segment
		(start 179.27725 136.108)
		(end 179.8261 136.108)
		(width 0.127)
		(layer "In2.Cu")
		(net "PCIE_RX3_N")
	)
	(segment
		(start 176.2261 133.0324)
		(end 176.2261 133.0286)
		(width 0.127)
		(layer "In2.Cu")
		(net "PCIE_RX3_N")
	)
	(arc
		(start 129.709337 150.51531)
		(mid 129.725641 150.50247)
		(end 129.742131 150.489869)
		(width 0.127)
		(layer "In2.Cu")
		(net "PCIE_RX3_N")
	)
	(arc
		(start 129.180055 153.596127)
		(mid 129.177093 153.580527)
		(end 129.1761 153.56468)
		(width 0.127)
		(layer "In2.Cu")
		(net "PCIE_RX3_N")
	)
	(arc
		(start 129.176101 151.62556)
		(mid 129.316066 151.009606)
		(end 129.709337 150.515311)
		(width 0.127)
		(layer "In2.Cu")
		(net "PCIE_RX3_N")
	)
	(arc
		(start 180.9965 139.16697)
		(mid 180.803153 140.138989)
		(end 180.252547 140.963026)
		(width 0.127)
		(layer "In2.Cu")
		(net "PCIE_RX3_N")
	)
	(arc
		(start 176.2261 133.03239)
		(mid 176.381745 133.265329)
		(end 176.4364 133.5401)
		(width 0.127)
		(layer "In2.Cu")
		(net "PCIE_RX3_N")
	)
	(arc
		(start 179.8261 136.108)
		(mid 180.176619 136.177723)
		(end 180.473774 136.376276)
		(width 0.127)
		(layer "In2.Cu")
		(net "PCIE_RX3_N")
	)
	(arc
		(start 130.134867 153.578677)
		(mid 129.664368 153.965198)
		(end 129.180055 153.596132)
		(width 0.127)
		(layer "In2.Cu")
		(net "PCIE_RX3_N")
	)
	(arc
		(start 176.792819 134.790451)
		(mid 176.52903 134.395664)
		(end 176.4364 133.92998)
		(width 0.127)
		(layer "In2.Cu")
		(net "PCIE_RX3_N")
	)
	(arc
		(start 131.085079 143.866635)
		(mid 131.21736 143.776936)
		(end 131.373999 143.745181)
		(width 0.127)
		(layer "In2.Cu")
		(net "PCIE_RX3_N")
	)
	(arc
		(start 129.772622 150.45645)
		(mid 129.758875 150.474524)
		(end 129.742129 150.48986)
		(width 0.127)
		(layer "In2.Cu")
		(net "PCIE_RX3_N")
	)
	(arc
		(start 179.27725 136.108)
		(mid 178.199193 135.893561)
		(end 177.285259 135.282891)
		(width 0.127)
		(layer "In2.Cu")
		(net "PCIE_RX3_N")
	)
	(arc
		(start 130.2981 149.86668)
		(mid 130.288538 149.915025)
		(end 130.261293 149.956091)
		(width 0.127)
		(layer "In2.Cu")
		(net "PCIE_RX3_N")
	)
	(arc
		(start 180.473776 136.376274)
		(mid 180.860648 136.955269)
		(end 180.996499 137.63824)
		(width 0.127)
		(layer "In2.Cu")
		(net "PCIE_RX3_N")
	)
	(arc
		(start 179.968083 141.247493)
		(mid 177.202186 143.095778)
		(end 173.939578 143.745189)
		(width 0.127)
		(layer "In2.Cu")
		(net "PCIE_RX3_N")
	)
	(arc
		(start 130.2981 145.81968)
		(mid 130.501256 144.769276)
		(end 131.081422 143.870372)
		(width 0.127)
		(layer "In2.Cu")
		(net "PCIE_RX3_N")
	)
	(arc
		(start 130.134877 153.578674)
		(mid 130.179586 153.506483)
		(end 130.259793 153.478602)
		(width 0.127)
		(layer "In2.Cu")
		(net "PCIE_RX3_N")
	)
	(segment
		(start 176.83583 132.93833)
		(end 176.83583 131.45545)
		(width 0.127)
		(layer "F.Cu")
		(net "PCIE_RX3_P")
	)
	(segment
		(start 129.52607 157.0786)
		(end 129.52607 153.8408)
		(width 0.127)
		(layer "F.Cu")
		(net "PCIE_RX3_P")
	)
	(segment
		(start 129.54607 157.7576)
		(end 129.7353 157.56837)
		(width 0.127)
		(layer "F.Cu")
		(net "PCIE_RX3_P")
	)
	(via
		(at 129.67566 153.47904)
		(size 0.4064)
		(drill 0.2032)
		(layers "F.Cu" "B.Cu")
		(tenting
			(front yes)
			(back yes)
		)
		(net "PCIE_RX3_P")
	)
	(via
		(at 176.9261 133.0286)
		(size 0.4064)
		(drill 0.2032)
		(layers "F.Cu" "B.Cu")
		(tenting
			(front yes)
			(back yes)
		)
		(net "PCIE_RX3_P")
	)
	(arc
		(start 129.52607 153.8408)
		(mid 129.564943 153.645064)
		(end 129.675662 153.479036)
		(width 0.127)
		(layer "F.Cu")
		(net "PCIE_RX3_P")
	)
	(arc
		(start 176.9261 133.0286)
		(mid 176.862269 133.002161)
		(end 176.83583 132.93833)
		(width 0.127)
		(layer "F.Cu")
		(net "PCIE_RX3_P")
	)
	(segment
		(start 131.37405 144.02458)
		(end 173.93816 144.02458)
		(width 0.127)
		(layer "In2.Cu")
		(net "PCIE_RX3_P")
	)
	(segment
		(start 176.99136 134.59386)
		(end 177.48215 135.08465)
		(width 0.127)
		(layer "In2.Cu")
		(net "PCIE_RX3_P")
	)
	(segment
		(start 130.08494 150.53873)
		(end 130.08495 150.53873)
		(width 0.127)
		(layer "In2.Cu")
		(net "PCIE_RX3_P")
	)
	(segment
		(start 180.16485 141.44586)
		(end 180.45061 141.1601)
		(width 0.127)
		(layer "In2.Cu")
		(net "PCIE_RX3_P")
	)
	(segment
		(start 173.93849 144.02458)
		(end 173.94076 144.02458)
		(width 0.127)
		(layer "In2.Cu")
		(net "PCIE_RX3_P")
	)
	(segment
		(start 129.4761 153.16337)
		(end 129.4761 153.22687)
		(width 0.127)
		(layer "In2.Cu")
		(net "PCIE_RX3_P")
	)
	(segment
		(start 176.9261 133.0324)
		(end 176.9261 133.0286)
		(width 0.127)
		(layer "In2.Cu")
		(net "PCIE_RX3_P")
	)
	(segment
		(start 181.2759 139.16766)
		(end 181.2759 137.634)
		(width 0.127)
		(layer "In2.Cu")
		(net "PCIE_RX3_P")
	)
	(segment
		(start 129.76776 150.9662)
		(end 129.76776 150.89735)
		(width 0.127)
		(layer "In2.Cu")
		(net "PCIE_RX3_P")
	)
	(segment
		(start 179.2782 135.8286)
		(end 179.82732 135.8286)
		(width 0.127)
		(layer "In2.Cu")
		(net "PCIE_RX3_P")
	)
	(segment
		(start 129.6206 152.21086)
		(end 129.94758 152.21086)
		(width 0.127)
		(layer "In2.Cu")
		(net "PCIE_RX3_P")
	)
	(segment
		(start 129.80495 150.80755)
		(end 130.45939 150.15312)
		(width 0.127)
		(layer "In2.Cu")
		(net "PCIE_RX3_P")
	)
	(segment
		(start 176.7158 133.9286)
		(end 176.7158 133.5401)
		(width 0.127)
		(layer "In2.Cu")
		(net "PCIE_RX3_P")
	)
	(segment
		(start 129.6206 151.82986)
		(end 129.95828 151.82986)
		(width 0.127)
		(layer "In2.Cu")
		(net "PCIE_RX3_P")
	)
	(segment
		(start 130.09259 150.52009)
		(end 130.09279 150.51973)
		(width 0.127)
		(layer "In2.Cu")
		(net "PCIE_RX3_P")
	)
	(segment
		(start 129.6666 152.59186)
		(end 129.94758 152.59186)
		(width 0.127)
		(layer "In2.Cu")
		(net "PCIE_RX3_P")
	)
	(segment
		(start 129.4761 153.16337)
		(end 129.4761 152.78236)
		(width 0.127)
		(layer "In2.Cu")
		(net "PCIE_RX3_P")
	)
	(segment
		(start 180.67048 136.17785)
		(end 180.67435 136.18172)
		(width 0.127)
		(layer "In2.Cu")
		(net "PCIE_RX3_P")
	)
	(segment
		(start 130.5775 149.86668)
		(end 130.5775 145.82063)
		(width 0.127)
		(layer "In2.Cu")
		(net "PCIE_RX3_P")
	)
	(segment
		(start 129.76776 151.25836)
		(end 129.76776 150.9662)
		(width 0.127)
		(layer "In2.Cu")
		(net "PCIE_RX3_P")
	)
	(segment
		(start 131.28425 144.06257)
		(end 131.28426 144.06257)
		(width 0.127)
		(layer "In2.Cu")
		(net "PCIE_RX3_P")
	)
	(segment
		(start 129.5133 153.31667)
		(end 129.67566 153.47904)
		(width 0.127)
		(layer "In2.Cu")
		(net "PCIE_RX3_P")
	)
	(segment
		(start 129.95826 151.44886)
		(end 129.95828 151.44886)
		(width 0.127)
		(layer "In2.Cu")
		(net "PCIE_RX3_P")
	)
	(arc
		(start 173.93816 144.02458)
		(mid 173.938325 144.02458)
		(end 173.93849 144.02458)
		(width 0.127)
		(layer "In2.Cu")
		(net "PCIE_RX3_P")
	)
	(arc
		(start 129.6206 152.21086)
		(mid 129.4301 152.02036)
		(end 129.6206 151.82986)
		(width 0.127)
		(layer "In2.Cu")
		(net "PCIE_RX3_P")
	)
	(arc
		(start 129.95826 151.44886)
		(mid 129.823556 151.393064)
		(end 129.76776 151.25836)
		(width 0.127)
		(layer "In2.Cu")
		(net "PCIE_RX3_P")
	)
	(arc
		(start 129.95828 151.44886)
		(mid 130.14878 151.63936)
		(end 129.95828 151.82986)
		(width 0.127)
		(layer "In2.Cu")
		(net "PCIE_RX3_P")
	)
	(arc
		(start 129.94758 152.21086)
		(mid 130.13808 152.40136)
		(end 129.94758 152.59186)
		(width 0.127)
		(layer "In2.Cu")
		(net "PCIE_RX3_P")
	)
	(arc
		(start 130.084941 150.538732)
		(mid 130.088397 150.52926)
		(end 130.092594 150.520093)
		(width 0.127)
		(layer "In2.Cu")
		(net "PCIE_RX3_P")
	)
	(arc
		(start 131.190133 144.166285)
		(mid 131.236476 144.113776)
		(end 131.284249 144.062565)
		(width 0.127)
		(layer "In2.Cu")
		(net "PCIE_RX3_P")
	)
	(arc
		(start 129.76776 150.89735)
		(mid 129.777427 150.84875)
		(end 129.804956 150.807549)
		(width 0.127)
		(layer "In2.Cu")
		(net "PCIE_RX3_P")
	)
	(arc
		(start 176.99136 134.59386)
		(mid 176.787416 134.288636)
		(end 176.7158 133.9286)
		(width 0.127)
		(layer "In2.Cu")
		(net "PCIE_RX3_P")
	)
	(arc
		(start 129.513297 153.316673)
		(mid 129.485768 153.275473)
		(end 129.476099 153.226875)
		(width 0.127)
		(layer "In2.Cu")
		(net "PCIE_RX3_P")
	)
	(arc
		(start 179.2782 135.8286)
		(mid 178.306184 135.635254)
		(end 177.482149 135.084651)
		(width 0.127)
		(layer "In2.Cu")
		(net "PCIE_RX3_P")
	)
	(arc
		(start 176.7158 133.5401)
		(mid 176.770455 133.265331)
		(end 176.926098 133.032392)
		(width 0.127)
		(layer "In2.Cu")
		(net "PCIE_RX3_P")
	)
	(arc
		(start 179.82732 135.8286)
		(mid 180.283632 135.919366)
		(end 180.670474 136.177846)
		(width 0.127)
		(layer "In2.Cu")
		(net "PCIE_RX3_P")
	)
	(arc
		(start 129.4761 152.78236)
		(mid 129.531896 152.647656)
		(end 129.6666 152.59186)
		(width 0.127)
		(layer "In2.Cu")
		(net "PCIE_RX3_P")
	)
	(arc
		(start 130.5775 145.82063)
		(mid 130.735577 144.938562)
		(end 131.190133 144.166285)
		(width 0.127)
		(layer "In2.Cu")
		(net "PCIE_RX3_P")
	)
	(arc
		(start 181.2759 139.16766)
		(mid 181.061415 140.245954)
		(end 180.450613 141.160089)
		(width 0.127)
		(layer "In2.Cu")
		(net "PCIE_RX3_P")
	)
	(arc
		(start 131.284257 144.062575)
		(mid 131.32536 144.03462)
		(end 131.374044 144.024583)
		(width 0.127)
		(layer "In2.Cu")
		(net "PCIE_RX3_P")
	)
	(arc
		(start 180.674345 136.18172)
		(mid 181.119561 136.848031)
		(end 181.275901 137.634)
		(width 0.127)
		(layer "In2.Cu")
		(net "PCIE_RX3_P")
	)
	(arc
		(start 130.5775 149.86668)
		(mid 130.546814 150.021599)
		(end 130.45939 150.153123)
		(width 0.127)
		(layer "In2.Cu")
		(net "PCIE_RX3_P")
	)
	(arc
		(start 180.164858 141.445865)
		(mid 177.309224 143.354118)
		(end 173.940761 144.02459)
		(width 0.127)
		(layer "In2.Cu")
		(net "PCIE_RX3_P")
	)
	(segment
		(start 126.52608 157.0786)
		(end 126.52608 153.59925)
		(width 0.127)
		(layer "F.Cu")
		(net "PCIE_RX2_N")
	)
	(segment
		(start 177.83583 137.3637)
		(end 177.83583 135.50523)
		(width 0.127)
		(layer "F.Cu")
		(net "PCIE_RX2_N")
	)
	(via
		(at 126.4761 153.4786)
		(size 0.4064)
		(drill 0.2032)
		(layers "F.Cu" "B.Cu")
		(tenting
			(front yes)
			(back yes)
		)
		(net "PCIE_RX2_N")
	)
	(via
		(at 177.7261 137.6286)
		(size 0.4064)
		(drill 0.2032)
		(layers "F.Cu" "B.Cu")
		(tenting
			(front yes)
			(back yes)
		)
		(net "PCIE_RX2_N")
	)
	(arc
		(start 177.83583 137.3637)
		(mid 177.807313 137.507065)
		(end 177.726103 137.628603)
		(width 0.127)
		(layer "F.Cu")
		(net "PCIE_RX2_N")
	)
	(arc
		(start 126.546076 157.757603)
		(mid 126.537804 157.745223)
		(end 126.5349 157.73062)
		(width 0.127)
		(layer "F.Cu")
		(net "PCIE_RX2_N")
	)
	(arc
		(start 126.546077 157.757603)
		(mid 126.368616 157.492014)
		(end 126.3063 157.17873)
		(width 0.127)
		(layer "F.Cu")
		(net "PCIE_RX2_N")
	)
	(arc
		(start 126.476104 153.478596)
		(mid 126.513092 153.533953)
		(end 126.526081 153.59925)
		(width 0.127)
		(layer "F.Cu")
		(net "PCIE_RX2_N")
	)
	(segment
		(start 125.41885 150.73585)
		(end 126.6761 149.47859)
		(width 0.127)
		(layer "In2.Cu")
		(net "PCIE_RX2_N")
	)
	(segment
		(start 131.04402 142.5192)
		(end 174.5596 142.5192)
		(width 0.127)
		(layer "In2.Cu")
		(net "PCIE_RX2_N")
	)
	(segment
		(start 176.35565 141.77525)
		(end 177.19245 140.93845)
		(width 0.127)
		(layer "In2.Cu")
		(net "PCIE_RX2_N")
	)
	(segment
		(start 127.1864 148.24663)
		(end 127.1864 147.34659)
		(width 0.127)
		(layer "In2.Cu")
		(net "PCIE_RX2_N")
	)
	(segment
		(start 127.2501 147.1928)
		(end 127.2501 145.65473)
		(width 0.127)
		(layer "In2.Cu")
		(net "PCIE_RX2_N")
	)
	(segment
		(start 177.7261 137.63239)
		(end 177.7261 137.6286)
		(width 0.127)
		(layer "In2.Cu")
		(net "PCIE_RX2_N")
	)
	(segment
		(start 177.9364 139.1424)
		(end 177.9364 138.14011)
		(width 0.127)
		(layer "In2.Cu")
		(net "PCIE_RX2_N")
	)
	(segment
		(start 125.40648 153.78627)
		(end 125.40717 153.78697)
		(width 0.127)
		(layer "In2.Cu")
		(net "PCIE_RX2_N")
	)
	(segment
		(start 126.26014 153.4786)
		(end 126.4761 153.4786)
		(width 0.127)
		(layer "In2.Cu")
		(net "PCIE_RX2_N")
	)
	(segment
		(start 127.60935 144.78742)
		(end 129.05276 143.34401)
		(width 0.127)
		(layer "In2.Cu")
		(net "PCIE_RX2_N")
	)
	(arc
		(start 177.726107 137.632393)
		(mid 177.881754 137.865336)
		(end 177.93641 138.14011)
		(width 0.127)
		(layer "In2.Cu")
		(net "PCIE_RX2_N")
	)
	(arc
		(start 126.135242 153.57858)
		(mid 125.833499 153.900415)
		(end 125.407169 153.786972)
		(width 0.127)
		(layer "In2.Cu")
		(net "PCIE_RX2_N")
	)
	(arc
		(start 127.1864 148.24663)
		(mid 127.053778 148.913368)
		(end 126.676101 149.478601)
		(width 0.127)
		(layer "In2.Cu")
		(net "PCIE_RX2_N")
	)
	(arc
		(start 127.25011 145.65473)
		(mid 127.343476 145.18535)
		(end 127.609358 144.787428)
		(width 0.127)
		(layer "In2.Cu")
		(net "PCIE_RX2_N")
	)
	(arc
		(start 126.135238 153.57858)
		(mid 126.179964 153.506454)
		(end 126.260133 153.478603)
		(width 0.127)
		(layer "In2.Cu")
		(net "PCIE_RX2_N")
	)
	(arc
		(start 127.1864 147.34659)
		(mid 127.202956 147.263356)
		(end 127.250104 147.192794)
		(width 0.127)
		(layer "In2.Cu")
		(net "PCIE_RX2_N")
	)
	(arc
		(start 124.78726 152.258762)
		(mid 124.951603 151.434496)
		(end 125.418845 150.735849)
		(width 0.127)
		(layer "In2.Cu")
		(net "PCIE_RX2_N")
	)
	(arc
		(start 176.355651 141.775251)
		(mid 175.531616 142.325854)
		(end 174.5596 142.5192)
		(width 0.127)
		(layer "In2.Cu")
		(net "PCIE_RX2_N")
	)
	(arc
		(start 177.9364 139.1424)
		(mid 177.743054 140.114416)
		(end 177.192451 140.938451)
		(width 0.127)
		(layer "In2.Cu")
		(net "PCIE_RX2_N")
	)
	(arc
		(start 129.052765 143.344005)
		(mid 129.966361 142.73356)
		(end 131.04402 142.5192)
		(width 0.127)
		(layer "In2.Cu")
		(net "PCIE_RX2_N")
	)
	(arc
		(start 125.40649 153.786265)
		(mid 124.948222 153.082774)
		(end 124.787271 152.258758)
		(width 0.127)
		(layer "In2.Cu")
		(net "PCIE_RX2_N")
	)
	(segment
		(start 125.69583 153.40817)
		(end 125.69613 153.40787)
		(width 0.127)
		(layer "F.Cu")
		(net "PCIE_RX2_P")
	)
	(segment
		(start 125.4935 157.70502)
		(end 125.54608 157.7576)
		(width 0.127)
		(layer "F.Cu")
		(net "PCIE_RX2_P")
	)
	(segment
		(start 125.54608 157.7576)
		(end 125.6205 157.68318)
		(width 0.127)
		(layer "F.Cu")
		(net "PCIE_RX2_P")
	)
	(segment
		(start 125.6677 153.47477)
		(end 125.6845 153.43091)
		(width 0.127)
		(layer "F.Cu")
		(net "PCIE_RX2_P")
	)
	(segment
		(start 125.64629 153.51109)
		(end 125.64677 153.51052)
		(width 0.127)
		(layer "F.Cu")
		(net "PCIE_RX2_P")
	)
	(segment
		(start 178.33595 137.41096)
		(end 178.33595 135.50523)
		(width 0.127)
		(layer "F.Cu")
		(net "PCIE_RX2_P")
	)
	(segment
		(start 125.69339 153.41236)
		(end 125.69583 153.40817)
		(width 0.127)
		(layer "F.Cu")
		(net "PCIE_RX2_P")
	)
	(segment
		(start 125.52608 157.0786)
		(end 125.52608 153.84078)
		(width 0.127)
		(layer "F.Cu")
		(net "PCIE_RX2_P")
	)
	(via
		(at 125.69613 153.40787)
		(size 0.4064)
		(drill 0.2032)
		(layers "F.Cu" "B.Cu")
		(tenting
			(front yes)
			(back yes)
		)
		(net "PCIE_RX2_P")
	)
	(via
		(at 178.4261 137.6286)
		(size 0.4064)
		(drill 0.2032)
		(layers "F.Cu" "B.Cu")
		(tenting
			(front yes)
			(back yes)
		)
		(net "PCIE_RX2_P")
	)
	(arc
		(start 178.4261 137.6286)
		(mid 178.35938 137.528746)
		(end 178.335951 137.41096)
		(width 0.127)
		(layer "F.Cu")
		(net "PCIE_RX2_P")
	)
	(arc
		(start 125.52608 153.84078)
		(mid 125.557071 153.665316)
		(end 125.646294 153.511085)
		(width 0.127)
		(layer "F.Cu")
		(net "PCIE_RX2_P")
	)
	(arc
		(start 125.667698 153.474767)
		(mid 125.658702 153.4935)
		(end 125.646772 153.510515)
		(width 0.127)
		(layer "F.Cu")
		(net "PCIE_RX2_P")
	)
	(arc
		(start 125.684502 153.430905)
		(mid 125.688569 153.421452)
		(end 125.693388 153.41236)
		(width 0.127)
		(layer "F.Cu")
		(net "PCIE_RX2_P")
	)
	(segment
		(start 125.67626 153.06998)
		(end 125.67626 153.06998)
		(width 0.127)
		(layer "In2.Cu")
		(net "PCIE_RX2_P")
	)
	(segment
		(start 176.55224 141.97379)
		(end 177.391 141.13504)
		(width 0.127)
		(layer "In2.Cu")
		(net "PCIE_RX2_P")
	)
	(segment
		(start 178.21581 139.14378)
		(end 178.21581 138.14011)
		(width 0.127)
		(layer "In2.Cu")
		(net "PCIE_RX2_P")
	)
	(segment
		(start 125.6762 153.22867)
		(end 125.67622 153.16517)
		(width 0.127)
		(layer "In2.Cu")
		(net "PCIE_RX2_P")
	)
	(segment
		(start 125.67686 151.54598)
		(end 125.67686 151.54598)
		(width 0.127)
		(layer "In2.Cu")
		(net "PCIE_RX2_P")
	)
	(segment
		(start 127.5295 147.26349)
		(end 127.5295 145.65753)
		(width 0.127)
		(layer "In2.Cu")
		(net "PCIE_RX2_P")
	)
	(segment
		(start 125.67709 150.98878)
		(end 125.67711 150.92528)
		(width 0.127)
		(layer "In2.Cu")
		(net "PCIE_RX2_P")
	)
	(segment
		(start 125.71431 150.83552)
		(end 126.87453 149.6753)
		(width 0.127)
		(layer "In2.Cu")
		(net "PCIE_RX2_P")
	)
	(segment
		(start 125.31784 151.73641)
		(end 125.48636 151.73641)
		(width 0.127)
		(layer "In2.Cu")
		(net "PCIE_RX2_P")
	)
	(segment
		(start 178.4261 137.6324)
		(end 178.4261 137.6286)
		(width 0.127)
		(layer "In2.Cu")
		(net "PCIE_RX2_P")
	)
	(segment
		(start 125.69612 153.40787)
		(end 125.69613 153.40787)
		(width 0.127)
		(layer "In2.Cu")
		(net "PCIE_RX2_P")
	)
	(segment
		(start 125.67615 153.33945)
		(end 125.6762 153.22867)
		(width 0.127)
		(layer "In2.Cu")
		(net "PCIE_RX2_P")
	)
	(segment
		(start 125.67615 153.33945)
		(end 125.67615 153.33945)
		(width 0.127)
		(layer "In2.Cu")
		(net "PCIE_RX2_P")
	)
	(segment
		(start 125.31754 152.49841)
		(end 125.73999 152.49841)
		(width 0.127)
		(layer "In2.Cu")
		(net "PCIE_RX2_P")
	)
	(segment
		(start 127.8089 144.983)
		(end 129.24935 143.54255)
		(width 0.127)
		(layer "In2.Cu")
		(net "PCIE_RX2_P")
	)
	(segment
		(start 125.67622 153.16517)
		(end 125.67626 153.06998)
		(width 0.127)
		(layer "In2.Cu")
		(net "PCIE_RX2_P")
	)
	(segment
		(start 125.31784 152.11741)
		(end 125.73999 152.11741)
		(width 0.127)
		(layer "In2.Cu")
		(net "PCIE_RX2_P")
	)
	(segment
		(start 125.67686 151.54598)
		(end 125.67709 150.98878)
		(width 0.127)
		(layer "In2.Cu")
		(net "PCIE_RX2_P")
	)
	(segment
		(start 131.0454 142.7986)
		(end 174.56098 142.7986)
		(width 0.127)
		(layer "In2.Cu")
		(net "PCIE_RX2_P")
	)
	(segment
		(start 127.4658 148.24785)
		(end 127.4658 147.41728)
		(width 0.127)
		(layer "In2.Cu")
		(net "PCIE_RX2_P")
	)
	(segment
		(start 125.31754 152.87941)
		(end 125.48576 152.87941)
		(width 0.127)
		(layer "In2.Cu")
		(net "PCIE_RX2_P")
	)
	(segment
		(start 125.67711 150.92528)
		(end 125.67711 150.92527)
		(width 0.127)
		(layer "In2.Cu")
		(net "PCIE_RX2_P")
	)
	(arc
		(start 125.696121 153.407864)
		(mid 125.681239 153.375088)
		(end 125.676151 153.339452)
		(width 0.127)
		(layer "In2.Cu")
		(net "PCIE_RX2_P")
	)
	(arc
		(start 125.73999 152.11741)
		(mid 125.93049 152.30791)
		(end 125.73999 152.49841)
		(width 0.127)
		(layer "In2.Cu")
		(net "PCIE_RX2_P")
	)
	(arc
		(start 125.67686 151.545986)
		(mid 125.621037 151.680641)
		(end 125.48636 151.73641)
		(width 0.127)
		(layer "In2.Cu")
		(net "PCIE_RX2_P")
	)
	(arc
		(start 176.552242 141.973792)
		(mid 175.638643 142.584239)
		(end 174.56098 142.7986)
		(width 0.127)
		(layer "In2.Cu")
		(net "PCIE_RX2_P")
	)
	(arc
		(start 127.4658 148.24785)
		(mid 127.312135 149.020377)
		(end 126.874534 149.675294)
		(width 0.127)
		(layer "In2.Cu")
		(net "PCIE_RX2_P")
	)
	(arc
		(start 178.2158 138.14011)
		(mid 178.270455 137.865341)
		(end 178.426098 137.632402)
		(width 0.127)
		(layer "In2.Cu")
		(net "PCIE_RX2_P")
	)
	(arc
		(start 125.48576 152.87941)
		(mid 125.62049 152.935232)
		(end 125.67626 153.069984)
		(width 0.127)
		(layer "In2.Cu")
		(net "PCIE_RX2_P")
	)
	(arc
		(start 125.67711 150.925272)
		(mid 125.686786 150.876697)
		(end 125.714307 150.835518)
		(width 0.127)
		(layer "In2.Cu")
		(net "PCIE_RX2_P")
	)
	(arc
		(start 127.4658 147.41728)
		(mid 127.474078 147.375663)
		(end 127.497652 147.340382)
		(width 0.127)
		(layer "In2.Cu")
		(net "PCIE_RX2_P")
	)
	(arc
		(start 125.31784 152.11741)
		(mid 125.12734 151.92691)
		(end 125.31784 151.73641)
		(width 0.127)
		(layer "In2.Cu")
		(net "PCIE_RX2_P")
	)
	(arc
		(start 127.5295 145.65753)
		(mid 127.602114 145.292477)
		(end 127.8089 144.983)
		(width 0.127)
		(layer "In2.Cu")
		(net "PCIE_RX2_P")
	)
	(arc
		(start 125.31754 152.87941)
		(mid 125.12704 152.68891)
		(end 125.31754 152.49841)
		(width 0.127)
		(layer "In2.Cu")
		(net "PCIE_RX2_P")
	)
	(arc
		(start 127.52951 147.26349)
		(mid 127.521232 147.305107)
		(end 127.497658 147.340388)
		(width 0.127)
		(layer "In2.Cu")
		(net "PCIE_RX2_P")
	)
	(arc
		(start 129.249349 143.542549)
		(mid 130.073384 142.991946)
		(end 131.0454 142.7986)
		(width 0.127)
		(layer "In2.Cu")
		(net "PCIE_RX2_P")
	)
	(arc
		(start 178.2158 139.143783)
		(mid 178.00144 140.221441)
		(end 177.390995 141.135035)
		(width 0.127)
		(layer "In2.Cu")
		(net "PCIE_RX2_P")
	)
	(segment
		(start 122.1761 153.99576)
		(end 122.1761 153.4786)
		(width 0.127)
		(layer "F.Cu")
		(net "PCIE_RX1_N")
	)
	(segment
		(start 174.67942 136.77528)
		(end 174.67965 136.77505)
		(width 0.127)
		(layer "F.Cu")
		(net "PCIE_RX1_N")
	)
	(segment
		(start 122.52608 157.0786)
		(end 122.52608 154.84069)
		(width 0.127)
		(layer "F.Cu")
		(net "PCIE_RX1_N")
	)
	(segment
		(start 174.83583 136.46369)
		(end 174.83583 135.50523)
		(width 0.127)
		(layer "F.Cu")
		(net "PCIE_RX1_N")
	)
	(segment
		(start 174.67965 136.77505)
		(end 174.7261 136.7286)
		(width 0.127)
		(layer "F.Cu")
		(net "PCIE_RX1_N")
	)
	(via
		(at 174.3261 137.6286)
		(size 0.4064)
		(drill 0.2032)
		(layers "F.Cu" "B.Cu")
		(tenting
			(front yes)
			(back yes)
		)
		(net "PCIE_RX1_N")
	)
	(via
		(at 122.1761 153.4786)
		(size 0.4064)
		(drill 0.2032)
		(layers "F.Cu" "B.Cu")
		(tenting
			(front yes)
			(back yes)
		)
		(net "PCIE_RX1_N")
	)
	(arc
		(start 122.546083 157.757597)
		(mid 122.321251 157.421112)
		(end 122.2423 157.0242)
		(width 0.127)
		(layer "F.Cu")
		(net "PCIE_RX1_N")
	)
	(arc
		(start 174.83583 136.46369)
		(mid 174.807312 136.607059)
		(end 174.7261 136.7286)
		(width 0.127)
		(layer "F.Cu")
		(net "PCIE_RX1_N")
	)
	(arc
		(start 174.32609 137.6286)
		(mid 174.417913 137.166812)
		(end 174.679411 136.775278)
		(width 0.127)
		(layer "F.Cu")
		(net "PCIE_RX1_N")
	)
	(arc
		(start 122.376105 154.478595)
		(mid 122.48711 154.644726)
		(end 122.52609 154.84069)
		(width 0.127)
		(layer "F.Cu")
		(net "PCIE_RX1_N")
	)
	(arc
		(start 122.376099 154.478601)
		(mid 122.228078 154.257072)
		(end 122.1761 153.99576)
		(width 0.127)
		(layer "F.Cu")
		(net "PCIE_RX1_N")
	)
	(segment
		(start 174.3261 137.6324)
		(end 174.3261 137.6286)
		(width 0.127)
		(layer "In2.Cu")
		(net "PCIE_RX1_N")
	)
	(segment
		(start 121.91774 153.49702)
		(end 121.91774 153.49702)
		(width 0.127)
		(layer "In2.Cu")
		(net "PCIE_RX1_N")
	)
	(segment
		(start 174.00253 140.69652)
		(end 174.36836 140.33069)
		(width 0.127)
		(layer "In2.Cu")
		(net "PCIE_RX1_N")
	)
	(segment
		(start 121.33775 153.01027)
		(end 121.33775 153.01027)
		(width 0.127)
		(layer "In2.Cu")
		(net "PCIE_RX1_N")
	)
	(segment
		(start 123.7864 146.1162)
		(end 123.7864 146.11398)
		(width 0.127)
		(layer "In2.Cu")
		(net "PCIE_RX1_N")
	)
	(segment
		(start 174.5364 139.92501)
		(end 174.5364 138.14011)
		(width 0.127)
		(layer "In2.Cu")
		(net "PCIE_RX1_N")
	)
	(segment
		(start 121.51163 152.81799)
		(end 121.60942 152.43171)
		(width 0.127)
		(layer "In2.Cu")
		(net "PCIE_RX1_N")
	)
	(segment
		(start 121.66406 150.29604)
		(end 121.66406 150.29604)
		(width 0.127)
		(layer "In2.Cu")
		(net "PCIE_RX1_N")
	)
	(segment
		(start 122.57386 148.38084)
		(end 123.04245 147.91225)
		(width 0.127)
		(layer "In2.Cu")
		(net "PCIE_RX1_N")
	)
	(segment
		(start 121.60942 152.43171)
		(end 121.60947 152.43151)
		(width 0.127)
		(layer "In2.Cu")
		(net "PCIE_RX1_N")
	)
	(segment
		(start 173.99969 140.69652)
		(end 174.00253 140.69652)
		(width 0.127)
		(layer "In2.Cu")
		(net "PCIE_RX1_N")
	)
	(segment
		(start 124.53566 144.30511)
		(end 126.61436 142.22641)
		(width 0.127)
		(layer "In2.Cu")
		(net "PCIE_RX1_N")
	)
	(segment
		(start 122.03396 153.4786)
		(end 122.1761 153.4786)
		(width 0.127)
		(layer "In2.Cu")
		(net "PCIE_RX1_N")
	)
	(segment
		(start 128.60562 141.4016)
		(end 172.2482 141.4016)
		(width 0.127)
		(layer "In2.Cu")
		(net "PCIE_RX1_N")
	)
	(segment
		(start 121.66365 152.26971)
		(end 121.66366 150.30604)
		(width 0.127)
		(layer "In2.Cu")
		(net "PCIE_RX1_N")
	)
	(segment
		(start 122.13216 148.96642)
		(end 122.13216 148.96642)
		(width 0.127)
		(layer "In2.Cu")
		(net "PCIE_RX1_N")
	)
	(segment
		(start 121.8329 153.58878)
		(end 121.8334 153.58675)
		(width 0.127)
		(layer "In2.Cu")
		(net "PCIE_RX1_N")
	)
	(arc
		(start 121.43758 152.946824)
		(mid 121.464094 152.902833)
		(end 121.492531 152.86006)
		(width 0.127)
		(layer "In2.Cu")
		(net "PCIE_RX1_N")
	)
	(arc
		(start 121.66406 150.29604)
		(mid 121.811311 149.600674)
		(end 122.132157 148.966423)
		(width 0.127)
		(layer "In2.Cu")
		(net "PCIE_RX1_N")
	)
	(arc
		(start 122.132167 148.96641)
		(mid 122.332608 148.658233)
		(end 122.573858 148.380838)
		(width 0.127)
		(layer "In2.Cu")
		(net "PCIE_RX1_N")
	)
	(arc
		(start 173.999691 140.696515)
		(mid 173.894749 140.794534)
		(end 173.783371 140.885174)
		(width 0.127)
		(layer "In2.Cu")
		(net "PCIE_RX1_N")
	)
	(arc
		(start 121.832899 153.588785)
		(mid 121.019107 153.784152)
		(end 121.337743 153.010268)
		(width 0.127)
		(layer "In2.Cu")
		(net "PCIE_RX1_N")
	)
	(arc
		(start 123.7864 146.1162)
		(mid 123.593054 147.088216)
		(end 123.042451 147.912251)
		(width 0.127)
		(layer "In2.Cu")
		(net "PCIE_RX1_N")
	)
	(arc
		(start 174.5364 139.92501)
		(mid 174.492727 140.144567)
		(end 174.368358 140.330698)
		(width 0.127)
		(layer "In2.Cu")
		(net "PCIE_RX1_N")
	)
	(arc
		(start 121.833394 153.586754)
		(mid 121.86396 153.530982)
		(end 121.917733 153.497022)
		(width 0.127)
		(layer "In2.Cu")
		(net "PCIE_RX1_N")
	)
	(arc
		(start 123.7864 146.11398)
		(mid 123.981125 145.13503)
		(end 124.535656 144.305116)
		(width 0.127)
		(layer "In2.Cu")
		(net "PCIE_RX1_N")
	)
	(arc
		(start 121.437576 152.946823)
		(mid 121.395497 152.990877)
		(end 121.337743 153.010266)
		(width 0.127)
		(layer "In2.Cu")
		(net "PCIE_RX1_N")
	)
	(arc
		(start 126.614365 142.226405)
		(mid 127.527961 141.61596)
		(end 128.60562 141.4016)
		(width 0.127)
		(layer "In2.Cu")
		(net "PCIE_RX1_N")
	)
	(arc
		(start 121.511627 152.817986)
		(mid 121.50401 152.839899)
		(end 121.492535 152.860061)
		(width 0.127)
		(layer "In2.Cu")
		(net "PCIE_RX1_N")
	)
	(arc
		(start 121.917739 153.497017)
		(mid 121.975124 153.483233)
		(end 122.03396 153.4786)
		(width 0.127)
		(layer "In2.Cu")
		(net "PCIE_RX1_N")
	)
	(arc
		(start 121.609471 152.431508)
		(mid 121.625934 152.379301)
		(end 121.648689 152.329514)
		(width 0.127)
		(layer "In2.Cu")
		(net "PCIE_RX1_N")
	)
	(arc
		(start 121.66366 150.306039)
		(mid 121.663759 150.301034)
		(end 121.664055 150.296037)
		(width 0.127)
		(layer "In2.Cu")
		(net "PCIE_RX1_N")
	)
	(arc
		(start 174.3261 137.6324)
		(mid 174.481745 137.865339)
		(end 174.5364 138.14011)
		(width 0.127)
		(layer "In2.Cu")
		(net "PCIE_RX1_N")
	)
	(arc
		(start 173.78336 140.885182)
		(mid 173.058046 141.269036)
		(end 172.2482 141.4016)
		(width 0.127)
		(layer "In2.Cu")
		(net "PCIE_RX1_N")
	)
	(arc
		(start 121.66365 152.269713)
		(mid 121.659852 152.300537)
		(end 121.648686 152.329517)
		(width 0.127)
		(layer "In2.Cu")
		(net "PCIE_RX1_N")
	)
	(segment
		(start 175.33596 136.46338)
		(end 175.33596 135.50523)
		(width 0.127)
		(layer "F.Cu")
		(net "PCIE_RX1_P")
	)
	(segment
		(start 175.0261 137.6286)
		(end 175.0261 137.21144)
		(width 0.127)
		(layer "F.Cu")
		(net "PCIE_RX1_P")
	)
	(segment
		(start 121.52609 157.0786)
		(end 121.52609 153.84069)
		(width 0.127)
		(layer "F.Cu")
		(net "PCIE_RX1_P")
	)
	(via
		(at 175.0261 137.6286)
		(size 0.4064)
		(drill 0.2032)
		(layers "F.Cu" "B.Cu")
		(tenting
			(front yes)
			(back yes)
		)
		(net "PCIE_RX1_P")
	)
	(via
		(at 121.3761 153.4786)
		(size 0.4064)
		(drill 0.2032)
		(layers "F.Cu" "B.Cu")
		(tenting
			(front yes)
			(back yes)
		)
		(net "PCIE_RX1_P")
	)
	(arc
		(start 175.33596 136.46338)
		(mid 175.307409 136.606917)
		(end 175.226102 136.728602)
		(width 0.127)
		(layer "F.Cu")
		(net "PCIE_RX1_P")
	)
	(arc
		(start 121.376105 153.478595)
		(mid 121.48711 153.644726)
		(end 121.52609 153.84069)
		(width 0.127)
		(layer "F.Cu")
		(net "PCIE_RX1_P")
	)
	(arc
		(start 175.0261 137.21144)
		(mid 175.078078 136.950128)
		(end 175.226099 136.728599)
		(width 0.127)
		(layer "F.Cu")
		(net "PCIE_RX1_P")
	)
	(arc
		(start 121.546085 157.757595)
		(mid 121.365806 157.487788)
		(end 121.302501 157.16953)
		(width 0.127)
		(layer "F.Cu")
		(net "PCIE_RX1_P")
	)
	(segment
		(start 122.16659 151.20533)
		(end 122.3248 151.20533)
		(width 0.127)
		(layer "In2.Cu")
		(net "PCIE_RX1_P")
	)
	(segment
		(start 121.97609 150.7421)
		(end 121.9761 150.6786)
		(width 0.127)
		(layer "In2.Cu")
		(net "PCIE_RX1_P")
	)
	(segment
		(start 174.24084 140.85619)
		(end 174.24084 140.85334)
		(width 0.127)
		(layer "In2.Cu")
		(net "PCIE_RX1_P")
	)
	(segment
		(start 121.85614 152.49208)
		(end 121.85615 152.49208)
		(width 0.127)
		(layer "In2.Cu")
		(net "PCIE_RX1_P")
	)
	(segment
		(start 122.04082 152.34833)
		(end 122.41719 152.34833)
		(width 0.127)
		(layer "In2.Cu")
		(net "PCIE_RX1_P")
	)
	(segment
		(start 175.0261 137.6286)
		(end 175.0261 137.6286)
		(width 0.127)
		(layer "In2.Cu")
		(net "PCIE_RX1_P")
	)
	(segment
		(start 122.77367 148.57616)
		(end 122.77367 148.57616)
		(width 0.127)
		(layer "In2.Cu")
		(net "PCIE_RX1_P")
	)
	(segment
		(start 121.72374 153.0151)
		(end 121.85615 152.49208)
		(width 0.127)
		(layer "In2.Cu")
		(net "PCIE_RX1_P")
	)
	(segment
		(start 128.607 141.681)
		(end 172.24958 141.681)
		(width 0.127)
		(layer "In2.Cu")
		(net "PCIE_RX1_P")
	)
	(segment
		(start 121.97609 151.01483)
		(end 121.97609 150.7421)
		(width 0.127)
		(layer "In2.Cu")
		(net "PCIE_RX1_P")
	)
	(segment
		(start 121.9761 150.6786)
		(end 121.9761 150.6786)
		(width 0.127)
		(layer "In2.Cu")
		(net "PCIE_RX1_P")
	)
	(segment
		(start 122.10817 151.58633)
		(end 122.3248 151.58633)
		(width 0.127)
		(layer "In2.Cu")
		(net "PCIE_RX1_P")
	)
	(segment
		(start 174.24084 140.85334)
		(end 174.60697 140.48721)
		(width 0.127)
		(layer "In2.Cu")
		(net "PCIE_RX1_P")
	)
	(segment
		(start 124.73578 144.50013)
		(end 126.81095 142.42495)
		(width 0.127)
		(layer "In2.Cu")
		(net "PCIE_RX1_P")
	)
	(segment
		(start 174.8624 138.029)
		(end 174.8624 139.87054)
		(width 0.127)
		(layer "In2.Cu")
		(net "PCIE_RX1_P")
	)
	(segment
		(start 122.77367 148.57616)
		(end 123.241 148.10884)
		(width 0.127)
		(layer "In2.Cu")
		(net "PCIE_RX1_P")
	)
	(segment
		(start 122.10817 151.96733)
		(end 122.41719 151.96733)
		(width 0.127)
		(layer "In2.Cu")
		(net "PCIE_RX1_P")
	)
	(segment
		(start 121.9761 150.6786)
		(end 121.9761 150.49942)
		(width 0.127)
		(layer "In2.Cu")
		(net "PCIE_RX1_P")
	)
	(arc
		(start 174.8624 139.87054)
		(mid 174.796015 140.204282)
		(end 174.606965 140.487215)
		(width 0.127)
		(layer "In2.Cu")
		(net "PCIE_RX1_P")
	)
	(arc
		(start 174.240842 140.856192)
		(mid 173.327243 141.466639)
		(end 172.24958 141.681)
		(width 0.127)
		(layer "In2.Cu")
		(net "PCIE_RX1_P")
	)
	(arc
		(start 124.0658 146.117583)
		(mid 123.85144 147.195241)
		(end 123.240995 148.108835)
		(width 0.127)
		(layer "In2.Cu")
		(net "PCIE_RX1_P")
	)
	(arc
		(start 122.41719 151.96733)
		(mid 122.60769 152.15783)
		(end 122.41719 152.34833)
		(width 0.127)
		(layer "In2.Cu")
		(net "PCIE_RX1_P")
	)
	(arc
		(start 122.10817 151.96733)
		(mid 121.91767 151.77683)
		(end 122.10817 151.58633)
		(width 0.127)
		(layer "In2.Cu")
		(net "PCIE_RX1_P")
	)
	(arc
		(start 124.06579 146.117584)
		(mid 124.239912 145.242222)
		(end 124.735766 144.500126)
		(width 0.127)
		(layer "In2.Cu")
		(net "PCIE_RX1_P")
	)
	(arc
		(start 121.723736 153.015098)
		(mid 121.705863 153.04701)
		(end 121.687422 153.078598)
		(width 0.127)
		(layer "In2.Cu")
		(net "PCIE_RX1_P")
	)
	(arc
		(start 126.810949 142.424949)
		(mid 127.634984 141.874346)
		(end 128.607 141.681)
		(width 0.127)
		(layer "In2.Cu")
		(net "PCIE_RX1_P")
	)
	(arc
		(start 122.16659 151.20533)
		(mid 122.031885 151.149533)
		(end 121.97609 151.014827)
		(width 0.127)
		(layer "In2.Cu")
		(net "PCIE_RX1_P")
	)
	(arc
		(start 175.026102 137.628602)
		(mid 175.019565 137.638011)
		(end 175.012206 137.646793)
		(width 0.127)
		(layer "In2.Cu")
		(net "PCIE_RX1_P")
	)
	(arc
		(start 174.862402 138.028999)
		(mid 174.900945 137.823647)
		(end 175.012209 137.646799)
		(width 0.127)
		(layer "In2.Cu")
		(net "PCIE_RX1_P")
	)
	(arc
		(start 122.3248 151.20533)
		(mid 122.5153 151.39583)
		(end 122.3248 151.58633)
		(width 0.127)
		(layer "In2.Cu")
		(net "PCIE_RX1_P")
	)
	(arc
		(start 121.687422 153.078598)
		(mid 121.54418 153.288265)
		(end 121.3761 153.478599)
		(width 0.127)
		(layer "In2.Cu")
		(net "PCIE_RX1_P")
	)
	(arc
		(start 121.856146 152.492079)
		(mid 121.923807 152.388503)
		(end 122.04082 152.34833)
		(width 0.127)
		(layer "In2.Cu")
		(net "PCIE_RX1_P")
	)
	(arc
		(start 121.976101 150.499412)
		(mid 122.183809 149.458548)
		(end 122.773667 148.576159)
		(width 0.127)
		(layer "In2.Cu")
		(net "PCIE_RX1_P")
	)
	(segment
		(start 117.52609 157.0786)
		(end 117.52609 154.56501)
		(width 0.127)
		(layer "F.Cu")
		(net "PCIE_RX0_N")
	)
	(segment
		(start 173.33596 132.91874)
		(end 173.33596 131.45545)
		(width 0.127)
		(layer "F.Cu")
		(net "PCIE_RX0_N")
	)
	(via
		(at 117.9761 153.4786)
		(size 0.4064)
		(drill 0.2032)
		(layers "F.Cu" "B.Cu")
		(tenting
			(front yes)
			(back yes)
		)
		(net "PCIE_RX0_N")
	)
	(via
		(at 173.2261 133.0286)
		(size 0.4064)
		(drill 0.2032)
		(layers "F.Cu" "B.Cu")
		(tenting
			(front yes)
			(back yes)
		)
		(net "PCIE_RX0_N")
	)
	(arc
		(start 117.52609 154.56501)
		(mid 117.643043 153.977048)
		(end 117.976097 153.478597)
		(width 0.127)
		(layer "F.Cu")
		(net "PCIE_RX0_N")
	)
	(arc
		(start 117.546094 157.757596)
		(mid 117.374837 157.501292)
		(end 117.314699 157.19896)
		(width 0.127)
		(layer "F.Cu")
		(net "PCIE_RX0_N")
	)
	(arc
		(start 173.33596 132.91874)
		(mid 173.303783 132.996423)
		(end 173.2261 133.0286)
		(width 0.127)
		(layer "F.Cu")
		(net "PCIE_RX0_N")
	)
	(segment
		(start 171.9256 136.52909)
		(end 172.69245 135.76224)
		(width 0.127)
		(layer "In2.Cu")
		(net "PCIE_RX0_N")
	)
	(segment
		(start 120.74056 147.80497)
		(end 120.74056 147.5907)
		(width 0.127)
		(layer "In2.Cu")
		(net "PCIE_RX0_N")
	)
	(segment
		(start 173.2261 133.03239)
		(end 173.2261 133.0286)
		(width 0.127)
		(layer "In2.Cu")
		(net "PCIE_RX0_N")
	)
	(segment
		(start 119.76802 151.41722)
		(end 119.76805 151.41724)
		(width 0.127)
		(layer "In2.Cu")
		(net "PCIE_RX0_N")
	)
	(segment
		(start 119.49862 151.68663)
		(end 119.49864 151.68665)
		(width 0.127)
		(layer "In2.Cu")
		(net "PCIE_RX0_N")
	)
	(segment
		(start 119.76805 151.41725)
		(end 119.76805 151.41724)
		(width 0.127)
		(layer "In2.Cu")
		(net "PCIE_RX0_N")
	)
	(segment
		(start 119.16654 151.89337)
		(end 119.22923 151.95605)
		(width 0.127)
		(layer "In2.Cu")
		(net "PCIE_RX0_N")
	)
	(segment
		(start 120.48333 150.97137)
		(end 120.64219 150.81251)
		(width 0.127)
		(layer "In2.Cu")
		(net "PCIE_RX0_N")
	)
	(segment
		(start 170.86925 140.09885)
		(end 170.9381 140.03)
		(width 0.127)
		(layer "In2.Cu")
		(net "PCIE_RX0_N")
	)
	(segment
		(start 118.89713 152.16277)
		(end 118.95982 152.22546)
		(width 0.127)
		(layer "In2.Cu")
		(net "PCIE_RX0_N")
	)
	(segment
		(start 120.03746 151.41724)
		(end 120.48333 150.97137)
		(width 0.127)
		(layer "In2.Cu")
		(net "PCIE_RX0_N")
	)
	(segment
		(start 118.3761 153.0786)
		(end 118.42101 153.03369)
		(width 0.127)
		(layer "In2.Cu")
		(net "PCIE_RX0_N")
	)
	(segment
		(start 120.64219 150.81251)
		(end 120.74056 150.71414)
		(width 0.127)
		(layer "In2.Cu")
		(net "PCIE_RX0_N")
	)
	(segment
		(start 171.5467 138.56072)
		(end 171.5467 137.44385)
		(width 0.127)
		(layer "In2.Cu")
		(net "PCIE_RX0_N")
	)
	(segment
		(start 120.74056 150.71414)
		(end 120.74056 147.80497)
		(width 0.127)
		(layer "In2.Cu")
		(net "PCIE_RX0_N")
	)
	(segment
		(start 117.9761 153.4786)
		(end 118.3761 153.0786)
		(width 0.127)
		(layer "In2.Cu")
		(net "PCIE_RX0_N")
	)
	(segment
		(start 121.56566 145.59871)
		(end 125.49676 141.66761)
		(width 0.127)
		(layer "In2.Cu")
		(net "PCIE_RX0_N")
	)
	(segment
		(start 118.33731 152.68058)
		(end 118.42101 152.76428)
		(width 0.127)
		(layer "In2.Cu")
		(net "PCIE_RX0_N")
	)
	(segment
		(start 173.4364 133.96619)
		(end 173.4364 133.54011)
		(width 0.127)
		(layer "In2.Cu")
		(net "PCIE_RX0_N")
	)
	(segment
		(start 127.48802 140.8428)
		(end 169.07319 140.8428)
		(width 0.127)
		(layer "In2.Cu")
		(net "PCIE_RX0_N")
	)
	(segment
		(start 118.60672 152.41117)
		(end 118.69041 152.49487)
		(width 0.127)
		(layer "In2.Cu")
		(net "PCIE_RX0_N")
	)
	(arc
		(start 171.5467 137.44385)
		(mid 171.645174 136.948788)
		(end 171.925604 136.529094)
		(width 0.127)
		(layer "In2.Cu")
		(net "PCIE_RX0_N")
	)
	(arc
		(start 119.498631 151.956056)
		(mid 119.363929 152.01185)
		(end 119.229227 151.956054)
		(width 0.127)
		(layer "In2.Cu")
		(net "PCIE_RX0_N")
	)
	(arc
		(start 125.496765 141.667605)
		(mid 126.410361 141.05716)
		(end 127.48802 140.8428)
		(width 0.127)
		(layer "In2.Cu")
		(net "PCIE_RX0_N")
	)
	(arc
		(start 118.897136 151.893366)
		(mid 119.03184 151.83757)
		(end 119.166544 151.893366)
		(width 0.127)
		(layer "In2.Cu")
		(net "PCIE_RX0_N")
	)
	(arc
		(start 119.498616 151.686624)
		(mid 119.44282 151.551922)
		(end 119.498613 151.417219)
		(width 0.127)
		(layer "In2.Cu")
		(net "PCIE_RX0_N")
	)
	(arc
		(start 120.74056 147.5907)
		(mid 120.954999 146.512643)
		(end 121.565669 145.598709)
		(width 0.127)
		(layer "In2.Cu")
		(net "PCIE_RX0_N")
	)
	(arc
		(start 173.226107 133.032393)
		(mid 173.381754 133.265336)
		(end 173.43641 133.54011)
		(width 0.127)
		(layer "In2.Cu")
		(net "PCIE_RX0_N")
	)
	(arc
		(start 173.4364 133.96619)
		(mid 173.243054 134.938206)
		(end 172.692451 135.762241)
		(width 0.127)
		(layer "In2.Cu")
		(net "PCIE_RX0_N")
	)
	(arc
		(start 119.498616 151.417216)
		(mid 119.63332 151.36142)
		(end 119.768024 151.417216)
		(width 0.127)
		(layer "In2.Cu")
		(net "PCIE_RX0_N")
	)
	(arc
		(start 118.959821 152.494866)
		(mid 118.825119 152.55066)
		(end 118.690417 152.494864)
		(width 0.127)
		(layer "In2.Cu")
		(net "PCIE_RX0_N")
	)
	(arc
		(start 118.897136 152.162774)
		(mid 118.84134 152.028072)
		(end 118.897133 151.893369)
		(width 0.127)
		(layer "In2.Cu")
		(net "PCIE_RX0_N")
	)
	(arc
		(start 170.869241 140.098851)
		(mid 170.045206 140.649454)
		(end 169.07319 140.8428)
		(width 0.127)
		(layer "In2.Cu")
		(net "PCIE_RX0_N")
	)
	(arc
		(start 118.337316 152.680584)
		(mid 118.28152 152.545882)
		(end 118.337313 152.411179)
		(width 0.127)
		(layer "In2.Cu")
		(net "PCIE_RX0_N")
	)
	(arc
		(start 118.959824 152.225466)
		(mid 119.01562 152.36017)
		(end 118.959824 152.494874)
		(width 0.127)
		(layer "In2.Cu")
		(net "PCIE_RX0_N")
	)
	(arc
		(start 119.498634 151.686646)
		(mid 119.55443 151.82135)
		(end 119.498634 151.956054)
		(width 0.127)
		(layer "In2.Cu")
		(net "PCIE_RX0_N")
	)
	(arc
		(start 118.421014 152.764286)
		(mid 118.47681 152.89899)
		(end 118.421014 153.033694)
		(width 0.127)
		(layer "In2.Cu")
		(net "PCIE_RX0_N")
	)
	(arc
		(start 118.337306 152.411176)
		(mid 118.47201 152.35538)
		(end 118.606714 152.411176)
		(width 0.127)
		(layer "In2.Cu")
		(net "PCIE_RX0_N")
	)
	(arc
		(start 171.5467 138.56072)
		(mid 171.388531 139.35589)
		(end 170.938103 140.030003)
		(width 0.127)
		(layer "In2.Cu")
		(net "PCIE_RX0_N")
	)
	(arc
		(start 120.037454 151.417244)
		(mid 119.90275 151.47304)
		(end 119.768046 151.417244)
		(width 0.127)
		(layer "In2.Cu")
		(net "PCIE_RX0_N")
	)
	(segment
		(start 116.5261 157.0786)
		(end 116.5261 155.04785)
		(width 0.127)
		(layer "F.Cu")
		(net "PCIE_RX0_P")
	)
	(segment
		(start 173.83583 132.93833)
		(end 173.83583 131.45545)
		(width 0.127)
		(layer "F.Cu")
		(net "PCIE_RX0_P")
	)
	(via
		(at 117.1761 153.4786)
		(size 0.4064)
		(drill 0.2032)
		(layers "F.Cu" "B.Cu")
		(tenting
			(front yes)
			(back yes)
		)
		(net "PCIE_RX0_P")
	)
	(via
		(at 173.9261 133.0286)
		(size 0.4064)
		(drill 0.2032)
		(layers "F.Cu" "B.Cu")
		(tenting
			(front yes)
			(back yes)
		)
		(net "PCIE_RX0_P")
	)
	(arc
		(start 173.9261 133.0286)
		(mid 173.862269 133.002161)
		(end 173.83583 132.93833)
		(width 0.127)
		(layer "F.Cu")
		(net "PCIE_RX0_P")
	)
	(arc
		(start 116.5261 155.04785)
		(mid 116.69503 154.19858)
		(end 117.176103 153.478603)
		(width 0.127)
		(layer "F.Cu")
		(net "PCIE_RX0_P")
	)
	(segment
		(start 171.06632 140.29692)
		(end 171.13705 140.22618)
		(width 0.127)
		(layer "In2.Cu")
		(net "PCIE_RX0_P")
	)
	(segment
		(start 173.7158 133.96758)
		(end 173.7158 133.5401)
		(width 0.127)
		(layer "In2.Cu")
		(net "PCIE_RX0_P")
	)
	(segment
		(start 117.1761 153.4786)
		(end 117.39206 153.4786)
		(width 0.127)
		(layer "In2.Cu")
		(net "PCIE_RX0_P")
	)
	(segment
		(start 172.12367 136.72616)
		(end 172.12367 136.72616)
		(width 0.127)
		(layer "In2.Cu")
		(net "PCIE_RX0_P")
	)
	(segment
		(start 121.0142 147.80497)
		(end 121.0142 147.60556)
		(width 0.127)
		(layer "In2.Cu")
		(net "PCIE_RX0_P")
	)
	(segment
		(start 127.4894 141.1222)
		(end 169.0739 141.1222)
		(width 0.127)
		(layer "In2.Cu")
		(net "PCIE_RX0_P")
	)
	(segment
		(start 171.8261 138.56267)
		(end 171.8261 137.44379)
		(width 0.127)
		(layer "In2.Cu")
		(net "PCIE_RX0_P")
	)
	(segment
		(start 173.9261 133.0324)
		(end 173.9261 133.0286)
		(width 0.127)
		(layer "In2.Cu")
		(net "PCIE_RX0_P")
	)
	(segment
		(start 121.0142 150.81251)
		(end 121.0142 147.80497)
		(width 0.127)
		(layer "In2.Cu")
		(net "PCIE_RX0_P")
	)
	(segment
		(start 172.12367 136.72616)
		(end 172.891 135.95883)
		(width 0.127)
		(layer "In2.Cu")
		(net "PCIE_RX0_P")
	)
	(segment
		(start 121.7639 145.7956)
		(end 125.69335 141.86615)
		(width 0.127)
		(layer "In2.Cu")
		(net "PCIE_RX0_P")
	)
	(segment
		(start 118.4734 153.3533)
		(end 121.0142 150.81251)
		(width 0.127)
		(layer "In2.Cu")
		(net "PCIE_RX0_P")
	)
	(segment
		(start 117.39206 153.4786)
		(end 117.39206 153.4786)
		(width 0.127)
		(layer "In2.Cu")
		(net "PCIE_RX0_P")
	)
	(arc
		(start 173.7158 133.96758)
		(mid 173.50144 135.04524)
		(end 172.890995 135.958835)
		(width 0.127)
		(layer "In2.Cu")
		(net "PCIE_RX0_P")
	)
	(arc
		(start 171.8261 137.443796)
		(mid 171.903579 137.055415)
		(end 172.123664 136.726165)
		(width 0.127)
		(layer "In2.Cu")
		(net "PCIE_RX0_P")
	)
	(arc
		(start 171.8261 138.562673)
		(mid 171.647021 139.462961)
		(end 171.137048 140.226188)
		(width 0.127)
		(layer "In2.Cu")
		(net "PCIE_RX0_P")
	)
	(arc
		(start 171.066323 140.296915)
		(mid 170.152191 140.907716)
		(end 169.0739 141.1222)
		(width 0.127)
		(layer "In2.Cu")
		(net "PCIE_RX0_P")
	)
	(arc
		(start 173.7158 133.5401)
		(mid 173.770455 133.265331)
		(end 173.926098 133.032393)
		(width 0.127)
		(layer "In2.Cu")
		(net "PCIE_RX0_P")
	)
	(arc
		(start 118.473404 153.353305)
		(mid 118.441959 153.600505)
		(end 118.308376 153.810868)
		(width 0.127)
		(layer "In2.Cu")
		(net "PCIE_RX0_P")
	)
	(arc
		(start 121.01419 147.60556)
		(mid 121.209034 146.626016)
		(end 121.763901 145.795599)
		(width 0.127)
		(layer "In2.Cu")
		(net "PCIE_RX0_P")
	)
	(arc
		(start 117.392067 153.478603)
		(mid 117.472235 153.506453)
		(end 117.516961 153.578578)
		(width 0.127)
		(layer "In2.Cu")
		(net "PCIE_RX0_P")
	)
	(arc
		(start 125.693349 141.866149)
		(mid 126.517384 141.315546)
		(end 127.4894 141.1222)
		(width 0.127)
		(layer "In2.Cu")
		(net "PCIE_RX0_P")
	)
	(arc
		(start 118.308368 153.810871)
		(mid 117.84376 153.929479)
		(end 117.51696 153.578581)
		(width 0.127)
		(layer "In2.Cu")
		(net "PCIE_RX0_P")
	)
	(segment
		(start 193.34123 123.81347)
		(end 195.31345 123.81347)
		(width 0.2032)
		(layer "F.Cu")
		(net "LED1")
	)
	(segment
		(start 69.8559 57.4)
		(end 69.8559 56.3114)
		(width 0.2032)
		(layer "F.Cu")
		(net "LED1")
	)
	(segment
		(start 195.31345 123.81347)
		(end 195.31363 123.8133)
		(width 0.2032)
		(layer "F.Cu")
		(net "LED1")
	)
	(segment
		(start 193.34105 123.81365)
		(end 193.34123 123.81347)
		(width 0.2032)
		(layer "F.Cu")
		(net "LED1")
	)
	(segment
		(start 69.8559 56.3114)
		(end 69.8761 56.2912)
		(width 0.2032)
		(layer "F.Cu")
		(net "LED1")
	)
	(via
		(at 193.34105 123.81365)
		(size 0.4064)
		(drill 0.2032)
		(layers "F.Cu" "B.Cu")
		(tenting
			(front yes)
			(back yes)
		)
		(net "LED1")
	)
	(via
		(at 69.8559 57.4)
		(size 0.4064)
		(drill 0.2032)
		(layers "F.Cu" "B.Cu")
		(tenting
			(front yes)
			(back yes)
		)
		(net "LED1")
	)
	(segment
		(start 189.1759 127.9788)
		(end 193.34105 123.81365)
		(width 0.2032)
		(layer "In2.Cu")
		(net "LED1")
	)
	(segment
		(start 155.3759 127.9788)
		(end 189.1759 127.9788)
		(width 0.2032)
		(layer "In2.Cu")
		(net "LED1")
	)
	(segment
		(start 69.8559 80.24691)
		(end 89.6761 100.06711)
		(width 0.2032)
		(layer "In2.Cu")
		(net "LED1")
	)
	(segment
		(start 69.8559 80.24691)
		(end 69.8559 57.4)
		(width 0.2032)
		(layer "In2.Cu")
		(net "LED1")
	)
	(segment
		(start 154.0385 129.3162)
		(end 155.3759 127.9788)
		(width 0.2032)
		(layer "In2.Cu")
		(net "LED1")
	)
	(segment
		(start 103.3137 129.3162)
		(end 154.0385 129.3162)
		(width 0.2032)
		(layer "In2.Cu")
		(net "LED1")
	)
	(segment
		(start 89.6761 115.6786)
		(end 89.6761 100.06711)
		(width 0.2032)
		(layer "In2.Cu")
		(net "LED1")
	)
	(segment
		(start 89.6761 115.6786)
		(end 103.3137 129.3162)
		(width 0.2032)
		(layer "In2.Cu")
		(net "LED1")
	)
	(segment
		(start 71.6261 57.3662)
		(end 71.6261 56.2912)
		(width 0.2032)
		(layer "F.Cu")
		(net "LED2")
	)
	(segment
		(start 193.367 123.20475)
		(end 193.47568 123.31342)
		(width 0.2032)
		(layer "F.Cu")
		(net "LED2")
	)
	(segment
		(start 193.31202 123.20475)
		(end 193.367 123.20475)
		(width 0.2032)
		(layer "F.Cu")
		(net "LED2")
	)
	(segment
		(start 193.47568 123.31342)
		(end 195.31363 123.31342)
		(width 0.2032)
		(layer "F.Cu")
		(net "LED2")
	)
	(via
		(at 193.31202 123.20475)
		(size 0.4064)
		(drill 0.2032)
		(layers "F.Cu" "B.Cu")
		(tenting
			(front yes)
			(back yes)
		)
		(net "LED2")
	)
	(via
		(at 71.6261 57.3662)
		(size 0.4064)
		(drill 0.2032)
		(layers "F.Cu" "B.Cu")
		(tenting
			(front yes)
			(back yes)
		)
		(net "LED2")
	)
	(segment
		(start 71.6261 81.55014)
		(end 90.0157 99.93974)
		(width 0.2032)
		(layer "In2.Cu")
		(net "LED2")
	)
	(segment
		(start 156.09631 126.65839)
		(end 189.85837 126.65839)
		(width 0.2032)
		(layer "In2.Cu")
		(net "LED2")
	)
	(segment
		(start 90.0157 115.4182)
		(end 90.0157 99.93974)
		(width 0.2032)
		(layer "In2.Cu")
		(net "LED2")
	)
	(segment
		(start 103.4137 128.8162)
		(end 153.9385 128.8162)
		(width 0.2032)
		(layer "In2.Cu")
		(net "LED2")
	)
	(segment
		(start 153.9385 128.8162)
		(end 156.09631 126.65839)
		(width 0.2032)
		(layer "In2.Cu")
		(net "LED2")
	)
	(segment
		(start 71.6261 81.55014)
		(end 71.6261 57.3662)
		(width 0.2032)
		(layer "In2.Cu")
		(net "LED2")
	)
	(segment
		(start 189.85837 126.65839)
		(end 193.31202 123.20475)
		(width 0.2032)
		(layer "In2.Cu")
		(net "LED2")
	)
	(segment
		(start 90.0157 115.4182)
		(end 103.4137 128.8162)
		(width 0.2032)
		(layer "In2.Cu")
		(net "LED2")
	)
	(segment
		(start 168.4261 90.0162)
		(end 168.5511 89.8912)
		(width 0.2032)
		(layer "F.Cu")
		(net "GND")
	)
	(segment
		(start 167.826 135.5286)
		(end 167.826 134.28368)
		(width 0.2032)
		(layer "F.Cu")
		(net "GND")
	)
	(segment
		(start 217.91544 78.6162)
		(end 217.92077 78.61087)
		(width 0.254)
		(layer "F.Cu")
		(net "GND")
	)
	(segment
		(start 177.32586 93.86847)
		(end 177.34922 93.89184)
		(width 0.2032)
		(layer "F.Cu")
		(net "GND")
	)
	(segment
		(start 84.8761 121.17119)
		(end 85.1261 120.92119)
		(width 0.2032)
		(layer "F.Cu")
		(net "GND")
	)
	(segment
		(start 189.6386 85.4662)
		(end 189.81668 85.4662)
		(width 0.254)
		(layer "F.Cu")
		(net "GND")
	)
	(segment
		(start 211.77089 77.6622)
		(end 211.8801 77.6622)
		(width 0.254)
		(layer "F.Cu")
		(net "GND")
	)
	(segment
		(start 194.8761 84.5786)
		(end 195.1511 84.8536)
		(width 0.2032)
		(layer "F.Cu")
		(net "GND")
	)
	(segment
		(start 142.78298 114.44892)
		(end 143.16077 114.8267)
		(width 0.2032)
		(layer "F.Cu")
		(net "GND")
	)
	(segment
		(start 233.8261 118.6162)
		(end 234.1261 118.9162)
		(width 0.254)
		(layer "F.Cu")
		(net "GND")
	)
	(segment
		(start 174.82573 93.86847)
		(end 174.8491 93.89184)
		(width 0.2032)
		(layer "F.Cu")
		(net "GND")
	)
	(segment
		(start 222.89164 78.8162)
		(end 222.89164 78.03695)
		(width 0.254)
		(layer "F.Cu")
		(net "GND")
	)
	(segment
		(start 222.9761 77.1162)
		(end 222.9761 77.02829)
		(width 0.254)
		(layer "F.Cu")
		(net "GND")
	)
	(segment
		(start 222.9761 77.02829)
		(end 223.60697 76.39742)
		(width 0.254)
		(layer "F.Cu")
		(net "GND")
	)
	(segment
		(start 174.32611 129.72861)
		(end 174.32612 129.72861)
		(width 0.2032)
		(layer "F.Cu")
		(net "GND")
	)
	(segment
		(start 198.13374 106.82097)
		(end 199.35577 106.82097)
		(width 0.2032)
		(layer "F.Cu")
		(net "GND")
	)
	(segment
		(start 228.7611 112.4812)
		(end 230.4261 112.4812)
		(width 0.254)
		(layer "F.Cu")
		(net "GND")
	)
	(segment
		(start 85.37393 87.36403)
		(end 85.62176 87.1162)
		(width 0.254)
		(layer "F.Cu")
		(net "GND")
	)
	(segment
		(start 77.3261 64.5162)
		(end 77.3261 63.1162)
		(width 0.762)
		(layer "F.Cu")
		(net "GND")
	)
	(segment
		(start 213.4261 129.49476)
		(end 214.04753 129.49476)
		(width 0.254)
		(layer "F.Cu")
		(net "GND")
	)
	(segment
		(start 151.54502 80.19267)
		(end 151.54502 77.94847)
		(width 0.762)
		(layer "F.Cu")
		(net "GND")
	)
	(segment
		(start 89.3761 90.38978)
		(end 89.3921 90.40578)
		(width 0.2032)
		(layer "F.Cu")
		(net "GND")
	)
	(segment
		(start 151.71732 114.83567)
		(end 151.74069 114.8123)
		(width 0.2032)
		(layer "F.Cu")
		(net "GND")
	)
	(segment
		(start 80.3761 126.5662)
		(end 80.4261 126.6162)
		(width 0.2032)
		(layer "F.Cu")
		(net "GND")
	)
	(segment
		(start 177.3011 97.16189)
		(end 177.30249 97.16327)
		(width 0.2032)
		(layer "F.Cu")
		(net "GND")
	)
	(segment
		(start 167.32588 95.09939)
		(end 167.32588 93.86847)
		(width 0.2032)
		(layer "F.Cu")
		(net "GND")
	)
	(segment
		(start 88.1261 81.1162)
		(end 88.1261 80.02861)
		(width 0.762)
		(layer "F.Cu")
		(net "GND")
	)
	(segment
		(start 115.50423 157.71574)
		(end 115.5461 157.7576)
		(width 0.508)
		(layer "F.Cu")
		(net "GND")
	)
	(segment
		(start 191.5661 89.0162)
		(end 191.5661 88.2762)
		(width 0.254)
		(layer "F.Cu")
		(net "GND")
	)
	(segment
		(start 150.40663 114.83567)
		(end 151.71732 114.83567)
		(width 0.2032)
		(layer "F.Cu")
		(net "GND")
	)
	(segment
		(start 217.92077 78.61087)
		(end 217.9261 78.6162)
		(width 0.254)
		(layer "F.Cu")
		(net "GND")
	)
	(segment
		(start 127.0261 85.9162)
		(end 128.0261 85.9162)
		(width 0.2032)
		(layer "F.Cu")
		(net "GND")
	)
	(segment
		(start 123.2285 154.3036)
		(end 123.52608 154.60118)
		(width 0.508)
		(layer "F.Cu")
		(net "GND")
	)
	(segment
		(start 239.38037 63.59799)
		(end 239.4261 63.64371)
		(width 0.254)
		(layer "F.Cu")
		(net "GND")
	)
	(segment
		(start 207.7261 135.5162)
		(end 207.7261 133.0162)
		(width 0.762)
		(layer "F.Cu")
		(net "GND")
	)
	(segment
		(start 211.6221 77.81099)
		(end 211.77089 77.6622)
		(width 0.254)
		(layer "F.Cu")
		(net "GND")
	)
	(segment
		(start 85.8761 80.0786)
		(end 85.8761 80.0786)
		(width 0.254)
		(layer "F.Cu")
		(net "GND")
	)
	(segment
		(start 80.3761 100.44103)
		(end 80.3761 99.5662)
		(width 0.2032)
		(layer "F.Cu")
		(net "GND")
	)
	(segment
		(start 204.0261 130.0162)
		(end 204.6261 129.4162)
		(width 0.254)
		(layer "F.Cu")
		(net "GND")
	)
	(segment
		(start 193.5245 86.4302)
		(end 194.1261 85.8286)
		(width 0.2032)
		(layer "F.Cu")
		(net "GND")
	)
	(segment
		(start 177.34922 95.20172)
		(end 177.3761 95.2286)
		(width 0.2032)
		(layer "F.Cu")
		(net "GND")
	)
	(segment
		(start 150.28597 112.30893)
		(end 151.75053 112.30893)
		(width 0.254)
		(layer "F.Cu")
		(net "GND")
	)
	(segment
		(start 94.7761 75.3286)
		(end 96.1261 75.3286)
		(width 0.762)
		(layer "F.Cu")
		(net "GND")
	)
	(segment
		(start 199.35576 116.82096)
		(end 199.3634 116.81331)
		(width 0.2032)
		(layer "F.Cu")
		(net "GND")
	)
	(segment
		(start 148.74187 117.31039)
		(end 149.07013 116.98213)
		(width 0.254)
		(layer "F.Cu")
		(net "GND")
	)
	(segment
		(start 191.5661 88.2762)
		(end 191.7261 88.1162)
		(width 0.254)
		(layer "F.Cu")
		(net "GND")
	)
	(segment
		(start 149.16456 107.30894)
		(end 149.1671 107.3064)
		(width 0.254)
		(layer "F.Cu")
		(net "GND")
	)
	(segment
		(start 234.1261 62.6162)
		(end 234.2261 62.5162)
		(width 0.762)
		(layer "F.Cu")
		(net "GND")
	)
	(segment
		(start 150.25041 122.30891)
		(end 151.75053 122.30891)
		(width 0.254)
		(layer "F.Cu")
		(net "GND")
	)
	(segment
		(start 120.53059 157.74211)
		(end 120.53059 154.37508)
		(width 0.508)
		(layer "F.Cu")
		(net "GND")
	)
	(segment
		(start 174.8491 95.2016)
		(end 174.8491 93.89184)
		(width 0.2032)
		(layer "F.Cu")
		(net "GND")
	)
	(segment
		(start 147.70203 112.3102)
		(end 149.0909 112.3102)
		(width 0.254)
		(layer "F.Cu")
		(net "GND")
	)
	(segment
		(start 198.1261 121.8286)
		(end 198.13375 121.82095)
		(width 0.2032)
		(layer "F.Cu")
		(net "GND")
	)
	(segment
		(start 74.3761 111.1162)
		(end 74.3761 110.0912)
		(width 0.2032)
		(layer "F.Cu")
		(net "GND")
	)
	(segment
		(start 184.2761 86.4662)
		(end 185.0136 86.4662)
		(width 0.254)
		(layer "F.Cu")
		(net "GND")
	)
	(segment
		(start 124.3596 85.29254)
		(end 124.98327 85.9162)
		(width 0.2032)
		(layer "F.Cu")
		(net "GND")
	)
	(segment
		(start 174.8091 96.4036)
		(end 174.81742 96.41192)
		(width 0.2032)
		(layer "F.Cu")
		(net "GND")
	)
	(segment
		(start 82.5761 83.1162)
		(end 82.5761 82.6662)
		(width 0.2032)
		(layer "F.Cu")
		(net "GND")
	)
	(segment
		(start 228.2261 113.8162)
		(end 228.3261 113.7162)
		(width 0.254)
		(layer "F.Cu")
		(net "GND")
	)
	(segment
		(start 118.54609 157.7576)
		(end 118.54609 155.05901)
		(width 0.508)
		(layer "F.Cu")
		(net "GND")
	)
	(segment
		(start 130.1261 83.5286)
		(end 130.1261 82.0786)
		(width 0.2032)
		(layer "F.Cu")
		(net "GND")
	)
	(segment
		(start 74.3761 124.3662)
		(end 74.3761 123.3412)
		(width 0.2032)
		(layer "F.Cu")
		(net "GND")
	)
	(segment
		(start 178.3761 87.0786)
		(end 179.8761 87.0786)
		(width 0.2032)
		(layer "F.Cu")
		(net "GND")
	)
	(segment
		(start 177.30249 97.89488)
		(end 177.30249 97.16327)
		(width 0.2032)
		(layer "F.Cu")
		(net "GND")
	)
	(segment
		(start 118.03129 154.41678)
		(end 118.34343 154.65301)
		(width 0.508)
		(layer "F.Cu")
		(net "GND")
	)
	(segment
		(start 233.5261 67.1162)
		(end 233.5261 65.8162)
		(width 0.762)
		(layer "F.Cu")
		(net "GND")
	)
	(segment
		(start 216.2261 66.5162)
		(end 216.2261 65.2162)
		(width 0.762)
		(layer "F.Cu")
		(net "GND")
	)
	(segment
		(start 172.83584 134.15826)
		(end 172.8907 134.1034)
		(width 0.254)
		(layer "F.Cu")
		(net "GND")
	)
	(segment
		(start 79.11797 85.0162)
		(end 79.9261 85.0162)
		(width 0.2032)
		(layer "F.Cu")
		(net "GND")
	)
	(segment
		(start 195.31363 111.81332)
		(end 195.32127 111.82096)
		(width 0.2032)
		(layer "F.Cu")
		(net "GND")
	)
	(segment
		(start 167.32588 97.91825)
		(end 167.32588 96.68381)
		(width 0.2032)
		(layer "F.Cu")
		(net "GND")
	)
	(segment
		(start 115.2761 154.3286)
		(end 115.50423 154.55673)
		(width 0.508)
		(layer "F.Cu")
		(net "GND")
	)
	(segment
		(start 69.8761 129.1162)
		(end 69.93108 129.1162)
		(width 0.2032)
		(layer "F.Cu")
		(net "GND")
	)
	(segment
		(start 196.3261 89.6162)
		(end 197.7261 91.0162)
		(width 0.254)
		(layer "F.Cu")
		(net "GND")
	)
	(segment
		(start 82.3761 88.6162)
		(end 82.6261 88.8662)
		(width 0.254)
		(layer "F.Cu")
		(net "GND")
	)
	(segment
		(start 148.42598 119.80676)
		(end 148.42954 119.8032)
		(width 0.254)
		(layer "F.Cu")
		(net "GND")
	)
	(segment
		(start 195.337 119.3368)
		(end 196.28372 119.3368)
		(width 0.2032)
		(layer "F.Cu")
		(net "GND")
	)
	(segment
		(start 85.62176 87.1162)
		(end 87.0511 87.1162)
		(width 0.254)
		(layer "F.Cu")
		(net "GND")
	)
	(segment
		(start 89.3761 84.7912)
		(end 89.3761 83.1162)
		(width 0.2032)
		(layer "F.Cu")
		(net "GND")
	)
	(segment
		(start 219.7261 76.6162)
		(end 219.8761 76.7662)
		(width 0.254)
		(layer "F.Cu")
		(net "GND")
	)
	(segment
		(start 222.9261 81.2162)
		(end 223.0761 81.0662)
		(width 0.254)
		(layer "F.Cu")
		(net "GND")
	)
	(segment
		(start 204.2261 110.6162)
		(end 205.0261 111.4162)
		(width 0.2032)
		(layer "F.Cu")
		(net "GND")
	)
	(segment
		(start 204.7261 108.7162)
		(end 205.26056 109.25066)
		(width 0.254)
		(layer "F.Cu")
		(net "GND")
	)
	(segment
		(start 170.32612 131.47882)
		(end 170.32612 129.89354)
		(width 0.2032)
		(layer "F.Cu")
		(net "GND")
	)
	(segment
		(start 164.82575 97.91825)
		(end 164.82575 96.67389)
		(width 0.2032)
		(layer "F.Cu")
		(net "GND")
	)
	(segment
		(start 74.3761 138.1162)
		(end 74.3761 137.0912)
		(width 0.2032)
		(layer "F.Cu")
		(net "GND")
	)
	(segment
		(start 196.57112 119.6242)
		(end 196.6261 119.6242)
		(width 0.2032)
		(layer "F.Cu")
		(net "GND")
	)
	(segment
		(start 94.5761 75.1286)
		(end 94.7761 75.3286)
		(width 0.2032)
		(layer "F.Cu")
		(net "GND")
	)
	(segment
		(start 218.06876 57.46478)
		(end 218.1261 57.40744)
		(width 0.762)
		(layer "F.Cu")
		(net "GND")
	)
	(segment
		(start 122.8745 154.3036)
		(end 123.2285 154.3036)
		(width 0.508)
		(layer "F.Cu")
		(net "GND")
	)
	(segment
		(start 150.3761 114.8662)
		(end 150.40663 114.83567)
		(width 0.2032)
		(layer "F.Cu")
		(net "GND")
	)
	(segment
		(start 199.35575 121.82095)
		(end 199.3634 121.8133)
		(width 0.2032)
		(layer "F.Cu")
		(net "GND")
	)
	(segment
		(start 198.13368 109.32103)
		(end 199.35583 109.32103)
		(width 0.2032)
		(layer "F.Cu")
		(net "GND")
	)
	(segment
		(start 228.4261 130.7162)
		(end 228.4261 130.6812)
		(width 0.254)
		(layer "F.Cu")
		(net "GND")
	)
	(segment
		(start 190.8261 87.4562)
		(end 191.70015 87.4562)
		(width 0.254)
		(layer "F.Cu")
		(net "GND")
	)
	(segment
		(start 151.70796 107.35152)
		(end 151.75053 107.30894)
		(width 0.254)
		(layer "F.Cu")
		(net "GND")
	)
	(segment
		(start 150.2339 122.2924)
		(end 150.25041 122.30891)
		(width 0.254)
		(layer "F.Cu")
		(net "GND")
	)
	(segment
		(start 114.5461 154.3286)
		(end 115.2761 154.3286)
		(width 0.508)
		(layer "F.Cu")
		(net "GND")
	)
	(segment
		(start 231.4261 75.2762)
		(end 231.4261 74.82811)
		(width 0.254)
		(layer "F.Cu")
		(net "GND")
	)
	(segment
		(start 237.2261 68.6162)
		(end 239.38328 68.6162)
		(width 0.254)
		(layer "F.Cu")
		(net "GND")
	)
	(segment
		(start 149.07013 116.98213)
		(end 149.11137 116.98213)
		(width 0.254)
		(layer "F.Cu")
		(net "GND")
	)
	(segment
		(start 180.3261 131.47882)
		(end 180.3261 129.7286)
		(width 0.2032)
		(layer "F.Cu")
		(net "GND")
	)
	(segment
		(start 88.1261 80.02861)
		(end 88.1261 80.0286)
		(width 0.254)
		(layer "F.Cu")
		(net "GND")
	)
	(segment
		(start 221.9637 72.6786)
		(end 223.6261 72.6786)
		(width 0.762)
		(layer "F.Cu")
		(net "GND")
	)
	(segment
		(start 164.82575 95.17895)
		(end 164.82575 93.86847)
		(width 0.2032)
		(layer "F.Cu")
		(net "GND")
	)
	(segment
		(start 214.04753 129.49476)
		(end 214.3261 129.2162)
		(width 0.254)
		(layer "F.Cu")
		(net "GND")
	)
	(segment
		(start 126.9761 154.1786)
		(end 126.99598 154.1786)
		(width 0.508)
		(layer "F.Cu")
		(net "GND")
	)
	(segment
		(start 196.62252 114.31702)
		(end 196.6261 114.3206)
		(width 0.2032)
		(layer "F.Cu")
		(net "GND")
	)
	(segment
		(start 81.3761 93.6162)
		(end 81.3761 92.6162)
		(width 0.254)
		(layer "F.Cu")
		(net "GND")
	)
	(segment
		(start 196.61853 109.32103)
		(end 196.6261 109.3286)
		(width 0.2032)
		(layer "F.Cu")
		(net "GND")
	)
	(segment
		(start 82.6261 94.8662)
		(end 83.7011 94.8662)
		(width 0.254)
		(layer "F.Cu")
		(net "GND")
	)
	(segment
		(start 79.3761 112.8662)
		(end 80.5761 112.8662)
		(width 0.2032)
		(layer "F.Cu")
		(net "GND")
	)
	(segment
		(start 127.44472 156.99725)
		(end 127.52607 157.0786)
		(width 0.508)
		(layer "F.Cu")
		(net "GND")
	)
	(segment
		(start 70.03108 129.2162)
		(end 71.1261 129.2162)
		(width 0.2032)
		(layer "F.Cu")
		(net "GND")
	)
	(segment
		(start 180.1261 86.8286)
		(end 180.1261 86.01239)
		(width 0.2032)
		(layer "F.Cu")
		(net "GND")
	)
	(segment
		(start 193.1011 86.5036)
		(end 193.1745 86.4302)
		(width 0.2032)
		(layer "F.Cu")
		(net "GND")
	)
	(segment
		(start 165.32613 131.47882)
		(end 165.32613 129.72863)
		(width 0.2032)
		(layer "F.Cu")
		(net "GND")
	)
	(segment
		(start 91.3261 63.5162)
		(end 91.4261 63.6162)
		(width 0.762)
		(layer "F.Cu")
		(net "GND")
	)
	(segment
		(start 177.34922 95.20172)
		(end 177.34922 93.89184)
		(width 0.2032)
		(layer "F.Cu")
		(net "GND")
	)
	(segment
		(start 80.3761 100.44103)
		(end 80.54375 100.60868)
		(width 0.2032)
		(layer "F.Cu")
		(net "GND")
	)
	(segment
		(start 202.4911 91.4512)
		(end 202.4911 89.9162)
		(width 0.254)
		(layer "F.Cu")
		(net "GND")
	)
	(segment
		(start 82.42611 87.6162)
		(end 83.1261 87.6162)
		(width 0.254)
		(layer "F.Cu")
		(net "GND")
	)
	(segment
		(start 177.32611 131.47882)
		(end 177.32611 129.88358)
		(width 0.2032)
		(layer "F.Cu")
		(net "GND")
	)
	(segment
		(start 212.29775 114.76641)
		(end 212.94753 115.4162)
		(width 0.254)
		(layer "F.Cu")
		(net "GND")
	)
	(segment
		(start 237.3261 61.6912)
		(end 237.3261 60.77227)
		(width 0.254)
		(layer "F.Cu")
		(net "GND")
	)
	(segment
		(start 147.69091 114.8123)
		(end 147.71428 114.83567)
		(width 0.2032)
		(layer "F.Cu")
		(net "GND")
	)
	(segment
		(start 150.22434 117.028)
		(end 150.50876 117.31242)
		(width 0.254)
		(layer "F.Cu")
		(net "GND")
	)
	(segment
		(start 85.1261 120.92119)
		(end 85.1261 120.8662)
		(width 0.2032)
		(layer "F.Cu")
		(net "GND")
	)
	(segment
		(start 83.1261 87.6162)
		(end 83.3261 87.8162)
		(width 0.254)
		(layer "F.Cu")
		(net "GND")
	)
	(segment
		(start 178.82598 131.47882)
		(end 178.82598 129.98371)
		(width 0.2032)
		(layer "F.Cu")
		(net "GND")
	)
	(segment
		(start 175.82599 129.8837)
		(end 175.9261 129.78359)
		(width 0.2032)
		(layer "F.Cu")
		(net "GND")
	)
	(segment
		(start 237.9011 70.6912)
		(end 238.1261 70.9162)
		(width 0.254)
		(layer "F.Cu")
		(net "GND")
	)
	(segment
		(start 127.44472 156.99725)
		(end 127.44472 154.64722)
		(width 0.508)
		(layer "F.Cu")
		(net "GND")
	)
	(segment
		(start 198.1261 114.3206)
		(end 198.12968 114.31702)
		(width 0.2032)
		(layer "F.Cu")
		(net "GND")
	)
	(segment
		(start 164.82575 96.67389)
		(end 165.0511 96.44854)
		(width 0.2032)
		(layer "F.Cu")
		(net "GND")
	)
	(segment
		(start 91.7011 87.1162)
		(end 92.64983 87.1162)
		(width 0.2032)
		(layer "F.Cu")
		(net "GND")
	)
	(segment
		(start 214.5261 68.8162)
		(end 215.9261 68.8162)
		(width 0.762)
		(layer "F.Cu")
		(net "GND")
	)
	(segment
		(start 172.82599 130.83087)
		(end 172.82599 129.86995)
		(width 0.254)
		(layer "F.Cu")
		(net "GND")
	)
	(segment
		(start 169.82574 95.02326)
		(end 169.9761 95.17361)
		(width 0.2032)
		(layer "F.Cu")
		(net "GND")
	)
	(segment
		(start 221.3681 64.6162)
		(end 222.02491 64.6162)
		(width 0.762)
		(layer "F.Cu")
		(net "GND")
	)
	(segment
		(start 82.3761 87.5662)
		(end 82.42611 87.6162)
		(width 0.254)
		(layer "F.Cu")
		(net "GND")
	)
	(segment
		(start 230.39336 136.44894)
		(end 230.39336 135.04894)
		(width 0.254)
		(layer "F.Cu")
		(net "GND")
	)
	(segment
		(start 136.26304 116.53826)
		(end 136.32038 116.48092)
		(width 0.2032)
		(layer "F.Cu")
		(net "GND")
	)
	(segment
		(start 222.02491 64.6162)
		(end 222.08731 64.6786)
		(width 0.762)
		(layer "F.Cu")
		(net "GND")
	)
	(segment
		(start 233.3261 57.5162)
		(end 233.7261 57.9162)
		(width 0.762)
		(layer "F.Cu")
		(net "GND")
	)
	(segment
		(start 174.8491 95.2016)
		(end 174.8761 95.2286)
		(width 0.2032)
		(layer "F.Cu")
		(net "GND")
	)
	(segment
		(start 177.30249 97.89488)
		(end 177.32586 97.91825)
		(width 0.2032)
		(layer "F.Cu")
		(net "GND")
	)
	(segment
		(start 83.8761 107.3662)
		(end 84.6261 107.3662)
		(width 0.2032)
		(layer "F.Cu")
		(net "GND")
	)
	(segment
		(start 195.32126 106.82097)
		(end 196.61847 106.82097)
		(width 0.2032)
		(layer "F.Cu")
		(net "GND")
	)
	(segment
		(start 167.4001 95.2286)
		(end 167.4001 95.17361)
		(width 0.2032)
		(layer "F.Cu")
		(net "GND")
	)
	(segment
		(start 217.9261 78.6162)
		(end 218.1261 78.8162)
		(width 0.254)
		(layer "F.Cu")
		(net "GND")
	)
	(segment
		(start 225.6261 127.2162)
		(end 225.6261 125.85066)
		(width 0.254)
		(layer "F.Cu")
		(net "GND")
	)
	(segment
		(start 167.32588 96.68381)
		(end 167.49809 96.5116)
		(width 0.2032)
		(layer "F.Cu")
		(net "GND")
	)
	(segment
		(start 211.8801 77.6622)
		(end 212.5261 77.0162)
		(width 0.254)
		(layer "F.Cu")
		(net "GND")
	)
	(segment
		(start 153.9261 77.9669)
		(end 154.0068 77.9669)
		(width 0.762)
		(layer "F.Cu")
		(net "GND")
	)
	(segment
		(start 177.32611 129.88358)
		(end 177.4261 129.78359)
		(width 0.2032)
		(layer "F.Cu")
		(net "GND")
	)
	(segment
		(start 195.1511 85.8536)
		(end 195.1511 84.8536)
		(width 0.2032)
		(layer "F.Cu")
		(net "GND")
	)
	(segment
		(start 175.9261 129.78359)
		(end 175.9261 129.7286)
		(width 0.2032)
		(layer "F.Cu")
		(net "GND")
	)
	(segment
		(start 123.52608 157.0786)
		(end 123.52608 154.60118)
		(width 0.508)
		(layer "F.Cu")
		(net "GND")
	)
	(segment
		(start 195.31363 106.81333)
		(end 195.32126 106.82097)
		(width 0.2032)
		(layer "F.Cu")
		(net "GND")
	)
	(segment
		(start 230.94871 74.35073)
		(end 231.4261 74.82811)
		(width 0.254)
		(layer "F.Cu")
		(net "GND")
	)
	(segment
		(start 198.1261 109.3286)
		(end 198.13368 109.32103)
		(width 0.2032)
		(layer "F.Cu")
		(net "GND")
	)
	(segment
		(start 197.7261 91.0162)
		(end 198.3861 91.0162)
		(width 0.254)
		(layer "F.Cu")
		(net "GND")
	)
	(segment
		(start 195.31363 116.81331)
		(end 195.32127 116.82096)
		(width 0.2032)
		(layer "F.Cu")
		(net "GND")
	)
	(segment
		(start 86.3761 67.8286)
		(end 88.3761 67.8286)
		(width 0.762)
		(layer "F.Cu")
		(net "GND")
	)
	(segment
		(start 167.826 131.47882)
		(end 167.82605 131.47877)
		(width 0.2032)
		(layer "F.Cu")
		(net "GND")
	)
	(segment
		(start 195.31363 114.31344)
		(end 195.31721 114.31702)
		(width 0.2032)
		(layer "F.Cu")
		(net "GND")
	)
	(segment
		(start 83.29027 81.95203)
		(end 84.48221 81.95203)
		(width 0.2032)
		(layer "F.Cu")
		(net "GND")
	)
	(segment
		(start 85.8761 81.1162)
		(end 85.8761 80.0786)
		(width 0.762)
		(layer "F.Cu")
		(net "GND")
	)
	(segment
		(start 201.58859 126.45771)
		(end 201.8301 126.2162)
		(width 0.254)
		(layer "F.Cu")
		(net "GND")
	)
	(segment
		(start 225.1261 130.7162)
		(end 226.5261 130.7162)
		(width 0.254)
		(layer "F.Cu")
		(net "GND")
	)
	(segment
		(start 122.8527 154.2818)
		(end 124.22214 154.2818)
		(width 0.508)
		(layer "F.Cu")
		(net "GND")
	)
	(segment
		(start 193.93815 142.80442)
		(end 193.96136 142.82763)
		(width 0.254)
		(layer "F.Cu")
		(net "GND")
	)
	(segment
		(start 89.3921 91.1162)
		(end 89.3921 90.40578)
		(width 0.2032)
		(layer "F.Cu")
		(net "GND")
	)
	(segment
		(start 169.82592 97.91807)
		(end 169.82592 96.40378)
		(width 0.2032)
		(layer "F.Cu")
		(net "GND")
	)
	(segment
		(start 74.3761 93.6412)
		(end 74.3761 92.6162)
		(width 0.2032)
		(layer "F.Cu")
		(net "GND")
	)
	(segment
		(start 179.7931 96.39385)
		(end 179.80941 96.41016)
		(width 0.2032)
		(layer "F.Cu")
		(net "GND")
	)
	(segment
		(start 130.8261 86.2162)
		(end 131.1261 86.5162)
		(width 0.2032)
		(layer "F.Cu")
		(net "GND")
	)
	(segment
		(start 198.1261 119.6242)
		(end 198.18109 119.6242)
		(width 0.2032)
		(layer "F.Cu")
		(net "GND")
	)
	(segment
		(start 189.6386 86.9662)
		(end 190.05015 86.9662)
		(width 0.254)
		(layer "F.Cu")
		(net "GND")
	)
	(segment
		(start 169.9761 95.2286)
		(end 169.9761 95.17361)
		(width 0.2032)
		(layer "F.Cu")
		(net "GND")
	)
	(segment
		(start 147.70076 107.30894)
		(end 149.16456 107.30894)
		(width 0.254)
		(layer "F.Cu")
		(net "GND")
	)
	(segment
		(start 234.7261 74.5762)
		(end 234.7261 73.66478)
		(width 0.254)
		(layer "F.Cu")
		(net "GND")
	)
	(segment
		(start 192.45618 138.98121)
		(end 192.70976 138.72763)
		(width 0.254)
		(layer "F.Cu")
		(net "GND")
	)
	(segment
		(start 225.6261 125.85066)
		(end 225.76056 125.7162)
		(width 0.254)
		(layer "F.Cu")
		(net "GND")
	)
	(segment
		(start 204.7261 108.7162)
		(end 204.7261 108.4162)
		(width 0.254)
		(layer "F.Cu")
		(net "GND")
	)
	(segment
		(start 179.80941 97.90194)
		(end 179.82572 97.91825)
		(width 0.2032)
		(layer "F.Cu")
		(net "GND")
	)
	(segment
		(start 150.3609 109.821)
		(end 150.37309 109.80881)
		(width 0.254)
		(layer "F.Cu")
		(net "GND")
	)
	(segment
		(start 147.70076 122.30891)
		(end 149.07439 122.30891)
		(width 0.254)
		(layer "F.Cu")
		(net "GND")
	)
	(segment
		(start 83.9511 108.3662)
		(end 84.6261 108.3662)
		(width 0.2032)
		(layer "F.Cu")
		(net "GND")
	)
	(segment
		(start 179.8761 87.0786)
		(end 180.1261 86.8286)
		(width 0.2032)
		(layer "F.Cu")
		(net "GND")
	)
	(segment
		(start 195.32128 121.82095)
		(end 196.61845 121.82095)
		(width 0.2032)
		(layer "F.Cu")
		(net "GND")
	)
	(segment
		(start 198.1261 106.8286)
		(end 198.13374 106.82097)
		(width 0.2032)
		(layer "F.Cu")
		(net "GND")
	)
	(segment
		(start 80.3761 141.6162)
		(end 80.3761 140.3162)
		(width 0.2032)
		(layer "F.Cu")
		(net "GND")
	)
	(segment
		(start 192.41494 138.98121)
		(end 192.45618 138.98121)
		(width 0.254)
		(layer "F.Cu")
		(net "GND")
	)
	(segment
		(start 232.5261 80.0162)
		(end 232.7261 79.8162)
		(width 0.254)
		(layer "F.Cu")
		(net "GND")
	)
	(segment
		(start 178.82598 129.98371)
		(end 179.0261 129.78359)
		(width 0.2032)
		(layer "F.Cu")
		(net "GND")
	)
	(segment
		(start 196.28372 119.3368)
		(end 196.57112 119.6242)
		(width 0.2032)
		(layer "F.Cu")
		(net "GND")
	)
	(segment
		(start 195.31721 114.31702)
		(end 196.62252 114.31702)
		(width 0.2032)
		(layer "F.Cu")
		(net "GND")
	)
	(segment
		(start 92.66568 87.13205)
		(end 93.3761 87.13205)
		(width 0.2032)
		(layer "F.Cu")
		(net "GND")
	)
	(segment
		(start 150.1831 117.028)
		(end 150.22434 117.028)
		(width 0.254)
		(layer "F.Cu")
		(net "GND")
	)
	(segment
		(start 150.37309 109.80881)
		(end 151.75053 109.80881)
		(width 0.254)
		(layer "F.Cu")
		(net "GND")
	)
	(segment
		(start 198.46849 119.3368)
		(end 199.34004 119.3368)
		(width 0.2032)
		(layer "F.Cu")
		(net "GND")
	)
	(segment
		(start 84.1261 87.8162)
		(end 84.9261 87.8162)
		(width 0.254)
		(layer "F.Cu")
		(net "GND")
	)
	(segment
		(start 150.30451 119.80879)
		(end 151.75053 119.80879)
		(width 0.254)
		(layer "F.Cu")
		(net "GND")
	)
	(segment
		(start 130.1261 83.5286)
		(end 130.1761 83.5786)
		(width 0.2032)
		(layer "F.Cu")
		(net "GND")
	)
	(segment
		(start 147.70076 112.30893)
		(end 147.70203 112.3102)
		(width 0.254)
		(layer "F.Cu")
		(net "GND")
	)
	(segment
		(start 190.05015 86.9662)
		(end 190.54014 87.4562)
		(width 0.254)
		(layer "F.Cu")
		(net "GND")
	)
	(segment
		(start 74.3761 134.1412)
		(end 74.3761 133.1162)
		(width 0.2032)
		(layer "F.Cu")
		(net "GND")
	)
	(segment
		(start 239.38328 68.6162)
		(end 239.3962 68.62912)
		(width 0.254)
		(layer "F.Cu")
		(net "GND")
	)
	(segment
		(start 204.6261 129.4162)
		(end 204.89295 129.4162)
		(width 0.254)
		(layer "F.Cu")
		(net "GND")
	)
	(segment
		(start 120.53059 154.37508)
		(end 120.54609 154.35959)
		(width 0.508)
		(layer "F.Cu")
		(net "GND")
	)
	(segment
		(start 190.20466 81.97346)
		(end 190.20559 81.97253)
		(width 0.254)
		(layer "F.Cu")
		(net "GND")
	)
	(segment
		(start 217.8761 61.8662)
		(end 217.8761 60.5786)
		(width 0.762)
		(layer "F.Cu")
		(net "GND")
	)
	(segment
		(start 174.81742 97.90993)
		(end 174.82573 97.91825)
		(width 0.2032)
		(layer "F.Cu")
		(net "GND")
	)
	(segment
		(start 218.1261 78.8162)
		(end 219.2261 78.8162)
		(width 0.254)
		(layer "F.Cu")
		(net "GND")
	)
	(segment
		(start 132.2261 88.5162)
		(end 132.8737 87.8686)
		(width 0.2032)
		(layer "F.Cu")
		(net "GND")
	)
	(segment
		(start 82.5761 82.6662)
		(end 83.29027 81.95203)
		(width 0.2032)
		(layer "F.Cu")
		(net "GND")
	)
	(segment
		(start 128.43222 156.98475)
		(end 128.52607 157.0786)
		(width 0.508)
		(layer "F.Cu")
		(net "GND")
	)
	(segment
		(start 122.28112 87.9836)
		(end 122.6261 88.32858)
		(width 0.2032)
		(layer "F.Cu")
		(net "GND")
	)
	(segment
		(start 150.2847 119.8286)
		(end 150.30451 119.80879)
		(width 0.254)
		(layer "F.Cu")
		(net "GND")
	)
	(segment
		(start 147.70279 119.80676)
		(end 148.42598 119.80676)
		(width 0.254)
		(layer "F.Cu")
		(net "GND")
	)
	(segment
		(start 192.53815 142.80442)
		(end 193.93815 142.80442)
		(width 0.254)
		(layer "F.Cu")
		(net "GND")
	)
	(segment
		(start 206.0261 133.0162)
		(end 207.7261 133.0162)
		(width 0.762)
		(layer "F.Cu")
		(net "GND")
	)
	(segment
		(start 232.7261 79.8162)
		(end 232.7261 79.1162)
		(width 0.254)
		(layer "F.Cu")
		(net "GND")
	)
	(segment
		(start 141.66107 114.44892)
		(end 142.78298 114.44892)
		(width 0.2032)
		(layer "F.Cu")
		(net "GND")
	)
	(segment
		(start 195.31363 109.31345)
		(end 195.3212 109.32103)
		(width 0.2032)
		(layer "F.Cu")
		(net "GND")
	)
	(segment
		(start 195.1261 85.8286)
		(end 195.1511 85.8536)
		(width 0.2032)
		(layer "F.Cu")
		(net "GND")
	)
	(segment
		(start 199.35576 111.82096)
		(end 199.3634 111.81332)
		(width 0.2032)
		(layer "F.Cu")
		(net "GND")
	)
	(segment
		(start 228.3261 112.9162)
		(end 228.7611 112.4812)
		(width 0.254)
		(layer "F.Cu")
		(net "GND")
	)
	(segment
		(start 150.2847 112.3102)
		(end 150.28597 112.30893)
		(width 0.254)
		(layer "F.Cu")
		(net "GND")
	)
	(segment
		(start 189.81668 85.4662)
		(end 190.55001 84.73286)
		(width 0.254)
		(layer "F.Cu")
		(net "GND")
	)
	(segment
		(start 203.7261 111.34963)
		(end 203.7261 111.1162)
		(width 0.254)
		(layer "F.Cu")
		(net "GND")
	)
	(segment
		(start 172.34923 95.19373)
		(end 172.3841 95.2286)
		(width 0.2032)
		(layer "F.Cu")
		(net "GND")
	)
	(segment
		(start 83.7011 135.3662)
		(end 84.3761 135.3662)
		(width 0.2032)
		(layer "F.Cu")
		(net "GND")
	)
	(segment
		(start 205.0261 111.4162)
		(end 205.24754 111.4162)
		(width 0.2032)
		(layer "F.Cu")
		(net "GND")
	)
	(segment
		(start 239.69164 71.9162)
		(end 239.69164 71.60334)
		(width 0.254)
		(layer "F.Cu")
		(net "GND")
	)
	(segment
		(start 147.70076 109.80881)
		(end 149.17929 109.80881)
		(width 0.254)
		(layer "F.Cu")
		(net "GND")
	)
	(segment
		(start 172.32587 97.91825)
		(end 172.32587 96.44182)
		(width 0.2032)
		(layer "F.Cu")
		(net "GND")
	)
	(segment
		(start 216.2261 65.2162)
		(end 216.2261 65.2162)
		(width 0.762)
		(layer "F.Cu")
		(net "GND")
	)
	(segment
		(start 122.6261 89.0866)
		(end 122.6261 88.32858)
		(width 0.2032)
		(layer "F.Cu")
		(net "GND")
	)
	(segment
		(start 172.3841 96.38359)
		(end 172.3841 96.3286)
		(width 0.2032)
		(layer "F.Cu")
		(net "GND")
	)
	(segment
		(start 184.2261 86.5162)
		(end 184.2761 86.4662)
		(width 0.254)
		(layer "F.Cu")
		(net "GND")
	)
	(segment
		(start 118.54609 155.05901)
		(end 118.54609 155.05901)
		(width 0.508)
		(layer "F.Cu")
		(net "GND")
	)
	(segment
		(start 235.72353 61.86053)
		(end 235.7261 61.8631)
		(width 0.254)
		(layer "F.Cu")
		(net "GND")
	)
	(segment
		(start 82.6261 89.6162)
		(end 82.6261 88.8662)
		(width 0.254)
		(layer "F.Cu")
		(net "GND")
	)
	(segment
		(start 150.50876 117.31242)
		(end 151.09274 117.31242)
		(width 0.254)
		(layer "F.Cu")
		(net "GND")
	)
	(segment
		(start 127.9511 154.1786)
		(end 128.43222 154.65972)
		(width 0.508)
		(layer "F.Cu")
		(net "GND")
	)
	(segment
		(start 128.43222 156.98475)
		(end 128.43222 154.65972)
		(width 0.508)
		(layer "F.Cu")
		(net "GND")
	)
	(segment
		(start 115.50423 157.71574)
		(end 115.50423 154.55673)
		(width 0.508)
		(layer "F.Cu")
		(net "GND")
	)
	(segment
		(start 231.44754 83.2162)
		(end 231.44754 82.3474)
		(width 0.254)
		(layer "F.Cu")
		(net "GND")
	)
	(segment
		(start 187.5761 88.3662)
		(end 187.5761 87.7787)
		(width 0.254)
		(layer "F.Cu")
		(net "GND")
	)
	(segment
		(start 167.826 134.28368)
		(end 167.9261 134.18359)
		(width 0.2032)
		(layer "F.Cu")
		(net "GND")
	)
	(segment
		(start 170.32612 134.38356)
		(end 170.5261 134.18359)
		(width 0.2032)
		(layer "F.Cu")
		(net "GND")
	)
	(segment
		(start 124.98327 85.9162)
		(end 125.4261 85.9162)
		(width 0.2032)
		(layer "F.Cu")
		(net "GND")
	)
	(segment
		(start 130.2761 87.9162)
		(end 131.0261 88.6662)
		(width 0.2032)
		(layer "F.Cu")
		(net "GND")
	)
	(segment
		(start 169.82592 96.40378)
		(end 169.8261 96.4036)
		(width 0.2032)
		(layer "F.Cu")
		(net "GND")
	)
	(segment
		(start 124.51973 157.07224)
		(end 124.51973 155.99134)
		(width 0.508)
		(layer "F.Cu")
		(net "GND")
	)
	(segment
		(start 219.8761 80.4662)
		(end 219.8761 79.6162)
		(width 0.254)
		(layer "F.Cu")
		(net "GND")
	)
	(segment
		(start 202.8511 106.0162)
		(end 202.8511 105.2412)
		(width 0.254)
		(layer "F.Cu")
		(net "GND")
	)
	(segment
		(start 84.6261 121.6162)
		(end 84.8761 121.3662)
		(width 0.2032)
		(layer "F.Cu")
		(net "GND")
	)
	(segment
		(start 164.8011 95.2036)
		(end 164.82575 95.17895)
		(width 0.2032)
		(layer "F.Cu")
		(net "GND")
	)
	(segment
		(start 84.3761 135.3662)
		(end 84.8761 134.8662)
		(width 0.2032)
		(layer "F.Cu")
		(net "GND")
	)
	(segment
		(start 212.5261 77.0162)
		(end 212.7261 77.0162)
		(width 0.254)
		(layer "F.Cu")
		(net "GND")
	)
	(segment
		(start 237.96122 135.34917)
		(end 238.90342 135.34917)
		(width 0.2032)
		(layer "F.Cu")
		(net "GND")
	)
	(segment
		(start 201.8301 126.2162)
		(end 202.46056 126.2162)
		(width 0.254)
		(layer "F.Cu")
		(net "GND")
	)
	(segment
		(start 207.31966 82.9162)
		(end 207.6754 82.56045)
		(width 0.254)
		(layer "F.Cu")
		(net "GND")
	)
	(segment
		(start 228.3261 113.7162)
		(end 228.3261 112.9162)
		(width 0.254)
		(layer "F.Cu")
		(net "GND")
	)
	(segment
		(start 202.0261 109.4162)
		(end 203.7261 111.1162)
		(width 0.254)
		(layer "F.Cu")
		(net "GND")
	)
	(segment
		(start 198.1261 116.8286)
		(end 198.13375 116.82096)
		(width 0.2032)
		(layer "F.Cu")
		(net "GND")
	)
	(segment
		(start 124.54608 157.7576)
		(end 124.54608 156.0177)
		(width 0.508)
		(layer "F.Cu")
		(net "GND")
	)
	(segment
		(start 193.6011 87.8036)
		(end 195.1261 89.3286)
		(width 0.2032)
		(layer "F.Cu")
		(net "GND")
	)
	(segment
		(start 236.8261 131.8162)
		(end 236.8261 130.9449)
		(width 0.254)
		(layer "F.Cu")
		(net "GND")
	)
	(segment
		(start 199.34004 119.3368)
		(end 199.3634 119.31343)
		(width 0.2032)
		(layer "F.Cu")
		(net "GND")
	)
	(segment
		(start 201.4761 122.6662)
		(end 202.4011 122.6662)
		(width 0.254)
		(layer "F.Cu")
		(net "GND")
	)
	(segment
		(start 207.7261 78.3162)
		(end 208.2261 78.8162)
		(width 0.254)
		(layer "F.Cu")
		(net "GND")
	)
	(segment
		(start 195.31363 121.8133)
		(end 195.32128 121.82095)
		(width 0.2032)
		(layer "F.Cu")
		(net "GND")
	)
	(segment
		(start 175.82599 131.47882)
		(end 175.82599 129.8837)
		(width 0.2032)
		(layer "F.Cu")
		(net "GND")
	)
	(segment
		(start 218.1261 57.40744)
		(end 218.1261 57.3662)
		(width 0.762)
		(layer "F.Cu")
		(net "GND")
	)
	(segment
		(start 233.7261 59.2162)
		(end 233.7261 59.2162)
		(width 0.254)
		(layer "F.Cu")
		(net "GND")
	)
	(segment
		(start 149.07439 122.30891)
		(end 149.0909 122.2924)
		(width 0.254)
		(layer "F.Cu")
		(net "GND")
	)
	(segment
		(start 69.93108 129.1162)
		(end 70.03108 129.2162)
		(width 0.2032)
		(layer "F.Cu")
		(net "GND")
	)
	(segment
		(start 130.8261 86.2162)
		(end 130.8261 85.3162)
		(width 0.2032)
		(layer "F.Cu")
		(net "GND")
	)
	(segment
		(start 233.7261 71.0162)
		(end 233.7261 69.5162)
		(width 0.762)
		(layer "F.Cu")
		(net "GND")
	)
	(segment
		(start 233.7261 71.0162)
		(end 233.7261 71.0162)
		(width 0.762)
		(layer "F.Cu")
		(net "GND")
	)
	(segment
		(start 124.9365 82.6162)
		(end 125.27067 82.28203)
		(width 0.254)
		(layer "F.Cu")
		(net "GND")
	)
	(segment
		(start 172.32587 93.86847)
		(end 172.34923 93.89184)
		(width 0.2032)
		(layer "F.Cu")
		(net "GND")
	)
	(segment
		(start 198.13375 121.82095)
		(end 199.35575 121.82095)
		(width 0.2032)
		(layer "F.Cu")
		(net "GND")
	)
	(segment
		(start 217.8861 132.7162)
		(end 219.5261 132.7162)
		(width 0.762)
		(layer "F.Cu")
		(net "GND")
	)
	(segment
		(start 81.3761 93.6162)
		(end 82.6261 94.8662)
		(width 0.254)
		(layer "F.Cu")
		(net "GND")
	)
	(segment
		(start 134.54606 157.7576)
		(end 134.5511 157.75256)
		(width 0.508)
		(layer "F.Cu")
		(net "GND")
	)
	(segment
		(start 179.7931 95.22841)
		(end 179.80941 95.2121)
		(width 0.2032)
		(layer "F.Cu")
		(net "GND")
	)
	(segment
		(start 211.5261 80.41565)
		(end 211.65601 80.54556)
		(width 0.254)
		(layer "F.Cu")
		(net "GND")
	)
	(segment
		(start 131.43222 156.98475)
		(end 131.43222 154.87014)
		(width 0.508)
		(layer "F.Cu")
		(net "GND")
	)
	(segment
		(start 187.2261 88.7162)
		(end 187.5761 88.3662)
		(width 0.254)
		(layer "F.Cu")
		(net "GND")
	)
	(segment
		(start 239.69164 71.60334)
		(end 240.10358 71.19139)
		(width 0.254)
		(layer "F.Cu")
		(net "GND")
	)
	(segment
		(start 172.83584 135.50523)
		(end 172.83584 134.15826)
		(width 0.254)
		(layer "F.Cu")
		(net "GND")
	)
	(segment
		(start 238.1261 70.9162)
		(end 239.4261 70.9162)
		(width 0.254)
		(layer "F.Cu")
		(net "GND")
	)
	(segment
		(start 170.32612 135.5286)
		(end 170.32612 134.38356)
		(width 0.2032)
		(layer "F.Cu")
		(net "GND")
	)
	(segment
		(start 226.6261 113.15821)
		(end 226.6261 112.8562)
		(width 0.254)
		(layer "F.Cu")
		(net "GND")
	)
	(segment
		(start 75.1261 64.1162)
		(end 75.1261 63.6162)
		(width 0.762)
		(layer "F.Cu")
		(net "GND")
	)
	(segment
		(start 192.51494 142.78121)
		(end 192.53815 142.80442)
		(width 0.254)
		(layer "F.Cu")
		(net "GND")
	)
	(segment
		(start 165.32613 135.5286)
		(end 165.32613 134.28355)
		(width 0.2032)
		(layer "F.Cu")
		(net "GND")
	)
	(segment
		(start 136.3261 115.0162)
		(end 136.38538 114.95692)
		(width 0.2032)
		(layer "F.Cu")
		(net "GND")
	)
	(segment
		(start 92.64983 87.1162)
		(end 92.66568 87.13205)
		(width 0.2032)
		(layer "F.Cu")
		(net "GND")
	)
	(segment
		(start 118.54609 155.05901)
		(end 118.54609 155.05901)
		(width 0.508)
		(layer "F.Cu")
		(net "GND")
	)
	(segment
		(start 223.0761 81.0662)
		(end 223.0761 80.4162)
		(width 0.254)
		(layer "F.Cu")
		(net "GND")
	)
	(segment
		(start 147.71428 114.83567)
		(end 149.09557 114.83567)
		(width 0.2032)
		(layer "F.Cu")
		(net "GND")
	)
	(segment
		(start 199.35583 109.32103)
		(end 199.3634 109.31345)
		(width 0.2032)
		(layer "F.Cu")
		(net "GND")
	)
	(segment
		(start 107.54611 157.7576)
		(end 107.54611 154.34359)
		(width 0.508)
		(layer "F.Cu")
		(net "GND")
	)
	(segment
		(start 195.31363 119.31343)
		(end 195.337 119.3368)
		(width 0.2032)
		(layer "F.Cu")
		(net "GND")
	)
	(segment
		(start 196.61846 116.82096)
		(end 196.6261 116.8286)
		(width 0.2032)
		(layer "F.Cu")
		(net "GND")
	)
	(segment
		(start 165.32613 134.28355)
		(end 165.4261 134.18359)
		(width 0.2032)
		(layer "F.Cu")
		(net "GND")
	)
	(segment
		(start 221.5261 73.1162)
		(end 221.9637 72.6786)
		(width 0.762)
		(layer "F.Cu")
		(net "GND")
	)
	(segment
		(start 149.09557 114.83567)
		(end 149.1261 114.8662)
		(width 0.2032)
		(layer "F.Cu")
		(net "GND")
	)
	(segment
		(start 234.2261 62.5162)
		(end 234.2261 61.1162)
		(width 0.762)
		(layer "F.Cu")
		(net "GND")
	)
	(segment
		(start 225.59931 136.46799)
		(end 225.59931 135.04299)
		(width 0.254)
		(layer "F.Cu")
		(net "GND")
	)
	(segment
		(start 190.20466 83.0162)
		(end 190.20466 81.97346)
		(width 0.254)
		(layer "F.Cu")
		(net "GND")
	)
	(segment
		(start 201.91605 82.8162)
		(end 202.9261 82.8162)
		(width 0.254)
		(layer "F.Cu")
		(net "GND")
	)
	(segment
		(start 222.08731 64.6786)
		(end 223.6261 64.6786)
		(width 0.762)
		(layer "F.Cu")
		(net "GND")
	)
	(segment
		(start 174.32612 131.47882)
		(end 174.32612 129.72861)
		(width 0.2032)
		(layer "F.Cu")
		(net "GND")
	)
	(segment
		(start 80.54375 100.66367)
		(end 80.54375 100.60868)
		(width 0.2032)
		(layer "F.Cu")
		(net "GND")
	)
	(segment
		(start 180.3261 134.18358)
		(end 180.4261 134.08359)
		(width 0.2032)
		(layer "F.Cu")
		(net "GND")
	)
	(segment
		(start 167.9261 134.18359)
		(end 167.9261 134.1286)
		(width 0.2032)
		(layer "F.Cu")
		(net "GND")
	)
	(segment
		(start 199.35982 114.31702)
		(end 199.3634 114.31344)
		(width 0.2032)
		(layer "F.Cu")
		(net "GND")
	)
	(segment
		(start 80.5761 112.8662)
		(end 80.6261 112.8162)
		(width 0.2032)
		(layer "F.Cu")
		(net "GND")
	)
	(segment
		(start 233.7261 59.2162)
		(end 233.7261 57.9162)
		(width 0.762)
		(layer "F.Cu")
		(net "GND")
	)
	(segment
		(start 179.80941 93.88478)
		(end 179.82572 93.86847)
		(width 0.2032)
		(layer "F.Cu")
		(net "GND")
	)
	(segment
		(start 195.32127 116.82096)
		(end 196.61846 116.82096)
		(width 0.2032)
		(layer "F.Cu")
		(net "GND")
	)
	(segment
		(start 204.2261 107.9162)
		(end 204.7261 108.4162)
		(width 0.254)
		(layer "F.Cu")
		(net "GND")
	)
	(segment
		(start 92.1261 76.2206)
		(end 92.1261 75.2786)
		(width 0.762)
		(layer "F.Cu")
		(net "GND")
	)
	(segment
		(start 180.3261 135.5286)
		(end 180.3261 134.18358)
		(width 0.2032)
		(layer "F.Cu")
		(net "GND")
	)
	(segment
		(start 218.06876 58.67651)
		(end 218.06876 57.46478)
		(width 0.762)
		(layer "F.Cu")
		(net "GND")
	)
	(segment
		(start 134.5511 157.75256)
		(end 134.5511 154.1786)
		(width 0.508)
		(layer "F.Cu")
		(net "GND")
	)
	(segment
		(start 84.8761 121.3662)
		(end 84.8761 121.17119)
		(width 0.2032)
		(layer "F.Cu")
		(net "GND")
	)
	(segment
		(start 205.26056 109.25066)
		(end 206.0261 109.25066)
		(width 0.254)
		(layer "F.Cu")
		(net "GND")
	)
	(segment
		(start 199.35577 106.82097)
		(end 199.3634 106.81333)
		(width 0.2032)
		(layer "F.Cu")
		(net "GND")
	)
	(segment
		(start 201.4261 122.6162)
		(end 201.4761 122.6662)
		(width 0.254)
		(layer "F.Cu")
		(net "GND")
	)
	(segment
		(start 167.82605 131.47877)
		(end 167.82605 129.72865)
		(width 0.2032)
		(layer "F.Cu")
		(net "GND")
	)
	(segment
		(start 127.56892 82.85066)
		(end 127.56915 82.85044)
		(width 0.2032)
		(layer "F.Cu")
		(net "GND")
	)
	(segment
		(start 217.8861 135.5162)
		(end 217.8861 132.7162)
		(width 0.762)
		(layer "F.Cu")
		(net "GND")
	)
	(segment
		(start 124.0261 82.6162)
		(end 124.9365 82.6162)
		(width 0.254)
		(layer "F.Cu")
		(net "GND")
	)
	(segment
		(start 84.8761 108.1162)
		(end 84.8761 107.6162)
		(width 0.2032)
		(layer "F.Cu")
		(net "GND")
	)
	(segment
		(start 172.9261 129.76984)
		(end 172.9261 129.7286)
		(width 0.254)
		(layer "F.Cu")
		(net "GND")
	)
	(segment
		(start 169.82574 97.91825)
		(end 169.82592 97.91807)
		(width 0.2032)
		(layer "F.Cu")
		(net "GND")
	)
	(segment
		(start 193.1011 87.8036)
		(end 193.6011 87.8036)
		(width 0.2032)
		(layer "F.Cu")
		(net "GND")
	)
	(segment
		(start 202.5261 104.9162)
		(end 202.8511 105.2412)
		(width 0.254)
		(layer "F.Cu")
		(net "GND")
	)
	(segment
		(start 149.0655 119.8032)
		(end 149.0909 119.8286)
		(width 0.254)
		(layer "F.Cu")
		(net "GND")
	)
	(segment
		(start 74.3761 107.1412)
		(end 74.3761 106.1162)
		(width 0.2032)
		(layer "F.Cu")
		(net "GND")
	)
	(segment
		(start 126.99598 154.1786)
		(end 127.9511 154.1786)
		(width 0.508)
		(layer "F.Cu")
		(net "GND")
	)
	(segment
		(start 84.6261 107.3662)
		(end 84.8761 107.6162)
		(width 0.2032)
		(layer "F.Cu")
		(net "GND")
	)
	(segment
		(start 84.6261 108.3662)
		(end 84.8761 108.1162)
		(width 0.2032)
		(layer "F.Cu")
		(net "GND")
	)
	(segment
		(start 231.41099 82.31086)
		(end 231.44754 82.3474)
		(width 0.254)
		(layer "F.Cu")
		(net "GND")
	)
	(segment
		(start 82.3761 87.5662)
		(end 82.3761 87.5662)
		(width 0.254)
		(layer "F.Cu")
		(net "GND")
	)
	(segment
		(start 126.7261 82.85066)
		(end 127.56892 82.85066)
		(width 0.2032)
		(layer "F.Cu")
		(net "GND")
	)
	(segment
		(start 150.35037 107.35152)
		(end 151.70796 107.35152)
		(width 0.254)
		(layer "F.Cu")
		(net "GND")
	)
	(segment
		(start 132.8737 87.8686)
		(end 134.1261 87.8686)
		(width 0.2032)
		(layer "F.Cu")
		(net "GND")
	)
	(segment
		(start 126.2261 87.9162)
		(end 126.2261 86.5662)
		(width 0.2032)
		(layer "F.Cu")
		(net "GND")
	)
	(segment
		(start 165.4261 134.18359)
		(end 165.4261 134.1286)
		(width 0.2032)
		(layer "F.Cu")
		(net "GND")
	)
	(segment
		(start 198.13375 116.82096)
		(end 199.35576 116.82096)
		(width 0.2032)
		(layer "F.Cu")
		(net "GND")
	)
	(segment
		(start 179.80941 95.2121)
		(end 179.80941 93.88478)
		(width 0.2032)
		(layer "F.Cu")
		(net "GND")
	)
	(segment
		(start 230.3261 136.5162)
		(end 230.39336 136.44894)
		(width 0.254)
		(layer "F.Cu")
		(net "GND")
	)
	(segment
		(start 198.12968 114.31702)
		(end 199.35982 114.31702)
		(width 0.2032)
		(layer "F.Cu")
		(net "GND")
	)
	(segment
		(start 131.43222 154.87014)
		(end 131.43222 154.87014)
		(width 0.508)
		(layer "F.Cu")
		(net "GND")
	)
	(segment
		(start 196.61845 121.82095)
		(end 196.6261 121.8286)
		(width 0.2032)
		(layer "F.Cu")
		(net "GND")
	)
	(segment
		(start 148.33887 117.31039)
		(end 148.74187 117.31039)
		(width 0.254)
		(layer "F.Cu")
		(net "GND")
	)
	(segment
		(start 126.9761 154.1786)
		(end 127.44472 154.64722)
		(width 0.508)
		(layer "F.Cu")
		(net "GND")
	)
	(segment
		(start 204.0261 107.9162)
		(end 204.2261 107.9162)
		(width 0.254)
		(layer "F.Cu")
		(net "GND")
	)
	(segment
		(start 83.3261 87.8162)
		(end 84.1261 87.8162)
		(width 0.254)
		(layer "F.Cu")
		(net "GND")
	)
	(segment
		(start 174.81742 97.90993)
		(end 174.81742 96.41192)
		(width 0.2032)
		(layer "F.Cu")
		(net "GND")
	)
	(segment
		(start 177.3011 97.16189)
		(end 177.3011 96.4036)
		(width 0.2032)
		(layer "F.Cu")
		(net "GND")
	)
	(segment
		(start 86.3761 59.8286)
		(end 88.8137 59.8286)
		(width 0.762)
		(layer "F.Cu")
		(net "GND")
	)
	(segment
		(start 239.4261 64.38513)
		(end 239.4261 63.64371)
		(width 0.254)
		(layer "F.Cu")
		(net "GND")
	)
	(segment
		(start 182.6261 86.5162)
		(end 183.4261 86.5162)
		(width 0.254)
		(layer "F.Cu")
		(net "GND")
	)
	(segment
		(start 189.5761 84.6537)
		(end 190.47085 84.6537)
		(width 0.254)
		(layer "F.Cu")
		(net "GND")
	)
	(segment
		(start 177.8761 86.5786)
		(end 178.3761 87.0786)
		(width 0.2032)
		(layer "F.Cu")
		(net "GND")
	)
	(segment
		(start 198.18109 119.6242)
		(end 198.46849 119.3368)
		(width 0.2032)
		(layer "F.Cu")
		(net "GND")
	)
	(segment
		(start 202.2261 129.2162)
		(end 202.34754 129.2162)
		(width 0.254)
		(layer "F.Cu")
		(net "GND")
	)
	(segment
		(start 179.0261 129.78359)
		(end 179.0261 129.7286)
		(width 0.2032)
		(layer "F.Cu")
		(net "GND")
	)
	(segment
		(start 206.8261 82.9162)
		(end 207.31966 82.9162)
		(width 0.254)
		(layer "F.Cu")
		(net "GND")
	)
	(segment
		(start 172.32587 96.44182)
		(end 172.3841 96.38359)
		(width 0.2032)
		(layer "F.Cu")
		(net "GND")
	)
	(segment
		(start 89.3761 90.38978)
		(end 89.3761 89.4412)
		(width 0.2032)
		(layer "F.Cu")
		(net "GND")
	)
	(segment
		(start 211.5261 80.41565)
		(end 211.5261 79.6162)
		(width 0.254)
		(layer "F.Cu")
		(net "GND")
	)
	(segment
		(start 85.37393 87.36837)
		(end 85.37393 87.36403)
		(width 0.254)
		(layer "F.Cu")
		(net "GND")
	)
	(segment
		(start 124.51973 157.07224)
		(end 124.52608 157.0786)
		(width 0.508)
		(layer "F.Cu")
		(net "GND")
	)
	(segment
		(start 171.3611 89.8912)
		(end 172.36022 89.8912)
		(width 0.2032)
		(layer "F.Cu")
		(net "GND")
	)
	(segment
		(start 195.32127 111.82096)
		(end 196.61846 111.82096)
		(width 0.2032)
		(layer "F.Cu")
		(net "GND")
	)
	(segment
		(start 177.0761 86.5786)
		(end 177.8761 86.5786)
		(width 0.2032)
		(layer "F.Cu")
		(net "GND")
	)
	(segment
		(start 172.36022 89.8912)
		(end 172.47108 89.78033)
		(width 0.2032)
		(layer "F.Cu")
		(net "GND")
	)
	(segment
		(start 197.3761 83.5786)
		(end 197.3761 81.5866)
		(width 0.2032)
		(layer "F.Cu")
		(net "GND")
	)
	(segment
		(start 195.3212 109.32103)
		(end 196.61853 109.32103)
		(width 0.2032)
		(layer "F.Cu")
		(net "GND")
	)
	(segment
		(start 124.51973 155.99134)
		(end 124.54608 156.0177)
		(width 0.508)
		(layer "F.Cu")
		(net "GND")
	)
	(segment
		(start 131.43222 154.87014)
		(end 131.43222 154.87014)
		(width 0.508)
		(layer "F.Cu")
		(net "GND")
	)
	(segment
		(start 237.92825 135.3162)
		(end 237.96122 135.34917)
		(width 0.2032)
		(layer "F.Cu")
		(net "GND")
	)
	(segment
		(start 194.8761 84.5786)
		(end 194.8761 81.5866)
		(width 0.2032)
		(layer "F.Cu")
		(net "GND")
	)
	(segment
		(start 192.70976 138.72763)
		(end 193.98636 138.72763)
		(width 0.254)
		(layer "F.Cu")
		(net "GND")
	)
	(segment
		(start 190.54014 87.4562)
		(end 190.8261 87.4562)
		(width 0.254)
		(layer "F.Cu")
		(net "GND")
	)
	(segment
		(start 182.6261 86.5162)
		(end 182.6261 86.5162)
		(width 0.254)
		(layer "F.Cu")
		(net "GND")
	)
	(segment
		(start 233.5261 65.8162)
		(end 233.7261 65.6162)
		(width 0.762)
		(layer "F.Cu")
		(net "GND")
	)
	(segment
		(start 201.6261 129.8162)
		(end 202.2261 129.2162)
		(width 0.254)
		(layer "F.Cu")
		(net "GND")
	)
	(segment
		(start 170.32612 129.89354)
		(end 170.4261 129.79356)
		(width 0.2032)
		(layer "F.Cu")
		(net "GND")
	)
	(segment
		(start 120.9761 87.9836)
		(end 122.28112 87.9836)
		(width 0.2032)
		(layer "F.Cu")
		(net "GND")
	)
	(segment
		(start 104.52961 157.74109)
		(end 104.54612 157.7576)
		(width 0.508)
		(layer "F.Cu")
		(net "GND")
	)
	(segment
		(start 179.80941 97.90194)
		(end 179.80941 96.41016)
		(width 0.2032)
		(layer "F.Cu")
		(net "GND")
	)
	(segment
		(start 219.8261 80.5162)
		(end 219.8761 80.4662)
		(width 0.254)
		(layer "F.Cu")
		(net "GND")
	)
	(segment
		(start 177.4261 129.78359)
		(end 177.4261 129.7286)
		(width 0.2032)
		(layer "F.Cu")
		(net "GND")
	)
	(segment
		(start 237.5261 63.63954)
		(end 237.55511 63.61053)
		(width 0.254)
		(layer "F.Cu")
		(net "GND")
	)
	(segment
		(start 217.9261 78.6162)
		(end 217.9261 78.6162)
		(width 0.254)
		(layer "F.Cu")
		(net "GND")
	)
	(segment
		(start 124.22214 154.2818)
		(end 124.51973 154.57938)
		(width 0.508)
		(layer "F.Cu")
		(net "GND")
	)
	(segment
		(start 124.51973 155.99134)
		(end 124.51973 154.57938)
		(width 0.508)
		(layer "F.Cu")
		(net "GND")
	)
	(segment
		(start 211.5261 78.0162)
		(end 211.6221 77.9202)
		(width 0.254)
		(layer "F.Cu")
		(net "GND")
	)
	(segment
		(start 198.13374 111.82096)
		(end 199.35576 111.82096)
		(width 0.2032)
		(layer "F.Cu")
		(net "GND")
	)
	(segment
		(start 198.1261 111.8286)
		(end 198.13374 111.82096)
		(width 0.2032)
		(layer "F.Cu")
		(net "GND")
	)
	(segment
		(start 94.7261 64.5162)
		(end 94.7261 63.6162)
		(width 0.762)
		(layer "F.Cu")
		(net "GND")
	)
	(segment
		(start 208.2261 78.8162)
		(end 210.8761 78.8162)
		(width 0.254)
		(layer "F.Cu")
		(net "GND")
	)
	(segment
		(start 193.1745 86.4302)
		(end 193.5245 86.4302)
		(width 0.2032)
		(layer "F.Cu")
		(net "GND")
	)
	(segment
		(start 94.7261 63.6162)
		(end 95.0261 63.3162)
		(width 0.762)
		(layer "F.Cu")
		(net "GND")
	)
	(segment
		(start 211.6221 77.9202)
		(end 211.6221 77.81099)
		(width 0.254)
		(layer "F.Cu")
		(net "GND")
	)
	(segment
		(start 172.82599 129.86995)
		(end 172.9261 129.76984)
		(width 0.254)
		(layer "F.Cu")
		(net "GND")
	)
	(segment
		(start 170.4261 129.79356)
		(end 170.4261 129.73857)
		(width 0.2032)
		(layer "F.Cu")
		(net "GND")
	)
	(segment
		(start 226.5261 130.7162)
		(end 228.4261 130.7162)
		(width 0.254)
		(layer "F.Cu")
		(net "GND")
	)
	(segment
		(start 236.79002 130.9449)
		(end 236.8261 130.9449)
		(width 0.254)
		(layer "F.Cu")
		(net "GND")
	)
	(segment
		(start 237.2979 60.74407)
		(end 237.3261 60.77227)
		(width 0.254)
		(layer "F.Cu")
		(net "GND")
	)
	(segment
		(start 198.2261 89.1162)
		(end 198.2261 87.52258)
		(width 0.254)
		(layer "F.Cu")
		(net "GND")
	)
	(segment
		(start 190.47085 84.6537)
		(end 190.55001 84.73286)
		(width 0.254)
		(layer "F.Cu")
		(net "GND")
	)
	(segment
		(start 225.5761 136.4912)
		(end 225.59931 136.46799)
		(width 0.254)
		(layer "F.Cu")
		(net "GND")
	)
	(segment
		(start 122.8527 154.2818)
		(end 122.8745 154.3036)
		(width 0.508)
		(layer "F.Cu")
		(net "GND")
	)
	(segment
		(start 234.9261 76.4162)
		(end 236.1261 76.4162)
		(width 0.254)
		(layer "F.Cu")
		(net "GND")
	)
	(segment
		(start 136.38538 114.95692)
		(end 137.66107 114.95692)
		(width 0.2032)
		(layer "F.Cu")
		(net "GND")
	)
	(segment
		(start 83.9511 121.6162)
		(end 84.6261 121.6162)
		(width 0.2032)
		(layer "F.Cu")
		(net "GND")
	)
	(segment
		(start 107.54611 154.34359)
		(end 107.5611 154.3286)
		(width 0.508)
		(layer "F.Cu")
		(net "GND")
	)
	(segment
		(start 233.8261 118.6162)
		(end 233.8261 116.6162)
		(width 0.254)
		(layer "F.Cu")
		(net "GND")
	)
	(segment
		(start 230.39336 135.04894)
		(end 230.42252 135.01978)
		(width 0.254)
		(layer "F.Cu")
		(net "GND")
	)
	(segment
		(start 79.00081 84.89904)
		(end 79.11797 85.0162)
		(width 0.2032)
		(layer "F.Cu")
		(net "GND")
	)
	(segment
		(start 235.7261 62.7162)
		(end 235.7261 61.8631)
		(width 0.254)
		(layer "F.Cu")
		(net "GND")
	)
	(segment
		(start 234.7261 73.66478)
		(end 234.81122 73.57966)
		(width 0.254)
		(layer "F.Cu")
		(net "GND")
	)
	(segment
		(start 214.8261 78.15066)
		(end 215.56056 77.4162)
		(width 0.254)
		(layer "F.Cu")
		(net "GND")
	)
	(segment
		(start 136.32038 116.48092)
		(end 137.66107 116.48092)
		(width 0.2032)
		(layer "F.Cu")
		(net "GND")
	)
	(segment
		(start 226.6261 113.15821)
		(end 227.32035 113.85246)
		(width 0.254)
		(layer "F.Cu")
		(net "GND")
	)
	(segment
		(start 131.43222 156.98475)
		(end 131.52607 157.0786)
		(width 0.508)
		(layer "F.Cu")
		(net "GND")
	)
	(segment
		(start 237.9011 70.6912)
		(end 237.9011 70.0317)
		(width 0.254)
		(layer "F.Cu")
		(net "GND")
	)
	(segment
		(start 167.49809 96.5116)
		(end 167.49809 96.45661)
		(width 0.2032)
		(layer "F.Cu")
		(net "GND")
	)
	(segment
		(start 191.70015 87.4562)
		(end 191.70264 87.45869)
		(width 0.254)
		(layer "F.Cu")
		(net "GND")
	)
	(segment
		(start 148.42954 119.8032)
		(end 149.0655 119.8032)
		(width 0.254)
		(layer "F.Cu")
		(net "GND")
	)
	(segment
		(start 176.8261 86.3286)
		(end 177.0761 86.5786)
		(width 0.2032)
		(layer "F.Cu")
		(net "GND")
	)
	(segment
		(start 196.61847 106.82097)
		(end 196.6261 106.8286)
		(width 0.2032)
		(layer "F.Cu")
		(net "GND")
	)
	(segment
		(start 131.0261 88.8162)
		(end 131.0261 88.6662)
		(width 0.2032)
		(layer "F.Cu")
		(net "GND")
	)
	(segment
		(start 170.5261 134.18359)
		(end 170.5261 134.1286)
		(width 0.2032)
		(layer "F.Cu")
		(net "GND")
	)
	(segment
		(start 130.99597 154.1786)
		(end 131.30685 154.53599)
		(width 0.508)
		(layer "F.Cu")
		(net "GND")
	)
	(segment
		(start 84.9261 87.8162)
		(end 85.37393 87.36837)
		(width 0.254)
		(layer "F.Cu")
		(net "GND")
	)
	(segment
		(start 149.17929 109.80881)
		(end 149.1925 109.7956)
		(width 0.254)
		(layer "F.Cu")
		(net "GND")
	)
	(segment
		(start 201.90818 82.80834)
		(end 201.91605 82.8162)
		(width 0.254)
		(layer "F.Cu")
		(net "GND")
	)
	(segment
		(start 194.1261 85.8286)
		(end 195.1261 85.8286)
		(width 0.2032)
		(layer "F.Cu")
		(net "GND")
	)
	(segment
		(start 104.52961 157.74109)
		(end 104.52961 154.36162)
		(width 0.508)
		(layer "F.Cu")
		(net "GND")
	)
	(segment
		(start 198.20352 87.5)
		(end 198.2261 87.52258)
		(width 0.254)
		(layer "F.Cu")
		(net "GND")
	)
	(segment
		(start 237.5261 64.35066)
		(end 237.5261 63.63954)
		(width 0.254)
		(layer "F.Cu")
		(net "GND")
	)
	(segment
		(start 167.82605 129.72865)
		(end 167.8261 129.7286)
		(width 0.2032)
		(layer "F.Cu")
		(net "GND")
	)
	(segment
		(start 167.32588 95.09939)
		(end 167.4001 95.17361)
		(width 0.2032)
		(layer "F.Cu")
		(net "GND")
	)
	(segment
		(start 215.56056 77.4162)
		(end 215.6261 77.4162)
		(width 0.254)
		(layer "F.Cu")
		(net "GND")
	)
	(segment
		(start 151.54502 77.94847)
		(end 151.57167 77.94847)
		(width 0.762)
		(layer "F.Cu")
		(net "GND")
	)
	(segment
		(start 91.4261 64.7162)
		(end 91.4261 63.6162)
		(width 0.762)
		(layer "F.Cu")
		(net "GND")
	)
	(segment
		(start 172.34923 95.19373)
		(end 172.34923 93.89184)
		(width 0.2032)
		(layer "F.Cu")
		(net "GND")
	)
	(segment
		(start 82.3761 88.6162)
		(end 82.3761 87.5662)
		(width 0.254)
		(layer "F.Cu")
		(net "GND")
	)
	(segment
		(start 88.8137 59.8286)
		(end 88.8261 59.8162)
		(width 0.762)
		(layer "F.Cu")
		(net "GND")
	)
	(segment
		(start 212.10657 114.76641)
		(end 212.29775 114.76641)
		(width 0.254)
		(layer "F.Cu")
		(net "GND")
	)
	(segment
		(start 196.61846 111.82096)
		(end 196.6261 111.8286)
		(width 0.2032)
		(layer "F.Cu")
		(net "GND")
	)
	(segment
		(start 168.5511 89.8912)
		(end 170.0911 89.8912)
		(width 0.2032)
		(layer "F.Cu")
		(net "GND")
	)
	(segment
		(start 222.89164 78.03695)
		(end 222.91764 78.01095)
		(width 0.254)
		(layer "F.Cu")
		(net "GND")
	)
	(segment
		(start 169.82574 95.02326)
		(end 169.82574 93.86847)
		(width 0.2032)
		(layer "F.Cu")
		(net "GND")
	)
	(segment
		(start 217.8261 78.6162)
		(end 217.91544 78.6162)
		(width 0.254)
		(layer "F.Cu")
		(net "GND")
	)
	(segment
		(start 180.4261 134.08359)
		(end 180.4261 134.0286)
		(width 0.2032)
		(layer "F.Cu")
		(net "GND")
	)
	(segment
		(start 175.3761 86.3286)
		(end 176.8261 86.3286)
		(width 0.2032)
		(layer "F.Cu")
		(net "GND")
	)
	(segment
		(start 202.1261 91.8162)
		(end 202.4911 91.4512)
		(width 0.254)
		(layer "F.Cu")
		(net "GND")
	)
	(segment
		(start 74.2261 62.7162)
		(end 75.1261 63.6162)
		(width 0.762)
		(layer "F.Cu")
		(net "GND")
	)
	(segment
		(start 74.3761 120.3912)
		(end 74.3761 119.3662)
		(width 0.2032)
		(layer "F.Cu")
		(net "GND")
	)
	(segment
		(start 71.1261 103.3662)
		(end 71.1261 101.8662)
		(width 0.2032)
		(layer "F.Cu")
		(net "GND")
	)
	(segment
		(start 219.8761 78.0162)
		(end 219.8761 76.7662)
		(width 0.254)
		(layer "F.Cu")
		(net "GND")
	)
	(segment
		(start 237.92825 137.0162)
		(end 238.9261 137.0162)
		(width 0.2032)
		(layer "F.Cu")
		(net "GND")
	)
	(segment
		(start 74.3761 97.6162)
		(end 74.3761 96.5912)
		(width 0.2032)
		(layer "F.Cu")
		(net "GND")
	)
	(segment
		(start 147.70076 119.80879)
		(end 147.70279 119.80676)
		(width 0.254)
		(layer "F.Cu")
		(net "GND")
	)
	(segment
		(start 165.0511 96.44854)
		(end 165.0511 96.39356)
		(width 0.2032)
		(layer "F.Cu")
		(net "GND")
	)
	(segment
		(start 225.59931 135.04299)
		(end 225.62252 135.01978)
		(width 0.254)
		(layer "F.Cu")
		(net "GND")
	)
	(segment
		(start 153.9261 79.7162)
		(end 153.9261 77.9669)
		(width 0.762)
		(layer "F.Cu")
		(net "GND")
	)
	(segment
		(start 80.6261 127.6162)
		(end 80.6261 126.5662)
		(width 0.2032)
		(layer "F.Cu")
		(net "GND")
	)
	(via
		(at 59.6821 90.5746)
		(size 0.4064)
		(drill 0.2032)
		(layers "F.Cu" "B.Cu")
		(tenting
			(front yes)
			(back yes)
		)
		(net "GND")
	)
	(via
		(at 66.2861 118.0066)
		(size 0.4064)
		(drill 0.2032)
		(layers "F.Cu" "B.Cu")
		(tenting
			(front yes)
			(back yes)
		)
		(net "GND")
	)
	(via
		(at 224.5261 101.9162)
		(size 0.4064)
		(drill 0.2032)
		(layers "F.Cu" "B.Cu")
		(net "GND")
	)
	(via
		(at 85.8761 81.1162)
		(size 0.4064)
		(drill 0.2032)
		(layers "F.Cu" "B.Cu")
		(tenting
			(front yes)
			(back yes)
		)
		(net "GND")
	)
	(via
		(at 239.4261 70.9162)
		(size 0.4064)
		(drill 0.2032)
		(layers "F.Cu" "B.Cu")
		(net "GND")
	)
	(via
		(at 151.57167 77.94847)
		(size 1.27)
		(drill 0.7112)
		(layers "F.Cu" "B.Cu")
		(net "GND")
	)
	(via
		(at 57.1421 103.7826)
		(size 0.4064)
		(drill 0.2032)
		(layers "F.Cu" "B.Cu")
		(tenting
			(front yes)
			(back yes)
		)
		(net "GND")
	)
	(via
		(at 180.4261 138.2162)
		(size 0.4064)
		(drill 0.2032)
		(layers "F.Cu" "B.Cu")
		(tenting
			(front yes)
			(back yes)
		)
		(net "GND")
	)
	(via
		(at 61.2061 97.6866)
		(size 0.4064)
		(drill 0.2032)
		(layers "F.Cu" "B.Cu")
		(tenting
			(front yes)
			(back yes)
		)
		(net "GND")
	)
	(via
		(at 66.7941 98.7026)
		(size 0.4064)
		(drill 0.2032)
		(layers "F.Cu" "B.Cu")
		(tenting
			(front yes)
			(back yes)
		)
		(net "GND")
	)
	(via
		(at 207.9261 105.9162)
		(size 0.4064)
		(drill 0.2032)
		(layers "F.Cu" "B.Cu")
		(net "GND")
	)
	(via
		(at 73.3981 140.3586)
		(size 0.4064)
		(drill 0.2032)
		(layers "F.Cu" "B.Cu")
		(tenting
			(front yes)
			(back yes)
		)
		(net "GND")
	)
	(via
		(at 182.6261 86.5162)
		(size 0.4064)
		(drill 0.2032)
		(layers "F.Cu" "B.Cu")
		(tenting
			(front yes)
			(back yes)
		)
		(net "GND")
	)
	(via
		(at 76.9541 129.1826)
		(size 0.4064)
		(drill 0.2032)
		(layers "F.Cu" "B.Cu")
		(tenting
			(front yes)
			(back yes)
		)
		(net "GND")
	)
	(via
		(at 130.99597 154.1786)
		(size 0.4064)
		(drill 0.2032)
		(layers "F.Cu" "B.Cu")
		(tenting
			(front yes)
			(back yes)
		)
		(net "GND")
	)
	(via
		(at 66.2861 142.3906)
		(size 0.4064)
		(drill 0.2032)
		(layers "F.Cu" "B.Cu")
		(tenting
			(front yes)
			(back yes)
		)
		(net "GND")
	)
	(via
		(at 214.5261 68.8162)
		(size 0.4064)
		(drill 0.2032)
		(layers "F.Cu" "B.Cu")
		(tenting
			(front yes)
			(back yes)
		)
		(net "GND")
	)
	(via
		(at 207.3261 120.9162)
		(size 0.4064)
		(drill 0.2032)
		(layers "F.Cu" "B.Cu")
		(net "GND")
	)
	(via
		(at 70.3501 97.6866)
		(size 0.4064)
		(drill 0.2032)
		(layers "F.Cu" "B.Cu")
		(tenting
			(front yes)
			(back yes)
		)
		(net "GND")
	)
	(via
		(at 62.7301 116.9906)
		(size 0.4064)
		(drill 0.2032)
		(layers "F.Cu" "B.Cu")
		(tenting
			(front yes)
			(back yes)
		)
		(net "GND")
	)
	(via
		(at 202.34165 102.16177)
		(size 0.4064)
		(drill 0.2032)
		(layers "F.Cu" "B.Cu")
		(net "GND")
	)
	(via
		(at 130.1261 82.0786)
		(size 0.4064)
		(drill 0.2032)
		(layers "F.Cu" "B.Cu")
		(tenting
			(front yes)
			(back yes)
		)
		(net "GND")
	)
	(via
		(at 215.6261 77.4162)
		(size 0.4064)
		(drill 0.2032)
		(layers "F.Cu" "B.Cu")
		(net "GND")
	)
	(via
		(at 71.8741 116.9906)
		(size 0.4064)
		(drill 0.2032)
		(layers "F.Cu" "B.Cu")
		(tenting
			(front yes)
			(back yes)
		)
		(net "GND")
	)
	(via
		(at 234.1261 98.9162)
		(size 0.4064)
		(drill 0.2032)
		(layers "F.Cu" "B.Cu")
		(net "GND")
	)
	(via
		(at 56.6341 135.2786)
		(size 0.4064)
		(drill 0.2032)
		(layers "F.Cu" "B.Cu")
		(tenting
			(front yes)
			(back yes)
		)
		(net "GND")
	)
	(via
		(at 75.9381 125.1186)
		(size 0.4064)
		(drill 0.2032)
		(layers "F.Cu" "B.Cu")
		(tenting
			(front yes)
			(back yes)
		)
		(net "GND")
	)
	(via
		(at 149.0909 119.8286)
		(size 0.4064)
		(drill 0.2032)
		(layers "F.Cu" "B.Cu")
		(tenting
			(front yes)
			(back yes)
		)
		(net "GND")
	)
	(via
		(at 72.3821 111.9106)
		(size 0.4064)
		(drill 0.2032)
		(layers "F.Cu" "B.Cu")
		(tenting
			(front yes)
			(back yes)
		)
		(net "GND")
	)
	(via
		(at 71.8741 110.8946)
		(size 0.4064)
		(drill 0.2032)
		(layers "F.Cu" "B.Cu")
		(tenting
			(front yes)
			(back yes)
		)
		(net "GND")
	)
	(via
		(at 75.9381 129.1826)
		(size 0.4064)
		(drill 0.2032)
		(layers "F.Cu" "B.Cu")
		(tenting
			(front yes)
			(back yes)
		)
		(net "GND")
	)
	(via
		(at 64.7621 116.9906)
		(size 0.4064)
		(drill 0.2032)
		(layers "F.Cu" "B.Cu")
		(tenting
			(front yes)
			(back yes)
		)
		(net "GND")
	)
	(via
		(at 179.7931 96.39385)
		(size 0.4064)
		(drill 0.2032)
		(layers "F.Cu" "B.Cu")
		(tenting
			(front yes)
			(back yes)
		)
		(net "GND")
	)
	(via
		(at 71.8741 123.0866)
		(size 0.4064)
		(drill 0.2032)
		(layers "F.Cu" "B.Cu")
		(tenting
			(front yes)
			(back yes)
		)
		(net "GND")
	)
	(via
		(at 72.8901 112.9266)
		(size 0.4064)
		(drill 0.2032)
		(layers "F.Cu" "B.Cu")
		(tenting
			(front yes)
			(back yes)
		)
		(net "GND")
	)
	(via
		(at 221.8261 119.0162)
		(size 0.4064)
		(drill 0.2032)
		(layers "F.Cu" "B.Cu")
		(net "GND")
	)
	(via
		(at 71.3661 140.3586)
		(size 0.4064)
		(drill 0.2032)
		(layers "F.Cu" "B.Cu")
		(tenting
			(front yes)
			(back yes)
		)
		(net "GND")
	)
	(via
		(at 68.8261 133.2466)
		(size 0.4064)
		(drill 0.2032)
		(layers "F.Cu" "B.Cu")
		(tenting
			(front yes)
			(back yes)
		)
		(net "GND")
	)
	(via
		(at 69.3341 144.4226)
		(size 0.4064)
		(drill 0.2032)
		(layers "F.Cu" "B.Cu")
		(tenting
			(front yes)
			(back yes)
		)
		(net "GND")
	)
	(via
		(at 67.3021 109.8786)
		(size 0.4064)
		(drill 0.2032)
		(layers "F.Cu" "B.Cu")
		(tenting
			(front yes)
			(back yes)
		)
		(net "GND")
	)
	(via
		(at 74.4141 128.1666)
		(size 0.4064)
		(drill 0.2032)
		(layers "F.Cu" "B.Cu")
		(tenting
			(front yes)
			(back yes)
		)
		(net "GND")
	)
	(via
		(at 57.1421 95.6546)
		(size 0.4064)
		(drill 0.2032)
		(layers "F.Cu" "B.Cu")
		(tenting
			(front yes)
			(back yes)
		)
		(net "GND")
	)
	(via
		(at 66.2861 138.3266)
		(size 0.4064)
		(drill 0.2032)
		(layers "F.Cu" "B.Cu")
		(tenting
			(front yes)
			(back yes)
		)
		(net "GND")
	)
	(via
		(at 177.3011 96.4036)
		(size 0.4064)
		(drill 0.2032)
		(layers "F.Cu" "B.Cu")
		(tenting
			(front yes)
			(back yes)
		)
		(net "GND")
	)
	(via
		(at 192.41494 138.98121)
		(size 0.4064)
		(drill 0.2032)
		(layers "F.Cu" "B.Cu")
		(tenting
			(front yes)
			(back yes)
		)
		(net "GND")
	)
	(via
		(at 176.9261 138.2162)
		(size 0.4064)
		(drill 0.2032)
		(layers "F.Cu" "B.Cu")
		(tenting
			(front yes)
			(back yes)
		)
		(net "GND")
	)
	(via
		(at 68.8261 121.0546)
		(size 0.4064)
		(drill 0.2032)
		(layers "F.Cu" "B.Cu")
		(tenting
			(front yes)
			(back yes)
		)
		(net "GND")
	)
	(via
		(at 72.3821 91.5906)
		(size 0.4064)
		(drill 0.2032)
		(layers "F.Cu" "B.Cu")
		(tenting
			(front yes)
			(back yes)
		)
		(net "GND")
	)
	(via
		(at 177.5261 138.2162)
		(size 0.4064)
		(drill 0.2032)
		(layers "F.Cu" "B.Cu")
		(tenting
			(front yes)
			(back yes)
		)
		(net "GND")
	)
	(via
		(at 234.9261 122.7162)
		(size 0.4064)
		(drill 0.2032)
		(layers "F.Cu" "B.Cu")
		(net "GND")
	)
	(via
		(at 60.6981 125.1186)
		(size 0.4064)
		(drill 0.2032)
		(layers "F.Cu" "B.Cu")
		(tenting
			(front yes)
			(back yes)
		)
		(net "GND")
	)
	(via
		(at 72.3821 142.3906)
		(size 0.4064)
		(drill 0.2032)
		(layers "F.Cu" "B.Cu")
		(tenting
			(front yes)
			(back yes)
		)
		(net "GND")
	)
	(via
		(at 209.9261 127.4162)
		(size 0.4064)
		(drill 0.2032)
		(layers "F.Cu" "B.Cu")
		(net "GND")
	)
	(via
		(at 77.4621 140.3586)
		(size 0.4064)
		(drill 0.2032)
		(layers "F.Cu" "B.Cu")
		(tenting
			(front yes)
			(back yes)
		)
		(net "GND")
	)
	(via
		(at 235.1261 98.9162)
		(size 0.4064)
		(drill 0.2032)
		(layers "F.Cu" "B.Cu")
		(net "GND")
	)
	(via
		(at 201.7261 119.6162)
		(size 0.4064)
		(drill 0.2032)
		(layers "F.Cu" "B.Cu")
		(net "GND")
	)
	(via
		(at 66.7941 133.2466)
		(size 0.4064)
		(drill 0.2032)
		(layers "F.Cu" "B.Cu")
		(tenting
			(front yes)
			(back yes)
		)
		(net "GND")
	)
	(via
		(at 56.6341 94.6386)
		(size 0.4064)
		(drill 0.2032)
		(layers "F.Cu" "B.Cu")
		(tenting
			(front yes)
			(back yes)
		)
		(net "GND")
	)
	(via
		(at 67.3021 105.8146)
		(size 0.4064)
		(drill 0.2032)
		(layers "F.Cu" "B.Cu")
		(tenting
			(front yes)
			(back yes)
		)
		(net "GND")
	)
	(via
		(at 69.8421 92.6066)
		(size 0.4064)
		(drill 0.2032)
		(layers "F.Cu" "B.Cu")
		(tenting
			(front yes)
			(back yes)
		)
		(net "GND")
	)
	(via
		(at 73.9061 141.3746)
		(size 0.4064)
		(drill 0.2032)
		(layers "F.Cu" "B.Cu")
		(tenting
			(front yes)
			(back yes)
		)
		(net "GND")
	)
	(via
		(at 66.7941 116.9906)
		(size 0.4064)
		(drill 0.2032)
		(layers "F.Cu" "B.Cu")
		(tenting
			(front yes)
			(back yes)
		)
		(net "GND")
	)
	(via
		(at 67.3021 138.3266)
		(size 0.4064)
		(drill 0.2032)
		(layers "F.Cu" "B.Cu")
		(tenting
			(front yes)
			(back yes)
		)
		(net "GND")
	)
	(via
		(at 66.7941 139.3426)
		(size 0.4064)
		(drill 0.2032)
		(layers "F.Cu" "B.Cu")
		(tenting
			(front yes)
			(back yes)
		)
		(net "GND")
	)
	(via
		(at 67.8101 133.2466)
		(size 0.4064)
		(drill 0.2032)
		(layers "F.Cu" "B.Cu")
		(tenting
			(front yes)
			(back yes)
		)
		(net "GND")
	)
	(via
		(at 150.3761 114.8662)
		(size 0.4064)
		(drill 0.2032)
		(layers "F.Cu" "B.Cu")
		(tenting
			(front yes)
			(back yes)
		)
		(net "GND")
	)
	(via
		(at 149.11137 116.98213)
		(size 0.4064)
		(drill 0.2032)
		(layers "F.Cu" "B.Cu")
		(tenting
			(front yes)
			(back yes)
		)
		(net "GND")
	)
	(via
		(at 72.3821 144.4226)
		(size 0.4064)
		(drill 0.2032)
		(layers "F.Cu" "B.Cu")
		(tenting
			(front yes)
			(back yes)
		)
		(net "GND")
	)
	(via
		(at 76.4461 105.8146)
		(size 0.4064)
		(drill 0.2032)
		(layers "F.Cu" "B.Cu")
		(tenting
			(front yes)
			(back yes)
		)
		(net "GND")
	)
	(via
		(at 67.8101 121.0546)
		(size 0.4064)
		(drill 0.2032)
		(layers "F.Cu" "B.Cu")
		(tenting
			(front yes)
			(back yes)
		)
		(net "GND")
	)
	(via
		(at 72.3821 93.6226)
		(size 0.4064)
		(drill 0.2032)
		(layers "F.Cu" "B.Cu")
		(tenting
			(front yes)
			(back yes)
		)
		(net "GND")
	)
	(via
		(at 233.6261 125.9162)
		(size 0.4064)
		(drill 0.2032)
		(layers "F.Cu" "B.Cu")
		(net "GND")
	)
	(via
		(at 196.3261 89.6162)
		(size 0.4064)
		(drill 0.2032)
		(layers "F.Cu" "B.Cu")
		(net "GND")
	)
	(via
		(at 219.5261 132.7162)
		(size 0.4064)
		(drill 0.2032)
		(layers "F.Cu" "B.Cu")
		(tenting
			(front yes)
			(back yes)
		)
		(net "GND")
	)
	(via
		(at 65.2701 144.4226)
		(size 0.4064)
		(drill 0.2032)
		(layers "F.Cu" "B.Cu")
		(tenting
			(front yes)
			(back yes)
		)
		(net "GND")
	)
	(via
		(at 67.8101 104.7986)
		(size 0.4064)
		(drill 0.2032)
		(layers "F.Cu" "B.Cu")
		(tenting
			(front yes)
			(back yes)
		)
		(net "GND")
	)
	(via
		(at 231.5261 97.0162)
		(size 0.4064)
		(drill 0.2032)
		(layers "F.Cu" "B.Cu")
		(net "GND")
	)
	(via
		(at 66.7941 129.1826)
		(size 0.4064)
		(drill 0.2032)
		(layers "F.Cu" "B.Cu")
		(tenting
			(front yes)
			(back yes)
		)
		(net "GND")
	)
	(via
		(at 74.3761 124.3662)
		(size 0.4064)
		(drill 0.2032)
		(layers "F.Cu" "B.Cu")
		(tenting
			(front yes)
			(back yes)
		)
		(net "GND")
	)
	(via
		(at 68.3181 142.3906)
		(size 0.4064)
		(drill 0.2032)
		(layers "F.Cu" "B.Cu")
		(tenting
			(front yes)
			(back yes)
		)
		(net "GND")
	)
	(via
		(at 84.8761 134.8662)
		(size 0.4064)
		(drill 0.2032)
		(layers "F.Cu" "B.Cu")
		(tenting
			(front yes)
			(back yes)
		)
		(net "GND")
	)
	(via
		(at 69.8421 90.5746)
		(size 0.4064)
		(drill 0.2032)
		(layers "F.Cu" "B.Cu")
		(tenting
			(front yes)
			(back yes)
		)
		(net "GND")
	)
	(via
		(at 77.4621 128.1666)
		(size 0.4064)
		(drill 0.2032)
		(layers "F.Cu" "B.Cu")
		(tenting
			(front yes)
			(back yes)
		)
		(net "GND")
	)
	(via
		(at 68.8261 141.3746)
		(size 0.4064)
		(drill 0.2032)
		(layers "F.Cu" "B.Cu")
		(tenting
			(front yes)
			(back yes)
		)
		(net "GND")
	)
	(via
		(at 75.9381 139.3426)
		(size 0.4064)
		(drill 0.2032)
		(layers "F.Cu" "B.Cu")
		(tenting
			(front yes)
			(back yes)
		)
		(net "GND")
	)
	(via
		(at 126.99598 154.1786)
		(size 0.4064)
		(drill 0.2032)
		(layers "F.Cu" "B.Cu")
		(tenting
			(front yes)
			(back yes)
		)
		(net "GND")
	)
	(via
		(at 61.7141 90.5746)
		(size 0.4064)
		(drill 0.2032)
		(layers "F.Cu" "B.Cu")
		(tenting
			(front yes)
			(back yes)
		)
		(net "GND")
	)
	(via
		(at 68.3181 118.0066)
		(size 0.4064)
		(drill 0.2032)
		(layers "F.Cu" "B.Cu")
		(tenting
			(front yes)
			(back yes)
		)
		(net "GND")
	)
	(via
		(at 71.8741 131.2146)
		(size 0.4064)
		(drill 0.2032)
		(layers "F.Cu" "B.Cu")
		(tenting
			(front yes)
			(back yes)
		)
		(net "GND")
	)
	(via
		(at 69.3341 132.2306)
		(size 0.4064)
		(drill 0.2032)
		(layers "F.Cu" "B.Cu")
		(tenting
			(front yes)
			(back yes)
		)
		(net "GND")
	)
	(via
		(at 61.2061 138.3266)
		(size 0.4064)
		(drill 0.2032)
		(layers "F.Cu" "B.Cu")
		(tenting
			(front yes)
			(back yes)
		)
		(net "GND")
	)
	(via
		(at 230.1261 96.9162)
		(size 0.4064)
		(drill 0.2032)
		(layers "F.Cu" "B.Cu")
		(net "GND")
	)
	(via
		(at 76.4461 113.9426)
		(size 0.4064)
		(drill 0.2032)
		(layers "F.Cu" "B.Cu")
		(tenting
			(front yes)
			(back yes)
		)
		(net "GND")
	)
	(via
		(at 73.9061 114.9586)
		(size 0.4064)
		(drill 0.2032)
		(layers "F.Cu" "B.Cu")
		(tenting
			(front yes)
			(back yes)
		)
		(net "GND")
	)
	(via
		(at 167.49809 96.45661)
		(size 0.4064)
		(drill 0.2032)
		(layers "F.Cu" "B.Cu")
		(tenting
			(front yes)
			(back yes)
		)
		(net "GND")
	)
	(via
		(at 75.4301 111.9106)
		(size 0.4064)
		(drill 0.2032)
		(layers "F.Cu" "B.Cu")
		(tenting
			(front yes)
			(back yes)
		)
		(net "GND")
	)
	(via
		(at 68.3181 124.1026)
		(size 0.4064)
		(drill 0.2032)
		(layers "F.Cu" "B.Cu")
		(tenting
			(front yes)
			(back yes)
		)
		(net "GND")
	)
	(via
		(at 74.9221 114.9586)
		(size 0.4064)
		(drill 0.2032)
		(layers "F.Cu" "B.Cu")
		(tenting
			(front yes)
			(back yes)
		)
		(net "GND")
	)
	(via
		(at 202.4261 119.5162)
		(size 0.4064)
		(drill 0.2032)
		(layers "F.Cu" "B.Cu")
		(net "GND")
	)
	(via
		(at 77.4621 118.0066)
		(size 0.4064)
		(drill 0.2032)
		(layers "F.Cu" "B.Cu")
		(tenting
			(front yes)
			(back yes)
		)
		(net "GND")
	)
	(via
		(at 125.27067 82.28203)
		(size 0.4064)
		(drill 0.2032)
		(layers "F.Cu" "B.Cu")
		(net "GND")
	)
	(via
		(at 227.32035 113.85246)
		(size 0.4064)
		(drill 0.2032)
		(layers "F.Cu" "B.Cu")
		(net "GND")
	)
	(via
		(at 73.3981 91.5906)
		(size 0.4064)
		(drill 0.2032)
		(layers "F.Cu" "B.Cu")
		(tenting
			(front yes)
			(back yes)
		)
		(net "GND")
	)
	(via
		(at 210.4261 112.9162)
		(size 0.4064)
		(drill 0.2032)
		(layers "F.Cu" "B.Cu")
		(net "GND")
	)
	(via
		(at 225.6261 127.2162)
		(size 0.4064)
		(drill 0.2032)
		(layers "F.Cu" "B.Cu")
		(net "GND")
	)
	(via
		(at 65.7781 125.1186)
		(size 0.4064)
		(drill 0.2032)
		(layers "F.Cu" "B.Cu")
		(tenting
			(front yes)
			(back yes)
		)
		(net "GND")
	)
	(via
		(at 61.2061 111.9106)
		(size 0.4064)
		(drill 0.2032)
		(layers "F.Cu" "B.Cu")
		(tenting
			(front yes)
			(back yes)
		)
		(net "GND")
	)
	(via
		(at 202.4261 101.3162)
		(size 0.4064)
		(drill 0.2032)
		(layers "F.Cu" "B.Cu")
		(net "GND")
	)
	(via
		(at 198.20352 87.5)
		(size 0.4064)
		(drill 0.2032)
		(layers "F.Cu" "B.Cu")
		(net "GND")
	)
	(via
		(at 190.55001 84.73286)
		(size 0.4064)
		(drill 0.2032)
		(layers "F.Cu" "B.Cu")
		(net "GND")
	)
	(via
		(at 66.2861 124.1026)
		(size 0.4064)
		(drill 0.2032)
		(layers "F.Cu" "B.Cu")
		(tenting
			(front yes)
			(back yes)
		)
		(net "GND")
	)
	(via
		(at 61.2061 132.2306)
		(size 0.4064)
		(drill 0.2032)
		(layers "F.Cu" "B.Cu")
		(tenting
			(front yes)
			(back yes)
		)
		(net "GND")
	)
	(via
		(at 75.4301 132.2306)
		(size 0.4064)
		(drill 0.2032)
		(layers "F.Cu" "B.Cu")
		(tenting
			(front yes)
			(back yes)
		)
		(net "GND")
	)
	(via
		(at 75.4301 105.8146)
		(size 0.4064)
		(drill 0.2032)
		(layers "F.Cu" "B.Cu")
		(tenting
			(front yes)
			(back yes)
		)
		(net "GND")
	)
	(via
		(at 71.1261 103.3662)
		(size 0.4064)
		(drill 0.2032)
		(layers "F.Cu" "B.Cu")
		(tenting
			(front yes)
			(back yes)
		)
		(net "GND")
	)
	(via
		(at 216.8261 117.2162)
		(size 0.4064)
		(drill 0.2032)
		(layers "F.Cu" "B.Cu")
		(net "GND")
	)
	(via
		(at 75.9381 90.5746)
		(size 0.4064)
		(drill 0.2032)
		(layers "F.Cu" "B.Cu")
		(tenting
			(front yes)
			(back yes)
		)
		(net "GND")
	)
	(via
		(at 127.56915 82.85044)
		(size 0.4064)
		(drill 0.2032)
		(layers "F.Cu" "B.Cu")
		(net "GND")
	)
	(via
		(at 71.8741 90.5746)
		(size 0.4064)
		(drill 0.2032)
		(layers "F.Cu" "B.Cu")
		(tenting
			(front yes)
			(back yes)
		)
		(net "GND")
	)
	(via
		(at 70.3501 140.3586)
		(size 0.4064)
		(drill 0.2032)
		(layers "F.Cu" "B.Cu")
		(tenting
			(front yes)
			(back yes)
		)
		(net "GND")
	)
	(via
		(at 174.8091 96.4036)
		(size 0.4064)
		(drill 0.2032)
		(layers "F.Cu" "B.Cu")
		(tenting
			(front yes)
			(back yes)
		)
		(net "GND")
	)
	(via
		(at 65.7781 139.3426)
		(size 0.4064)
		(drill 0.2032)
		(layers "F.Cu" "B.Cu")
		(tenting
			(front yes)
			(back yes)
		)
		(net "GND")
	)
	(via
		(at 72.3821 138.3266)
		(size 0.4064)
		(drill 0.2032)
		(layers "F.Cu" "B.Cu")
		(tenting
			(front yes)
			(back yes)
		)
		(net "GND")
	)
	(via
		(at 68.3181 105.8146)
		(size 0.4064)
		(drill 0.2032)
		(layers "F.Cu" "B.Cu")
		(tenting
			(front yes)
			(back yes)
		)
		(net "GND")
	)
	(via
		(at 69.8421 131.2146)
		(size 0.4064)
		(drill 0.2032)
		(layers "F.Cu" "B.Cu")
		(tenting
			(front yes)
			(back yes)
		)
		(net "GND")
	)
	(via
		(at 66.2861 132.2306)
		(size 0.4064)
		(drill 0.2032)
		(layers "F.Cu" "B.Cu")
		(tenting
			(front yes)
			(back yes)
		)
		(net "GND")
	)
	(via
		(at 74.9221 131.2146)
		(size 0.4064)
		(drill 0.2032)
		(layers "F.Cu" "B.Cu")
		(tenting
			(front yes)
			(back yes)
		)
		(net "GND")
	)
	(via
		(at 206.0261 133.0162)
		(size 0.4064)
		(drill 0.2032)
		(layers "F.Cu" "B.Cu")
		(tenting
			(front yes)
			(back yes)
		)
		(net "GND")
	)
	(via
		(at 175.3261 138.2162)
		(size 0.4064)
		(drill 0.2032)
		(layers "F.Cu" "B.Cu")
		(tenting
			(front yes)
			(back yes)
		)
		(net "GND")
	)
	(via
		(at 70.8581 141.3746)
		(size 0.4064)
		(drill 0.2032)
		(layers "F.Cu" "B.Cu")
		(tenting
			(front yes)
			(back yes)
		)
		(net "GND")
	)
	(via
		(at 239.3962 68.62912)
		(size 0.4064)
		(drill 0.2032)
		(layers "F.Cu" "B.Cu")
		(net "GND")
	)
	(via
		(at 71.3661 91.5906)
		(size 0.4064)
		(drill 0.2032)
		(layers "F.Cu" "B.Cu")
		(tenting
			(front yes)
			(back yes)
		)
		(net "GND")
	)
	(via
		(at 77.4621 113.9426)
		(size 0.4064)
		(drill 0.2032)
		(layers "F.Cu" "B.Cu")
		(tenting
			(front yes)
			(back yes)
		)
		(net "GND")
	)
	(via
		(at 202.1261 95.0162)
		(size 0.4064)
		(drill 0.2032)
		(layers "F.Cu" "B.Cu")
		(net "GND")
	)
	(via
		(at 175.8261 138.2162)
		(size 0.4064)
		(drill 0.2032)
		(layers "F.Cu" "B.Cu")
		(tenting
			(front yes)
			(back yes)
		)
		(net "GND")
	)
	(via
		(at 71.8741 112.9266)
		(size 0.4064)
		(drill 0.2032)
		(layers "F.Cu" "B.Cu")
		(tenting
			(front yes)
			(back yes)
		)
		(net "GND")
	)
	(via
		(at 76.4461 111.9106)
		(size 0.4064)
		(drill 0.2032)
		(layers "F.Cu" "B.Cu")
		(tenting
			(front yes)
			(back yes)
		)
		(net "GND")
	)
	(via
		(at 70.8581 92.6066)
		(size 0.4064)
		(drill 0.2032)
		(layers "F.Cu" "B.Cu")
		(tenting
			(front yes)
			(back yes)
		)
		(net "GND")
	)
	(via
		(at 67.3021 97.6866)
		(size 0.4064)
		(drill 0.2032)
		(layers "F.Cu" "B.Cu")
		(tenting
			(front yes)
			(back yes)
		)
		(net "GND")
	)
	(via
		(at 198.1261 106.8286)
		(size 0.4064)
		(drill 0.2032)
		(layers "F.Cu" "B.Cu")
		(tenting
			(front yes)
			(back yes)
		)
		(net "GND")
	)
	(via
		(at 67.8101 110.8946)
		(size 0.4064)
		(drill 0.2032)
		(layers "F.Cu" "B.Cu")
		(tenting
			(front yes)
			(back yes)
		)
		(net "GND")
	)
	(via
		(at 204.2261 110.6162)
		(size 0.4064)
		(drill 0.2032)
		(layers "F.Cu" "B.Cu")
		(net "GND")
	)
	(via
		(at 77.4621 126.1346)
		(size 0.4064)
		(drill 0.2032)
		(layers "F.Cu" "B.Cu")
		(tenting
			(front yes)
			(back yes)
		)
		(net "GND")
	)
	(via
		(at 114.5461 154.3286)
		(size 0.4064)
		(drill 0.2032)
		(layers "F.Cu" "B.Cu")
		(tenting
			(front yes)
			(back yes)
		)
		(net "GND")
	)
	(via
		(at 74.3761 138.1162)
		(size 0.4064)
		(drill 0.2032)
		(layers "F.Cu" "B.Cu")
		(tenting
			(front yes)
			(back yes)
		)
		(net "GND")
	)
	(via
		(at 60.6981 119.0226)
		(size 0.4064)
		(drill 0.2032)
		(layers "F.Cu" "B.Cu")
		(tenting
			(front yes)
			(back yes)
		)
		(net "GND")
	)
	(via
		(at 70.8581 139.3426)
		(size 0.4064)
		(drill 0.2032)
		(layers "F.Cu" "B.Cu")
		(tenting
			(front yes)
			(back yes)
		)
		(net "GND")
	)
	(via
		(at 76.9541 114.9586)
		(size 0.4064)
		(drill 0.2032)
		(layers "F.Cu" "B.Cu")
		(tenting
			(front yes)
			(back yes)
		)
		(net "GND")
	)
	(via
		(at 66.2861 111.9106)
		(size 0.4064)
		(drill 0.2032)
		(layers "F.Cu" "B.Cu")
		(tenting
			(front yes)
			(back yes)
		)
		(net "GND")
	)
	(via
		(at 91.3261 63.5162)
		(size 0.4064)
		(drill 0.2032)
		(layers "F.Cu" "B.Cu")
		(tenting
			(front yes)
			(back yes)
		)
		(net "GND")
	)
	(via
		(at 221.3681 64.6162)
		(size 0.4064)
		(drill 0.2032)
		(layers "F.Cu" "B.Cu")
		(tenting
			(front yes)
			(back yes)
		)
		(net "GND")
	)
	(via
		(at 230.94871 74.35073)
		(size 0.4064)
		(drill 0.2032)
		(layers "F.Cu" "B.Cu")
		(net "GND")
	)
	(via
		(at 65.7781 96.6706)
		(size 0.4064)
		(drill 0.2032)
		(layers "F.Cu" "B.Cu")
		(tenting
			(front yes)
			(back yes)
		)
		(net "GND")
	)
	(via
		(at 207.7261 78.3162)
		(size 0.4064)
		(drill 0.2032)
		(layers "F.Cu" "B.Cu")
		(net "GND")
	)
	(via
		(at 88.2761 86.0162)
		(size 0.5)
		(drill 0.2)
		(layers "F.Cu" "B.Cu")
		(net "GND")
	)
	(via
		(at 214.3261 129.2162)
		(size 0.4064)
		(drill 0.2032)
		(layers "F.Cu" "B.Cu")
		(net "GND")
	)
	(via
		(at 71.3661 142.3906)
		(size 0.4064)
		(drill 0.2032)
		(layers "F.Cu" "B.Cu")
		(tenting
			(front yes)
			(back yes)
		)
		(net "GND")
	)
	(via
		(at 66.7941 92.6066)
		(size 0.4064)
		(drill 0.2032)
		(layers "F.Cu" "B.Cu")
		(tenting
			(front yes)
			(back yes)
		)
		(net "GND")
	)
	(via
		(at 68.8261 129.1826)
		(size 0.4064)
		(drill 0.2032)
		(layers "F.Cu" "B.Cu")
		(tenting
			(front yes)
			(back yes)
		)
		(net "GND")
	)
	(via
		(at 72.3821 113.9426)
		(size 0.4064)
		(drill 0.2032)
		(layers "F.Cu" "B.Cu")
		(tenting
			(front yes)
			(back yes)
		)
		(net "GND")
	)
	(via
		(at 172.47108 89.78033)
		(size 0.4064)
		(drill 0.2032)
		(layers "F.Cu" "B.Cu")
		(net "GND")
	)
	(via
		(at 149.1671 107.3064)
		(size 0.4064)
		(drill 0.2032)
		(layers "F.Cu" "B.Cu")
		(tenting
			(front yes)
			(back yes)
		)
		(net "GND")
	)
	(via
		(at 74.9221 139.3426)
		(size 0.4064)
		(drill 0.2032)
		(layers "F.Cu" "B.Cu")
		(tenting
			(front yes)
			(back yes)
		)
		(net "GND")
	)
	(via
		(at 76.4461 103.7826)
		(size 0.4064)
		(drill 0.2032)
		(layers "F.Cu" "B.Cu")
		(tenting
			(front yes)
			(back yes)
		)
		(net "GND")
	)
	(via
		(at 67.3021 111.9106)
		(size 0.4064)
		(drill 0.2032)
		(layers "F.Cu" "B.Cu")
		(tenting
			(front yes)
			(back yes)
		)
		(net "GND")
	)
	(via
		(at 207.4261 127.3162)
		(size 0.4064)
		(drill 0.2032)
		(layers "F.Cu" "B.Cu")
		(net "GND")
	)
	(via
		(at 196.6261 119.6242)
		(size 0.4064)
		(drill 0.2032)
		(layers "F.Cu" "B.Cu")
		(tenting
			(front yes)
			(back yes)
		)
		(net "GND")
	)
	(via
		(at 73.9061 90.5746)
		(size 0.4064)
		(drill 0.2032)
		(layers "F.Cu" "B.Cu")
		(tenting
			(front yes)
			(back yes)
		)
		(net "GND")
	)
	(via
		(at 68.3181 113.9426)
		(size 0.4064)
		(drill 0.2032)
		(layers "F.Cu" "B.Cu")
		(tenting
			(front yes)
			(back yes)
		)
		(net "GND")
	)
	(via
		(at 72.8901 116.9906)
		(size 0.4064)
		(drill 0.2032)
		(layers "F.Cu" "B.Cu")
		(tenting
			(front yes)
			(back yes)
		)
		(net "GND")
	)
	(via
		(at 67.3021 103.7826)
		(size 0.4064)
		(drill 0.2032)
		(layers "F.Cu" "B.Cu")
		(tenting
			(front yes)
			(back yes)
		)
		(net "GND")
	)
	(via
		(at 233.7261 65.6162)
		(size 0.4064)
		(drill 0.2032)
		(layers "F.Cu" "B.Cu")
		(tenting
			(front yes)
			(back yes)
		)
		(net "GND")
	)
	(via
		(at 61.7141 131.2146)
		(size 0.4064)
		(drill 0.2032)
		(layers "F.Cu" "B.Cu")
		(tenting
			(front yes)
			(back yes)
		)
		(net "GND")
	)
	(via
		(at 66.7941 104.7986)
		(size 0.4064)
		(drill 0.2032)
		(layers "F.Cu" "B.Cu")
		(tenting
			(front yes)
			(back yes)
		)
		(net "GND")
	)
	(via
		(at 77.4621 144.4226)
		(size 0.4064)
		(drill 0.2032)
		(layers "F.Cu" "B.Cu")
		(tenting
			(front yes)
			(back yes)
		)
		(net "GND")
	)
	(via
		(at 76.9541 112.9266)
		(size 0.4064)
		(drill 0.2032)
		(layers "F.Cu" "B.Cu")
		(tenting
			(front yes)
			(back yes)
		)
		(net "GND")
	)
	(via
		(at 179.0261 129.7286)
		(size 0.4064)
		(drill 0.2032)
		(layers "F.Cu" "B.Cu")
		(tenting
			(front yes)
			(back yes)
		)
		(net "GND")
	)
	(via
		(at 76.9541 123.0866)
		(size 0.4064)
		(drill 0.2032)
		(layers "F.Cu" "B.Cu")
		(tenting
			(front yes)
			(back yes)
		)
		(net "GND")
	)
	(via
		(at 66.2861 144.4226)
		(size 0.4064)
		(drill 0.2032)
		(layers "F.Cu" "B.Cu")
		(tenting
			(front yes)
			(back yes)
		)
		(net "GND")
	)
	(via
		(at 76.9541 92.6066)
		(size 0.4064)
		(drill 0.2032)
		(layers "F.Cu" "B.Cu")
		(tenting
			(front yes)
			(back yes)
		)
		(net "GND")
	)
	(via
		(at 149.1925 109.7956)
		(size 0.4064)
		(drill 0.2032)
		(layers "F.Cu" "B.Cu")
		(tenting
			(front yes)
			(back yes)
		)
		(net "GND")
	)
	(via
		(at 83.8761 107.3662)
		(size 0.4064)
		(drill 0.2032)
		(layers "F.Cu" "B.Cu")
		(tenting
			(front yes)
			(back yes)
		)
		(net "GND")
	)
	(via
		(at 67.3021 134.2626)
		(size 0.4064)
		(drill 0.2032)
		(layers "F.Cu" "B.Cu")
		(tenting
			(front yes)
			(back yes)
		)
		(net "GND")
	)
	(via
		(at 233.7261 71.0162)
		(size 0.4064)
		(drill 0.2032)
		(layers "F.Cu" "B.Cu")
		(tenting
			(front yes)
			(back yes)
		)
		(net "GND")
	)
	(via
		(at 75.9381 131.2146)
		(size 0.4064)
		(drill 0.2032)
		(layers "F.Cu" "B.Cu")
		(tenting
			(front yes)
			(back yes)
		)
		(net "GND")
	)
	(via
		(at 96.1261 75.3286)
		(size 0.4064)
		(drill 0.2032)
		(layers "F.Cu" "B.Cu")
		(tenting
			(front yes)
			(back yes)
		)
		(net "GND")
	)
	(via
		(at 67.8101 119.0226)
		(size 0.4064)
		(drill 0.2032)
		(layers "F.Cu" "B.Cu")
		(tenting
			(front yes)
			(back yes)
		)
		(net "GND")
	)
	(via
		(at 215.5261 118.2162)
		(size 0.4064)
		(drill 0.2032)
		(layers "F.Cu" "B.Cu")
		(net "GND")
	)
	(via
		(at 66.2861 105.8146)
		(size 0.4064)
		(drill 0.2032)
		(layers "F.Cu" "B.Cu")
		(tenting
			(front yes)
			(back yes)
		)
		(net "GND")
	)
	(via
		(at 212.0261 112.7162)
		(size 0.4064)
		(drill 0.2032)
		(layers "F.Cu" "B.Cu")
		(net "GND")
	)
	(via
		(at 73.3981 113.9426)
		(size 0.4064)
		(drill 0.2032)
		(layers "F.Cu" "B.Cu")
		(tenting
			(front yes)
			(back yes)
		)
		(net "GND")
	)
	(via
		(at 204.0261 130.0162)
		(size 0.4064)
		(drill 0.2032)
		(layers "F.Cu" "B.Cu")
		(net "GND")
	)
	(via
		(at 69.3341 128.1666)
		(size 0.4064)
		(drill 0.2032)
		(layers "F.Cu" "B.Cu")
		(tenting
			(front yes)
			(back yes)
		)
		(net "GND")
	)
	(via
		(at 68.8261 119.0226)
		(size 0.4064)
		(drill 0.2032)
		(layers "F.Cu" "B.Cu")
		(tenting
			(front yes)
			(back yes)
		)
		(net "GND")
	)
	(via
		(at 238.9261 137.0162)
		(size 0.4064)
		(drill 0.2032)
		(layers "F.Cu" "B.Cu")
		(net "GND")
	)
	(via
		(at 67.8101 131.2146)
		(size 0.4064)
		(drill 0.2032)
		(layers "F.Cu" "B.Cu")
		(tenting
			(front yes)
			(back yes)
		)
		(net "GND")
	)
	(via
		(at 68.8261 96.6706)
		(size 0.4064)
		(drill 0.2032)
		(layers "F.Cu" "B.Cu")
		(tenting
			(front yes)
			(back yes)
		)
		(net "GND")
	)
	(via
		(at 66.7941 90.5746)
		(size 0.4064)
		(drill 0.2032)
		(layers "F.Cu" "B.Cu")
		(tenting
			(front yes)
			(back yes)
		)
		(net "GND")
	)
	(via
		(at 67.3021 118.0066)
		(size 0.4064)
		(drill 0.2032)
		(layers "F.Cu" "B.Cu")
		(tenting
			(front yes)
			(back yes)
		)
		(net "GND")
	)
	(via
		(at 80.3761 141.6162)
		(size 0.4064)
		(drill 0.2032)
		(layers "F.Cu" "B.Cu")
		(tenting
			(front yes)
			(back yes)
		)
		(net "GND")
	)
	(via
		(at 77.4621 111.9106)
		(size 0.4064)
		(drill 0.2032)
		(layers "F.Cu" "B.Cu")
		(tenting
			(front yes)
			(back yes)
		)
		(net "GND")
	)
	(via
		(at 66.7941 106.8306)
		(size 0.4064)
		(drill 0.2032)
		(layers "F.Cu" "B.Cu")
		(tenting
			(front yes)
			(back yes)
		)
		(net "GND")
	)
	(via
		(at 234.2261 109.4162)
		(size 0.4064)
		(drill 0.2032)
		(layers "F.Cu" "B.Cu")
		(net "GND")
	)
	(via
		(at 136.3261 115.0162)
		(size 0.4064)
		(drill 0.2032)
		(layers "F.Cu" "B.Cu")
		(tenting
			(front yes)
			(back yes)
		)
		(net "GND")
	)
	(via
		(at 219.7261 120.0162)
		(size 0.4064)
		(drill 0.2032)
		(layers "F.Cu" "B.Cu")
		(net "GND")
	)
	(via
		(at 198.1261 111.8286)
		(size 0.4064)
		(drill 0.2032)
		(layers "F.Cu" "B.Cu")
		(tenting
			(front yes)
			(back yes)
		)
		(net "GND")
	)
	(via
		(at 143.16077 114.8267)
		(size 0.4064)
		(drill 0.2032)
		(layers "F.Cu" "B.Cu")
		(net "GND")
	)
	(via
		(at 81.3761 92.6162)
		(size 0.4064)
		(drill 0.2032)
		(layers "F.Cu" "B.Cu")
		(tenting
			(front yes)
			(back yes)
		)
		(net "GND")
	)
	(via
		(at 196.6261 121.8286)
		(size 0.4064)
		(drill 0.2032)
		(layers "F.Cu" "B.Cu")
		(tenting
			(front yes)
			(back yes)
		)
		(net "GND")
	)
	(via
		(at 77.4621 91.5906)
		(size 0.4064)
		(drill 0.2032)
		(layers "F.Cu" "B.Cu")
		(tenting
			(front yes)
			(back yes)
		)
		(net "GND")
	)
	(via
		(at 71.8741 133.2466)
		(size 0.4064)
		(drill 0.2032)
		(layers "F.Cu" "B.Cu")
		(tenting
			(front yes)
			(back yes)
		)
		(net "GND")
	)
	(via
		(at 61.2061 118.0066)
		(size 0.4064)
		(drill 0.2032)
		(layers "F.Cu" "B.Cu")
		(tenting
			(front yes)
			(back yes)
		)
		(net "GND")
	)
	(via
		(at 75.9381 119.0226)
		(size 0.4064)
		(drill 0.2032)
		(layers "F.Cu" "B.Cu")
		(tenting
			(front yes)
			(back yes)
		)
		(net "GND")
	)
	(via
		(at 65.7781 131.2146)
		(size 0.4064)
		(drill 0.2032)
		(layers "F.Cu" "B.Cu")
		(tenting
			(front yes)
			(back yes)
		)
		(net "GND")
	)
	(via
		(at 76.9541 106.8306)
		(size 0.4064)
		(drill 0.2032)
		(layers "F.Cu" "B.Cu")
		(tenting
			(front yes)
			(back yes)
		)
		(net "GND")
	)
	(via
		(at 76.9541 110.8946)
		(size 0.4064)
		(drill 0.2032)
		(layers "F.Cu" "B.Cu")
		(tenting
			(front yes)
			(back yes)
		)
		(net "GND")
	)
	(via
		(at 204.0261 107.9162)
		(size 0.4064)
		(drill 0.2032)
		(layers "F.Cu" "B.Cu")
		(net "GND")
	)
	(via
		(at 67.8101 123.0866)
		(size 0.4064)
		(drill 0.2032)
		(layers "F.Cu" "B.Cu")
		(tenting
			(front yes)
			(back yes)
		)
		(net "GND")
	)
	(via
		(at 79.00081 84.89904)
		(size 0.4064)
		(drill 0.2032)
		(layers "F.Cu" "B.Cu")
		(net "GND")
	)
	(via
		(at 74.4141 142.3906)
		(size 0.4064)
		(drill 0.2032)
		(layers "F.Cu" "B.Cu")
		(tenting
			(front yes)
			(back yes)
		)
		(net "GND")
	)
	(via
		(at 71.3661 93.6226)
		(size 0.4064)
		(drill 0.2032)
		(layers "F.Cu" "B.Cu")
		(tenting
			(front yes)
			(back yes)
		)
		(net "GND")
	)
	(via
		(at 67.8101 116.9906)
		(size 0.4064)
		(drill 0.2032)
		(layers "F.Cu" "B.Cu")
		(tenting
			(front yes)
			(back yes)
		)
		(net "GND")
	)
	(via
		(at 172.83584 134.15826)
		(size 0.4064)
		(drill 0.2032)
		(layers "F.Cu" "B.Cu")
		(tenting
			(front yes)
			(back yes)
		)
		(net "GND")
	)
	(via
		(at 75.4301 91.5906)
		(size 0.4064)
		(drill 0.2032)
		(layers "F.Cu" "B.Cu")
		(tenting
			(front yes)
			(back yes)
		)
		(net "GND")
	)
	(via
		(at 60.6981 139.3426)
		(size 0.4064)
		(drill 0.2032)
		(layers "F.Cu" "B.Cu")
		(tenting
			(front yes)
			(back yes)
		)
		(net "GND")
	)
	(via
		(at 95.0261 63.3162)
		(size 0.4064)
		(drill 0.2032)
		(layers "F.Cu" "B.Cu")
		(tenting
			(front yes)
			(back yes)
		)
		(net "GND")
	)
	(via
		(at 57.6501 135.2786)
		(size 0.4064)
		(drill 0.2032)
		(layers "F.Cu" "B.Cu")
		(tenting
			(front yes)
			(back yes)
		)
		(net "GND")
	)
	(via
		(at 77.4621 120.0386)
		(size 0.4064)
		(drill 0.2032)
		(layers "F.Cu" "B.Cu")
		(tenting
			(front yes)
			(back yes)
		)
		(net "GND")
	)
	(via
		(at 67.3021 124.1026)
		(size 0.4064)
		(drill 0.2032)
		(layers "F.Cu" "B.Cu")
		(tenting
			(front yes)
			(back yes)
		)
		(net "GND")
	)
	(via
		(at 73.3981 118.0066)
		(size 0.4064)
		(drill 0.2032)
		(layers "F.Cu" "B.Cu")
		(tenting
			(front yes)
			(back yes)
		)
		(net "GND")
	)
	(via
		(at 208.20129 127.28681)
		(size 0.4064)
		(drill 0.2032)
		(layers "F.Cu" "B.Cu")
		(net "GND")
	)
	(via
		(at 233.3261 57.5162)
		(size 0.4064)
		(drill 0.2032)
		(layers "F.Cu" "B.Cu")
		(tenting
			(front yes)
			(back yes)
		)
		(net "GND")
	)
	(via
		(at 71.8741 96.6706)
		(size 0.4064)
		(drill 0.2032)
		(layers "F.Cu" "B.Cu")
		(tenting
			(front yes)
			(back yes)
		)
		(net "GND")
	)
	(via
		(at 69.8421 133.2466)
		(size 0.4064)
		(drill 0.2032)
		(layers "F.Cu" "B.Cu")
		(tenting
			(front yes)
			(back yes)
		)
		(net "GND")
	)
	(via
		(at 74.4141 126.1346)
		(size 0.4064)
		(drill 0.2032)
		(layers "F.Cu" "B.Cu")
		(tenting
			(front yes)
			(back yes)
		)
		(net "GND")
	)
	(via
		(at 68.3181 97.6866)
		(size 0.4064)
		(drill 0.2032)
		(layers "F.Cu" "B.Cu")
		(tenting
			(front yes)
			(back yes)
		)
		(net "GND")
	)
	(via
		(at 74.9221 116.9906)
		(size 0.4064)
		(drill 0.2032)
		(layers "F.Cu" "B.Cu")
		(tenting
			(front yes)
			(back yes)
		)
		(net "GND")
	)
	(via
		(at 61.2061 105.8146)
		(size 0.4064)
		(drill 0.2032)
		(layers "F.Cu" "B.Cu")
		(tenting
			(front yes)
			(back yes)
		)
		(net "GND")
	)
	(via
		(at 118.03129 154.41678)
		(size 0.4064)
		(drill 0.2032)
		(layers "F.Cu" "B.Cu")
		(tenting
			(front yes)
			(back yes)
		)
		(net "GND")
	)
	(via
		(at 194.8761 81.5866)
		(size 0.4064)
		(drill 0.2032)
		(layers "F.Cu" "B.Cu")
		(tenting
			(front yes)
			(back yes)
		)
		(net "GND")
	)
	(via
		(at 69.3341 103.7826)
		(size 0.4064)
		(drill 0.2032)
		(layers "F.Cu" "B.Cu")
		(tenting
			(front yes)
			(back yes)
		)
		(net "GND")
	)
	(via
		(at 64.7621 90.5746)
		(size 0.4064)
		(drill 0.2032)
		(layers "F.Cu" "B.Cu")
		(tenting
			(front yes)
			(back yes)
		)
		(net "GND")
	)
	(via
		(at 187.2261 88.7162)
		(size 0.4064)
		(drill 0.2032)
		(layers "F.Cu" "B.Cu")
		(net "GND")
	)
	(via
		(at 221.8261 120.1162)
		(size 0.4064)
		(drill 0.2032)
		(layers "F.Cu" "B.Cu")
		(net "GND")
	)
	(via
		(at 68.3181 120.0386)
		(size 0.4064)
		(drill 0.2032)
		(layers "F.Cu" "B.Cu")
		(tenting
			(front yes)
			(back yes)
		)
		(net "GND")
	)
	(via
		(at 69.3341 142.3906)
		(size 0.4064)
		(drill 0.2032)
		(layers "F.Cu" "B.Cu")
		(tenting
			(front yes)
			(back yes)
		)
		(net "GND")
	)
	(via
		(at 72.8901 90.5746)
		(size 0.4064)
		(drill 0.2032)
		(layers "F.Cu" "B.Cu")
		(tenting
			(front yes)
			(back yes)
		)
		(net "GND")
	)
	(via
		(at 76.9541 141.3746)
		(size 0.4064)
		(drill 0.2032)
		(layers "F.Cu" "B.Cu")
		(tenting
			(front yes)
			(back yes)
		)
		(net "GND")
	)
	(via
		(at 218.6261 119.0162)
		(size 0.4064)
		(drill 0.2032)
		(layers "F.Cu" "B.Cu")
		(net "GND")
	)
	(via
		(at 65.7781 123.0866)
		(size 0.4064)
		(drill 0.2032)
		(layers "F.Cu" "B.Cu")
		(tenting
			(front yes)
			(back yes)
		)
		(net "GND")
	)
	(via
		(at 70.3501 138.3266)
		(size 0.4064)
		(drill 0.2032)
		(layers "F.Cu" "B.Cu")
		(tenting
			(front yes)
			(back yes)
		)
		(net "GND")
	)
	(via
		(at 209.1261 127.3162)
		(size 0.4064)
		(drill 0.2032)
		(layers "F.Cu" "B.Cu")
		(net "GND")
	)
	(via
		(at 68.3181 93.6226)
		(size 0.4064)
		(drill 0.2032)
		(layers "F.Cu" "B.Cu")
		(tenting
			(front yes)
			(back yes)
		)
		(net "GND")
	)
	(via
		(at 198.1261 121.8286)
		(size 0.4064)
		(drill 0.2032)
		(layers "F.Cu" "B.Cu")
		(tenting
			(front yes)
			(back yes)
		)
		(net "GND")
	)
	(via
		(at 77.4621 138.3266)
		(size 0.4064)
		(drill 0.2032)
		(layers "F.Cu" "B.Cu")
		(tenting
			(front yes)
			(back yes)
		)
		(net "GND")
	)
	(via
		(at 238.90342 135.34917)
		(size 0.4064)
		(drill 0.2032)
		(layers "F.Cu" "B.Cu")
		(net "GND")
	)
	(via
		(at 88.3761 67.8286)
		(size 0.4064)
		(drill 0.2032)
		(layers "F.Cu" "B.Cu")
		(tenting
			(front yes)
			(back yes)
		)
		(net "GND")
	)
	(via
		(at 201.4261 122.6162)
		(size 0.4064)
		(drill 0.2032)
		(layers "F.Cu" "B.Cu")
		(net "GND")
	)
	(via
		(at 63.2381 144.4226)
		(size 0.4064)
		(drill 0.2032)
		(layers "F.Cu" "B.Cu")
		(tenting
			(front yes)
			(back yes)
		)
		(net "GND")
	)
	(via
		(at 77.4621 109.8786)
		(size 0.4064)
		(drill 0.2032)
		(layers "F.Cu" "B.Cu")
		(tenting
			(front yes)
			(back yes)
		)
		(net "GND")
	)
	(via
		(at 67.8101 106.8306)
		(size 0.4064)
		(drill 0.2032)
		(layers "F.Cu" "B.Cu")
		(tenting
			(front yes)
			(back yes)
		)
		(net "GND")
	)
	(via
		(at 231.41099 82.31086)
		(size 0.4064)
		(drill 0.2032)
		(layers "F.Cu" "B.Cu")
		(net "GND")
	)
	(via
		(at 65.2701 103.7826)
		(size 0.4064)
		(drill 0.2032)
		(layers "F.Cu" "B.Cu")
		(tenting
			(front yes)
			(back yes)
		)
		(net "GND")
	)
	(via
		(at 128.98452 154.23884)
		(size 0.4064)
		(drill 0.2032)
		(layers "F.Cu" "B.Cu")
		(tenting
			(front yes)
			(back yes)
		)
		(net "GND")
	)
	(via
		(at 63.7461 116.9906)
		(size 0.4064)
		(drill 0.2032)
		(layers "F.Cu" "B.Cu")
		(tenting
			(front yes)
			(back yes)
		)
		(net "GND")
	)
	(via
		(at 92.1261 76.2206)
		(size 0.4064)
		(drill 0.2032)
		(layers "F.Cu" "B.Cu")
		(tenting
			(front yes)
			(back yes)
		)
		(net "GND")
	)
	(via
		(at 221.7261 118.1162)
		(size 0.4064)
		(drill 0.2032)
		(layers "F.Cu" "B.Cu")
		(net "GND")
	)
	(via
		(at 76.9541 133.2466)
		(size 0.4064)
		(drill 0.2032)
		(layers "F.Cu" "B.Cu")
		(tenting
			(front yes)
			(back yes)
		)
		(net "GND")
	)
	(via
		(at 74.3761 106.1162)
		(size 0.4064)
		(drill 0.2032)
		(layers "F.Cu" "B.Cu")
		(tenting
			(front yes)
			(back yes)
		)
		(net "GND")
	)
	(via
		(at 60.6981 116.9906)
		(size 0.4064)
		(drill 0.2032)
		(layers "F.Cu" "B.Cu")
		(tenting
			(front yes)
			(back yes)
		)
		(net "GND")
	)
	(via
		(at 61.2061 91.5906)
		(size 0.4064)
		(drill 0.2032)
		(layers "F.Cu" "B.Cu")
		(tenting
			(front yes)
			(back yes)
		)
		(net "GND")
	)
	(via
		(at 75.9381 112.9266)
		(size 0.4064)
		(drill 0.2032)
		(layers "F.Cu" "B.Cu")
		(tenting
			(front yes)
			(back yes)
		)
		(net "GND")
	)
	(via
		(at 67.8101 141.3746)
		(size 0.4064)
		(drill 0.2032)
		(layers "F.Cu" "B.Cu")
		(tenting
			(front yes)
			(back yes)
		)
		(net "GND")
	)
	(via
		(at 66.7941 119.0226)
		(size 0.4064)
		(drill 0.2032)
		(layers "F.Cu" "B.Cu")
		(tenting
			(front yes)
			(back yes)
		)
		(net "GND")
	)
	(via
		(at 61.7141 116.9906)
		(size 0.4064)
		(drill 0.2032)
		(layers "F.Cu" "B.Cu")
		(tenting
			(front yes)
			(back yes)
		)
		(net "GND")
	)
	(via
		(at 56.6341 131.2146)
		(size 0.4064)
		(drill 0.2032)
		(layers "F.Cu" "B.Cu")
		(tenting
			(front yes)
			(back yes)
		)
		(net "GND")
	)
	(via
		(at 235.0261 123.9162)
		(size 0.4064)
		(drill 0.2032)
		(layers "F.Cu" "B.Cu")
		(net "GND")
	)
	(via
		(at 88.1261 81.1162)
		(size 0.4064)
		(drill 0.2032)
		(layers "F.Cu" "B.Cu")
		(tenting
			(front yes)
			(back yes)
		)
		(net "GND")
	)
	(via
		(at 122.8527 154.2818)
		(size 0.4064)
		(drill 0.2032)
		(layers "F.Cu" "B.Cu")
		(tenting
			(front yes)
			(back yes)
		)
		(net "GND")
	)
	(via
		(at 211.8261 84.3162)
		(size 0.4064)
		(drill 0.2032)
		(layers "F.Cu" "B.Cu")
		(net "GND")
	)
	(via
		(at 76.4461 109.8786)
		(size 0.4064)
		(drill 0.2032)
		(layers "F.Cu" "B.Cu")
		(tenting
			(front yes)
			(back yes)
		)
		(net "GND")
	)
	(via
		(at 76.4461 132.2306)
		(size 0.4064)
		(drill 0.2032)
		(layers "F.Cu" "B.Cu")
		(tenting
			(front yes)
			(back yes)
		)
		(net "GND")
	)
	(via
		(at 71.8741 114.9586)
		(size 0.4064)
		(drill 0.2032)
		(layers "F.Cu" "B.Cu")
		(tenting
			(front yes)
			(back yes)
		)
		(net "GND")
	)
	(via
		(at 196.6261 111.8286)
		(size 0.4064)
		(drill 0.2032)
		(layers "F.Cu" "B.Cu")
		(tenting
			(front yes)
			(back yes)
		)
		(net "GND")
	)
	(via
		(at 76.4461 140.3586)
		(size 0.4064)
		(drill 0.2032)
		(layers "F.Cu" "B.Cu")
		(tenting
			(front yes)
			(back yes)
		)
		(net "GND")
	)
	(via
		(at 76.4461 124.1026)
		(size 0.4064)
		(drill 0.2032)
		(layers "F.Cu" "B.Cu")
		(tenting
			(front yes)
			(back yes)
		)
		(net "GND")
	)
	(via
		(at 172.6261 133.4162)
		(size 0.4064)
		(drill 0.2032)
		(layers "F.Cu" "B.Cu")
		(tenting
			(front yes)
			(back yes)
		)
		(net "GND")
	)
	(via
		(at 71.3661 144.4226)
		(size 0.4064)
		(drill 0.2032)
		(layers "F.Cu" "B.Cu")
		(tenting
			(front yes)
			(back yes)
		)
		(net "GND")
	)
	(via
		(at 56.6341 121.0546)
		(size 0.4064)
		(drill 0.2032)
		(layers "F.Cu" "B.Cu")
		(tenting
			(front yes)
			(back yes)
		)
		(net "GND")
	)
	(via
		(at 66.2861 134.2626)
		(size 0.4064)
		(drill 0.2032)
		(layers "F.Cu" "B.Cu")
		(tenting
			(front yes)
			(back yes)
		)
		(net "GND")
	)
	(via
		(at 165.0511 96.39356)
		(size 0.4064)
		(drill 0.2032)
		(layers "F.Cu" "B.Cu")
		(tenting
			(front yes)
			(back yes)
		)
		(net "GND")
	)
	(via
		(at 74.4141 118.0066)
		(size 0.4064)
		(drill 0.2032)
		(layers "F.Cu" "B.Cu")
		(tenting
			(front yes)
			(back yes)
		)
		(net "GND")
	)
	(via
		(at 77.4621 93.6226)
		(size 0.4064)
		(drill 0.2032)
		(layers "F.Cu" "B.Cu")
		(tenting
			(front yes)
			(back yes)
		)
		(net "GND")
	)
	(via
		(at 234.1261 62.6162)
		(size 0.4064)
		(drill 0.2032)
		(layers "F.Cu" "B.Cu")
		(tenting
			(front yes)
			(back yes)
		)
		(net "GND")
	)
	(via
		(at 66.7941 137.3106)
		(size 0.4064)
		(drill 0.2032)
		(layers "F.Cu" "B.Cu")
		(tenting
			(front yes)
			(back yes)
		)
		(net "GND")
	)
	(via
		(at 169.9761 95.2286)
		(size 0.4064)
		(drill 0.2032)
		(layers "F.Cu" "B.Cu")
		(tenting
			(front yes)
			(back yes)
		)
		(net "GND")
	)
	(via
		(at 69.8421 139.3426)
		(size 0.4064)
		(drill 0.2032)
		(layers "F.Cu" "B.Cu")
		(tenting
			(front yes)
			(back yes)
		)
		(net "GND")
	)
	(via
		(at 70.3501 144.4226)
		(size 0.4064)
		(drill 0.2032)
		(layers "F.Cu" "B.Cu")
		(tenting
			(front yes)
			(back yes)
		)
		(net "GND")
	)
	(via
		(at 64.2541 144.4226)
		(size 0.4064)
		(drill 0.2032)
		(layers "F.Cu" "B.Cu")
		(tenting
			(front yes)
			(back yes)
		)
		(net "GND")
	)
	(via
		(at 66.7941 121.0546)
		(size 0.4064)
		(drill 0.2032)
		(layers "F.Cu" "B.Cu")
		(tenting
			(front yes)
			(back yes)
		)
		(net "GND")
	)
	(via
		(at 90.4761 87.1162)
		(size 0.5)
		(drill 0.2)
		(layers "F.Cu" "B.Cu")
		(net "GND")
	)
	(via
		(at 73.9061 116.9906)
		(size 0.4064)
		(drill 0.2032)
		(layers "F.Cu" "B.Cu")
		(tenting
			(front yes)
			(back yes)
		)
		(net "GND")
	)
	(via
		(at 232.5261 80.0162)
		(size 0.4064)
		(drill 0.2032)
		(layers "F.Cu" "B.Cu")
		(net "GND")
	)
	(via
		(at 65.7781 137.3106)
		(size 0.4064)
		(drill 0.2032)
		(layers "F.Cu" "B.Cu")
		(tenting
			(front yes)
			(back yes)
		)
		(net "GND")
	)
	(via
		(at 222.9261 81.2162)
		(size 0.4064)
		(drill 0.2032)
		(layers "F.Cu" "B.Cu")
		(net "GND")
	)
	(via
		(at 66.7941 96.6706)
		(size 0.4064)
		(drill 0.2032)
		(layers "F.Cu" "B.Cu")
		(tenting
			(front yes)
			(back yes)
		)
		(net "GND")
	)
	(via
		(at 128.0261 85.9162)
		(size 0.4064)
		(drill 0.2032)
		(layers "F.Cu" "B.Cu")
		(net "GND")
	)
	(via
		(at 67.3021 132.2306)
		(size 0.4064)
		(drill 0.2032)
		(layers "F.Cu" "B.Cu")
		(tenting
			(front yes)
			(back yes)
		)
		(net "GND")
	)
	(via
		(at 88.2761 87.1162)
		(size 0.5)
		(drill 0.2)
		(layers "F.Cu" "B.Cu")
		(net "GND")
	)
	(via
		(at 68.3181 91.5906)
		(size 0.4064)
		(drill 0.2032)
		(layers "F.Cu" "B.Cu")
		(tenting
			(front yes)
			(back yes)
		)
		(net "GND")
	)
	(via
		(at 67.3021 120.0386)
		(size 0.4064)
		(drill 0.2032)
		(layers "F.Cu" "B.Cu")
		(tenting
			(front yes)
			(back yes)
		)
		(net "GND")
	)
	(via
		(at 172.2261 138.1162)
		(size 0.4064)
		(drill 0.2032)
		(layers "F.Cu" "B.Cu")
		(tenting
			(front yes)
			(back yes)
		)
		(net "GND")
	)
	(via
		(at 57.6501 108.8626)
		(size 0.4064)
		(drill 0.2032)
		(layers "F.Cu" "B.Cu")
		(tenting
			(front yes)
			(back yes)
		)
		(net "GND")
	)
	(via
		(at 202.5261 104.9162)
		(size 0.4064)
		(drill 0.2032)
		(layers "F.Cu" "B.Cu")
		(net "GND")
	)
	(via
		(at 67.8101 90.5746)
		(size 0.4064)
		(drill 0.2032)
		(layers "F.Cu" "B.Cu")
		(tenting
			(front yes)
			(back yes)
		)
		(net "GND")
	)
	(via
		(at 177.4261 129.7286)
		(size 0.4064)
		(drill 0.2032)
		(layers "F.Cu" "B.Cu")
		(tenting
			(front yes)
			(back yes)
		)
		(net "GND")
	)
	(via
		(at 210.2261 104.7162)
		(size 0.4064)
		(drill 0.2032)
		(layers "F.Cu" "B.Cu")
		(net "GND")
	)
	(via
		(at 236.0261 109.0162)
		(size 0.4064)
		(drill 0.2032)
		(layers "F.Cu" "B.Cu")
		(net "GND")
	)
	(via
		(at 225.1261 130.7162)
		(size 0.4064)
		(drill 0.2032)
		(layers "F.Cu" "B.Cu")
		(net "GND")
	)
	(via
		(at 73.9061 131.2146)
		(size 0.4064)
		(drill 0.2032)
		(layers "F.Cu" "B.Cu")
		(tenting
			(front yes)
			(back yes)
		)
		(net "GND")
	)
	(via
		(at 217.8761 61.8662)
		(size 0.4064)
		(drill 0.2032)
		(layers "F.Cu" "B.Cu")
		(tenting
			(front yes)
			(back yes)
		)
		(net "GND")
	)
	(via
		(at 76.4461 91.5906)
		(size 0.4064)
		(drill 0.2032)
		(layers "F.Cu" "B.Cu")
		(tenting
			(front yes)
			(back yes)
		)
		(net "GND")
	)
	(via
		(at 76.9541 131.2146)
		(size 0.4064)
		(drill 0.2032)
		(layers "F.Cu" "B.Cu")
		(tenting
			(front yes)
			(back yes)
		)
		(net "GND")
	)
	(via
		(at 202.5261 100.5162)
		(size 0.4064)
		(drill 0.2032)
		(layers "F.Cu" "B.Cu")
		(net "GND")
	)
	(via
		(at 180.3261 129.7286)
		(size 0.4064)
		(drill 0.2032)
		(layers "F.Cu" "B.Cu")
		(tenting
			(front yes)
			(back yes)
		)
		(net "GND")
	)
	(via
		(at 150.2847 112.3102)
		(size 0.4064)
		(drill 0.2032)
		(layers "F.Cu" "B.Cu")
		(tenting
			(front yes)
			(back yes)
		)
		(net "GND")
	)
	(via
		(at 70.8581 90.5746)
		(size 0.4064)
		(drill 0.2032)
		(layers "F.Cu" "B.Cu")
		(tenting
			(front yes)
			(back yes)
		)
		(net "GND")
	)
	(via
		(at 68.8261 116.9906)
		(size 0.4064)
		(drill 0.2032)
		(layers "F.Cu" "B.Cu")
		(tenting
			(front yes)
			(back yes)
		)
		(net "GND")
	)
	(via
		(at 67.8101 96.6706)
		(size 0.4064)
		(drill 0.2032)
		(layers "F.Cu" "B.Cu")
		(tenting
			(front yes)
			(back yes)
		)
		(net "GND")
	)
	(via
		(at 67.8101 98.7026)
		(size 0.4064)
		(drill 0.2032)
		(layers "F.Cu" "B.Cu")
		(tenting
			(front yes)
			(back yes)
		)
		(net "GND")
	)
	(via
		(at 232.3261 109.2162)
		(size 0.4064)
		(drill 0.2032)
		(layers "F.Cu" "B.Cu")
		(net "GND")
	)
	(via
		(at 75.9381 141.3746)
		(size 0.4064)
		(drill 0.2032)
		(layers "F.Cu" "B.Cu")
		(tenting
			(front yes)
			(back yes)
		)
		(net "GND")
	)
	(via
		(at 72.3821 109.8786)
		(size 0.4064)
		(drill 0.2032)
		(layers "F.Cu" "B.Cu")
		(tenting
			(front yes)
			(back yes)
		)
		(net "GND")
	)
	(via
		(at 134.5511 154.1786)
		(size 0.4064)
		(drill 0.2032)
		(layers "F.Cu" "B.Cu")
		(tenting
			(front yes)
			(back yes)
		)
		(net "GND")
	)
	(via
		(at 184.2261 86.5162)
		(size 0.4064)
		(drill 0.2032)
		(layers "F.Cu" "B.Cu")
		(net "GND")
	)
	(via
		(at 202.1261 91.8162)
		(size 0.4064)
		(drill 0.2032)
		(layers "F.Cu" "B.Cu")
		(net "GND")
	)
	(via
		(at 233.6261 124.9162)
		(size 0.4064)
		(drill 0.2032)
		(layers "F.Cu" "B.Cu")
		(net "GND")
	)
	(via
		(at 71.8741 139.3426)
		(size 0.4064)
		(drill 0.2032)
		(layers "F.Cu" "B.Cu")
		(tenting
			(front yes)
			(back yes)
		)
		(net "GND")
	)
	(via
		(at 172.9261 129.7286)
		(size 0.4064)
		(drill 0.2032)
		(layers "F.Cu" "B.Cu")
		(tenting
			(front yes)
			(back yes)
		)
		(net "GND")
	)
	(via
		(at 56.6341 123.0866)
		(size 0.4064)
		(drill 0.2032)
		(layers "F.Cu" "B.Cu")
		(tenting
			(front yes)
			(back yes)
		)
		(net "GND")
	)
	(via
		(at 211.65601 80.54556)
		(size 0.4064)
		(drill 0.2032)
		(layers "F.Cu" "B.Cu")
		(net "GND")
	)
	(via
		(at 201.6261 129.8162)
		(size 0.4064)
		(drill 0.2032)
		(layers "F.Cu" "B.Cu")
		(net "GND")
	)
	(via
		(at 66.2861 93.6226)
		(size 0.4064)
		(drill 0.2032)
		(layers "F.Cu" "B.Cu")
		(tenting
			(front yes)
			(back yes)
		)
		(net "GND")
	)
	(via
		(at 61.2061 144.4226)
		(size 0.4064)
		(drill 0.2032)
		(layers "F.Cu" "B.Cu")
		(tenting
			(front yes)
			(back yes)
		)
		(net "GND")
	)
	(via
		(at 67.8101 125.1186)
		(size 0.4064)
		(drill 0.2032)
		(layers "F.Cu" "B.Cu")
		(tenting
			(front yes)
			(back yes)
		)
		(net "GND")
	)
	(via
		(at 177.8261 133.6162)
		(size 0.4064)
		(drill 0.2032)
		(layers "F.Cu" "B.Cu")
		(tenting
			(front yes)
			(back yes)
		)
		(net "GND")
	)
	(via
		(at 76.9541 125.1186)
		(size 0.4064)
		(drill 0.2032)
		(layers "F.Cu" "B.Cu")
		(tenting
			(front yes)
			(back yes)
		)
		(net "GND")
	)
	(via
		(at 59.1741 103.7826)
		(size 0.4064)
		(drill 0.2032)
		(layers "F.Cu" "B.Cu")
		(tenting
			(front yes)
			(back yes)
		)
		(net "GND")
	)
	(via
		(at 217.8261 78.6162)
		(size 0.4064)
		(drill 0.2032)
		(layers "F.Cu" "B.Cu")
		(net "GND")
	)
	(via
		(at 74.4141 113.9426)
		(size 0.4064)
		(drill 0.2032)
		(layers "F.Cu" "B.Cu")
		(tenting
			(front yes)
			(back yes)
		)
		(net "GND")
	)
	(via
		(at 169.8261 96.4036)
		(size 0.4064)
		(drill 0.2032)
		(layers "F.Cu" "B.Cu")
		(tenting
			(front yes)
			(back yes)
		)
		(net "GND")
	)
	(via
		(at 69.3341 97.6866)
		(size 0.4064)
		(drill 0.2032)
		(layers "F.Cu" "B.Cu")
		(tenting
			(front yes)
			(back yes)
		)
		(net "GND")
	)
	(via
		(at 195.1011 89.3036)
		(size 0.4064)
		(drill 0.2032)
		(layers "F.Cu" "B.Cu")
		(tenting
			(front yes)
			(back yes)
		)
		(net "GND")
	)
	(via
		(at 76.9541 104.7986)
		(size 0.4064)
		(drill 0.2032)
		(layers "F.Cu" "B.Cu")
		(tenting
			(front yes)
			(back yes)
		)
		(net "GND")
	)
	(via
		(at 76.9541 139.3426)
		(size 0.4064)
		(drill 0.2032)
		(layers "F.Cu" "B.Cu")
		(tenting
			(front yes)
			(back yes)
		)
		(net "GND")
	)
	(via
		(at 107.5611 154.3286)
		(size 0.4064)
		(drill 0.2032)
		(layers "F.Cu" "B.Cu")
		(tenting
			(front yes)
			(back yes)
		)
		(net "GND")
	)
	(via
		(at 60.1901 126.1346)
		(size 0.4064)
		(drill 0.2032)
		(layers "F.Cu" "B.Cu")
		(tenting
			(front yes)
			(back yes)
		)
		(net "GND")
	)
	(via
		(at 68.8261 104.7986)
		(size 0.4064)
		(drill 0.2032)
		(layers "F.Cu" "B.Cu")
		(tenting
			(front yes)
			(back yes)
		)
		(net "GND")
	)
	(via
		(at 89.3761 83.1162)
		(size 0.4064)
		(drill 0.2032)
		(layers "F.Cu" "B.Cu")
		(tenting
			(front yes)
			(back yes)
		)
		(net "GND")
	)
	(via
		(at 198.1261 116.8286)
		(size 0.4064)
		(drill 0.2032)
		(layers "F.Cu" "B.Cu")
		(tenting
			(front yes)
			(back yes)
		)
		(net "GND")
	)
	(via
		(at 225.62252 135.01978)
		(size 0.4064)
		(drill 0.2032)
		(layers "F.Cu" "B.Cu")
		(tenting
			(front yes)
			(back yes)
		)
		(net "GND")
	)
	(via
		(at 207.9261 120.1162)
		(size 0.4064)
		(drill 0.2032)
		(layers "F.Cu" "B.Cu")
		(net "GND")
	)
	(via
		(at 79.3761 112.8662)
		(size 0.4064)
		(drill 0.2032)
		(layers "F.Cu" "B.Cu")
		(tenting
			(front yes)
			(back yes)
		)
		(net "GND")
	)
	(via
		(at 233.7261 127.0162)
		(size 0.4064)
		(drill 0.2032)
		(layers "F.Cu" "B.Cu")
		(net "GND")
	)
	(via
		(at 68.8261 137.3106)
		(size 0.4064)
		(drill 0.2032)
		(layers "F.Cu" "B.Cu")
		(tenting
			(front yes)
			(back yes)
		)
		(net "GND")
	)
	(via
		(at 190.20559 81.97253)
		(size 0.4064)
		(drill 0.2032)
		(layers "F.Cu" "B.Cu")
		(net "GND")
	)
	(via
		(at 72.3821 120.0386)
		(size 0.4064)
		(drill 0.2032)
		(layers "F.Cu" "B.Cu")
		(tenting
			(front yes)
			(back yes)
		)
		(net "GND")
	)
	(via
		(at 89.3761 87.1162)
		(size 0.5)
		(drill 0.2)
		(layers "F.Cu" "B.Cu")
		(net "GND")
	)
	(via
		(at 60.6981 104.7986)
		(size 0.4064)
		(drill 0.2032)
		(layers "F.Cu" "B.Cu")
		(tenting
			(front yes)
			(back yes)
		)
		(net "GND")
	)
	(via
		(at 234.0261 120.4162)
		(size 0.4064)
		(drill 0.2032)
		(layers "F.Cu" "B.Cu")
		(net "GND")
	)
	(via
		(at 69.8421 104.7986)
		(size 0.4064)
		(drill 0.2032)
		(layers "F.Cu" "B.Cu")
		(tenting
			(front yes)
			(back yes)
		)
		(net "GND")
	)
	(via
		(at 67.8101 129.1826)
		(size 0.4064)
		(drill 0.2032)
		(layers "F.Cu" "B.Cu")
		(tenting
			(front yes)
			(back yes)
		)
		(net "GND")
	)
	(via
		(at 234.9261 76.4162)
		(size 0.4064)
		(drill 0.2032)
		(layers "F.Cu" "B.Cu")
		(net "GND")
	)
	(via
		(at 191.70264 87.45869)
		(size 0.4064)
		(drill 0.2032)
		(layers "F.Cu" "B.Cu")
		(net "GND")
	)
	(via
		(at 74.4141 144.4226)
		(size 0.4064)
		(drill 0.2032)
		(layers "F.Cu" "B.Cu")
		(tenting
			(front yes)
			(back yes)
		)
		(net "GND")
	)
	(via
		(at 76.9541 90.5746)
		(size 0.4064)
		(drill 0.2032)
		(layers "F.Cu" "B.Cu")
		(tenting
			(front yes)
			(back yes)
		)
		(net "GND")
	)
	(via
		(at 85.1261 120.8662)
		(size 0.4064)
		(drill 0.2032)
		(layers "F.Cu" "B.Cu")
		(tenting
			(front yes)
			(back yes)
		)
		(net "GND")
	)
	(via
		(at 60.1901 144.4226)
		(size 0.4064)
		(drill 0.2032)
		(layers "F.Cu" "B.Cu")
		(tenting
			(front yes)
			(back yes)
		)
		(net "GND")
	)
	(via
		(at 73.9061 112.9266)
		(size 0.4064)
		(drill 0.2032)
		(layers "F.Cu" "B.Cu")
		(tenting
			(front yes)
			(back yes)
		)
		(net "GND")
	)
	(via
		(at 64.2541 103.7826)
		(size 0.4064)
		(drill 0.2032)
		(layers "F.Cu" "B.Cu")
		(tenting
			(front yes)
			(back yes)
		)
		(net "GND")
	)
	(via
		(at 75.9381 116.9906)
		(size 0.4064)
		(drill 0.2032)
		(layers "F.Cu" "B.Cu")
		(tenting
			(front yes)
			(back yes)
		)
		(net "GND")
	)
	(via
		(at 104.54612 154.36162)
		(size 0.4064)
		(drill 0.2032)
		(layers "F.Cu" "B.Cu")
		(tenting
			(front yes)
			(back yes)
		)
		(net "GND")
	)
	(via
		(at 80.54375 100.66367)
		(size 0.4064)
		(drill 0.2032)
		(layers "F.Cu" "B.Cu")
		(tenting
			(front yes)
			(back yes)
		)
		(net "GND")
	)
	(via
		(at 88.8261 59.8162)
		(size 0.4064)
		(drill 0.2032)
		(layers "F.Cu" "B.Cu")
		(tenting
			(front yes)
			(back yes)
		)
		(net "GND")
	)
	(via
		(at 90.4761 86.0162)
		(size 0.5)
		(drill 0.2)
		(layers "F.Cu" "B.Cu")
		(net "GND")
	)
	(via
		(at 131.0261 88.8162)
		(size 0.4064)
		(drill 0.2032)
		(layers "F.Cu" "B.Cu")
		(tenting
			(front yes)
			(back yes)
		)
		(net "GND")
	)
	(via
		(at 236.79002 130.9449)
		(size 0.4064)
		(drill 0.2032)
		(layers "F.Cu" "B.Cu")
		(net "GND")
	)
	(via
		(at 211.5261 85.0162)
		(size 0.4064)
		(drill 0.2032)
		(layers "F.Cu" "B.Cu")
		(net "GND")
	)
	(via
		(at 80.6261 127.6162)
		(size 0.4064)
		(drill 0.2032)
		(layers "F.Cu" "B.Cu")
		(tenting
			(front yes)
			(back yes)
		)
		(net "GND")
	)
	(via
		(at 174.0261 138.2162)
		(size 0.4064)
		(drill 0.2032)
		(layers "F.Cu" "B.Cu")
		(tenting
			(front yes)
			(back yes)
		)
		(net "GND")
	)
	(via
		(at 201.90818 82.80834)
		(size 0.4064)
		(drill 0.2032)
		(layers "F.Cu" "B.Cu")
		(net "GND")
	)
	(via
		(at 88.2761 88.2162)
		(size 0.5)
		(drill 0.2)
		(layers "F.Cu" "B.Cu")
		(net "GND")
	)
	(via
		(at 65.7781 121.0546)
		(size 0.4064)
		(drill 0.2032)
		(layers "F.Cu" "B.Cu")
		(tenting
			(front yes)
			(back yes)
		)
		(net "GND")
	)
	(via
		(at 164.8011 95.2036)
		(size 0.4064)
		(drill 0.2032)
		(layers "F.Cu" "B.Cu")
		(tenting
			(front yes)
			(back yes)
		)
		(net "GND")
	)
	(via
		(at 69.8421 96.6706)
		(size 0.4064)
		(drill 0.2032)
		(layers "F.Cu" "B.Cu")
		(tenting
			(front yes)
			(back yes)
		)
		(net "GND")
	)
	(via
		(at 154.0068 77.9669)
		(size 1.27)
		(drill 0.7112)
		(layers "F.Cu" "B.Cu")
		(net "GND")
	)
	(via
		(at 71.3661 138.3266)
		(size 0.4064)
		(drill 0.2032)
		(layers "F.Cu" "B.Cu")
		(tenting
			(front yes)
			(back yes)
		)
		(net "GND")
	)
	(via
		(at 74.3761 97.6162)
		(size 0.4064)
		(drill 0.2032)
		(layers "F.Cu" "B.Cu")
		(tenting
			(front yes)
			(back yes)
		)
		(net "GND")
	)
	(via
		(at 209.9261 105.6162)
		(size 0.4064)
		(drill 0.2032)
		(layers "F.Cu" "B.Cu")
		(net "GND")
	)
	(via
		(at 65.7781 104.7986)
		(size 0.4064)
		(drill 0.2032)
		(layers "F.Cu" "B.Cu")
		(tenting
			(front yes)
			(back yes)
		)
		(net "GND")
	)
	(via
		(at 198.1261 114.3206)
		(size 0.4064)
		(drill 0.2032)
		(layers "F.Cu" "B.Cu")
		(tenting
			(front yes)
			(back yes)
		)
		(net "GND")
	)
	(via
		(at 61.2061 103.7826)
		(size 0.4064)
		(drill 0.2032)
		(layers "F.Cu" "B.Cu")
		(tenting
			(front yes)
			(back yes)
		)
		(net "GND")
	)
	(via
		(at 150.1831 117.028)
		(size 0.4064)
		(drill 0.2032)
		(layers "F.Cu" "B.Cu")
		(tenting
			(front yes)
			(back yes)
		)
		(net "GND")
	)
	(via
		(at 68.3181 144.4226)
		(size 0.4064)
		(drill 0.2032)
		(layers "F.Cu" "B.Cu")
		(tenting
			(front yes)
			(back yes)
		)
		(net "GND")
	)
	(via
		(at 132.2261 88.5162)
		(size 0.4064)
		(drill 0.2032)
		(layers "F.Cu" "B.Cu")
		(tenting
			(front yes)
			(back yes)
		)
		(net "GND")
	)
	(via
		(at 75.4301 144.4226)
		(size 0.4064)
		(drill 0.2032)
		(layers "F.Cu" "B.Cu")
		(tenting
			(front yes)
			(back yes)
		)
		(net "GND")
	)
	(via
		(at 75.4301 140.3586)
		(size 0.4064)
		(drill 0.2032)
		(layers "F.Cu" "B.Cu")
		(tenting
			(front yes)
			(back yes)
		)
		(net "GND")
	)
	(via
		(at 198.1261 119.6242)
		(size 0.4064)
		(drill 0.2032)
		(layers "F.Cu" "B.Cu")
		(tenting
			(front yes)
			(back yes)
		)
		(net "GND")
	)
	(via
		(at 77.4621 142.3906)
		(size 0.4064)
		(drill 0.2032)
		(layers "F.Cu" "B.Cu")
		(tenting
			(front yes)
			(back yes)
		)
		(net "GND")
	)
	(via
		(at 77.4621 103.7826)
		(size 0.4064)
		(drill 0.2032)
		(layers "F.Cu" "B.Cu")
		(tenting
			(front yes)
			(back yes)
		)
		(net "GND")
	)
	(via
		(at 74.9221 112.9266)
		(size 0.4064)
		(drill 0.2032)
		(layers "F.Cu" "B.Cu")
		(tenting
			(front yes)
			(back yes)
		)
		(net "GND")
	)
	(via
		(at 89.3921 91.1162)
		(size 0.4064)
		(drill 0.2032)
		(layers "F.Cu" "B.Cu")
		(tenting
			(front yes)
			(back yes)
		)
		(net "GND")
	)
	(via
		(at 60.1901 118.0066)
		(size 0.4064)
		(drill 0.2032)
		(layers "F.Cu" "B.Cu")
		(tenting
			(front yes)
			(back yes)
		)
		(net "GND")
	)
	(via
		(at 68.8261 131.2146)
		(size 0.4064)
		(drill 0.2032)
		(layers "F.Cu" "B.Cu")
		(tenting
			(front yes)
			(back yes)
		)
		(net "GND")
	)
	(via
		(at 67.3021 91.5906)
		(size 0.4064)
		(drill 0.2032)
		(layers "F.Cu" "B.Cu")
		(tenting
			(front yes)
			(back yes)
		)
		(net "GND")
	)
	(via
		(at 234.2261 121.5162)
		(size 0.4064)
		(drill 0.2032)
		(layers "F.Cu" "B.Cu")
		(net "GND")
	)
	(via
		(at 205.3261 120.4162)
		(size 0.4064)
		(drill 0.2032)
		(layers "F.Cu" "B.Cu")
		(net "GND")
	)
	(via
		(at 67.3021 144.4226)
		(size 0.4064)
		(drill 0.2032)
		(layers "F.Cu" "B.Cu")
		(tenting
			(front yes)
			(back yes)
		)
		(net "GND")
	)
	(via
		(at 75.9381 104.7986)
		(size 0.4064)
		(drill 0.2032)
		(layers "F.Cu" "B.Cu")
		(tenting
			(front yes)
			(back yes)
		)
		(net "GND")
	)
	(via
		(at 60.6981 90.5746)
		(size 0.4064)
		(drill 0.2032)
		(layers "F.Cu" "B.Cu")
		(tenting
			(front yes)
			(back yes)
		)
		(net "GND")
	)
	(via
		(at 58.1581 144.4226)
		(size 0.4064)
		(drill 0.2032)
		(layers "F.Cu" "B.Cu")
		(tenting
			(front yes)
			(back yes)
		)
		(net "GND")
	)
	(via
		(at 75.4301 126.1346)
		(size 0.4064)
		(drill 0.2032)
		(layers "F.Cu" "B.Cu")
		(tenting
			(front yes)
			(back yes)
		)
		(net "GND")
	)
	(via
		(at 201.58859 126.45771)
		(size 0.4064)
		(drill 0.2032)
		(layers "F.Cu" "B.Cu")
		(net "GND")
	)
	(via
		(at 149.0909 112.3102)
		(size 0.4064)
		(drill 0.2032)
		(layers "F.Cu" "B.Cu")
		(tenting
			(front yes)
			(back yes)
		)
		(net "GND")
	)
	(via
		(at 67.3021 126.1346)
		(size 0.4064)
		(drill 0.2032)
		(layers "F.Cu" "B.Cu")
		(tenting
			(front yes)
			(back yes)
		)
		(net "GND")
	)
	(via
		(at 223.60697 76.39742)
		(size 0.4064)
		(drill 0.2032)
		(layers "F.Cu" "B.Cu")
		(net "GND")
	)
	(via
		(at 68.8261 123.0866)
		(size 0.4064)
		(drill 0.2032)
		(layers "F.Cu" "B.Cu")
		(tenting
			(front yes)
			(back yes)
		)
		(net "GND")
	)
	(via
		(at 68.3181 132.2306)
		(size 0.4064)
		(drill 0.2032)
		(layers "F.Cu" "B.Cu")
		(tenting
			(front yes)
			(back yes)
		)
		(net "GND")
	)
	(via
		(at 71.8741 141.3746)
		(size 0.4064)
		(drill 0.2032)
		(layers "F.Cu" "B.Cu")
		(tenting
			(front yes)
			(back yes)
		)
		(net "GND")
	)
	(via
		(at 65.7781 98.7026)
		(size 0.4064)
		(drill 0.2032)
		(layers "F.Cu" "B.Cu")
		(tenting
			(front yes)
			(back yes)
		)
		(net "GND")
	)
	(via
		(at 214.2261 100.6162)
		(size 0.4064)
		(drill 0.2032)
		(layers "F.Cu" "B.Cu")
		(net "GND")
	)
	(via
		(at 212.7261 77.0162)
		(size 0.4064)
		(drill 0.2032)
		(layers "F.Cu" "B.Cu")
		(net "GND")
	)
	(via
		(at 68.8261 92.6066)
		(size 0.4064)
		(drill 0.2032)
		(layers "F.Cu" "B.Cu")
		(tenting
			(front yes)
			(back yes)
		)
		(net "GND")
	)
	(via
		(at 191.7261 88.1162)
		(size 0.4064)
		(drill 0.2032)
		(layers "F.Cu" "B.Cu")
		(net "GND")
	)
	(via
		(at 197.3761 81.5866)
		(size 0.4064)
		(drill 0.2032)
		(layers "F.Cu" "B.Cu")
		(tenting
			(front yes)
			(back yes)
		)
		(net "GND")
	)
	(via
		(at 76.4461 144.4226)
		(size 0.4064)
		(drill 0.2032)
		(layers "F.Cu" "B.Cu")
		(tenting
			(front yes)
			(back yes)
		)
		(net "GND")
	)
	(via
		(at 175.3761 86.3286)
		(size 0.4064)
		(drill 0.2032)
		(layers "F.Cu" "B.Cu")
		(tenting
			(front yes)
			(back yes)
		)
		(net "GND")
	)
	(via
		(at 70.3501 142.3906)
		(size 0.4064)
		(drill 0.2032)
		(layers "F.Cu" "B.Cu")
		(tenting
			(front yes)
			(back yes)
		)
		(net "GND")
	)
	(via
		(at 68.3181 140.3586)
		(size 0.4064)
		(drill 0.2032)
		(layers "F.Cu" "B.Cu")
		(tenting
			(front yes)
			(back yes)
		)
		(net "GND")
	)
	(via
		(at 76.4461 118.0066)
		(size 0.4064)
		(drill 0.2032)
		(layers "F.Cu" "B.Cu")
		(tenting
			(front yes)
			(back yes)
		)
		(net "GND")
	)
	(via
		(at 202.0261 109.4162)
		(size 0.4064)
		(drill 0.2032)
		(layers "F.Cu" "B.Cu")
		(net "GND")
	)
	(via
		(at 65.7781 106.8306)
		(size 0.4064)
		(drill 0.2032)
		(layers "F.Cu" "B.Cu")
		(tenting
			(front yes)
			(back yes)
		)
		(net "GND")
	)
	(via
		(at 66.2861 91.5906)
		(size 0.4064)
		(drill 0.2032)
		(layers "F.Cu" "B.Cu")
		(tenting
			(front yes)
			(back yes)
		)
		(net "GND")
	)
	(via
		(at 74.9221 129.1826)
		(size 0.4064)
		(drill 0.2032)
		(layers "F.Cu" "B.Cu")
		(tenting
			(front yes)
			(back yes)
		)
		(net "GND")
	)
	(via
		(at 76.4461 93.6226)
		(size 0.4064)
		(drill 0.2032)
		(layers "F.Cu" "B.Cu")
		(tenting
			(front yes)
			(back yes)
		)
		(net "GND")
	)
	(via
		(at 196.6261 106.8286)
		(size 0.4064)
		(drill 0.2032)
		(layers "F.Cu" "B.Cu")
		(tenting
			(front yes)
			(back yes)
		)
		(net "GND")
	)
	(via
		(at 73.9061 139.3426)
		(size 0.4064)
		(drill 0.2032)
		(layers "F.Cu" "B.Cu")
		(tenting
			(front yes)
			(back yes)
		)
		(net "GND")
	)
	(via
		(at 180.4261 134.0286)
		(size 0.4064)
		(drill 0.2032)
		(layers "F.Cu" "B.Cu")
		(tenting
			(front yes)
			(back yes)
		)
		(net "GND")
	)
	(via
		(at 74.4141 91.5906)
		(size 0.4064)
		(drill 0.2032)
		(layers "F.Cu" "B.Cu")
		(tenting
			(front yes)
			(back yes)
		)
		(net "GND")
	)
	(via
		(at 66.7941 125.1186)
		(size 0.4064)
		(drill 0.2032)
		(layers "F.Cu" "B.Cu")
		(tenting
			(front yes)
			(back yes)
		)
		(net "GND")
	)
	(via
		(at 68.8261 98.7026)
		(size 0.4064)
		(drill 0.2032)
		(layers "F.Cu" "B.Cu")
		(tenting
			(front yes)
			(back yes)
		)
		(net "GND")
	)
	(via
		(at 62.2221 144.4226)
		(size 0.4064)
		(drill 0.2032)
		(layers "F.Cu" "B.Cu")
		(tenting
			(front yes)
			(back yes)
		)
		(net "GND")
	)
	(via
		(at 60.6981 98.7026)
		(size 0.4064)
		(drill 0.2032)
		(layers "F.Cu" "B.Cu")
		(tenting
			(front yes)
			(back yes)
		)
		(net "GND")
	)
	(via
		(at 240.10358 71.19139)
		(size 0.4064)
		(drill 0.2032)
		(layers "F.Cu" "B.Cu")
		(net "GND")
	)
	(via
		(at 69.8421 141.3746)
		(size 0.4064)
		(drill 0.2032)
		(layers "F.Cu" "B.Cu")
		(tenting
			(front yes)
			(back yes)
		)
		(net "GND")
	)
	(via
		(at 66.7941 123.0866)
		(size 0.4064)
		(drill 0.2032)
		(layers "F.Cu" "B.Cu")
		(tenting
			(front yes)
			(back yes)
		)
		(net "GND")
	)
	(via
		(at 172.3841 95.2286)
		(size 0.4064)
		(drill 0.2032)
		(layers "F.Cu" "B.Cu")
		(tenting
			(front yes)
			(back yes)
		)
		(net "GND")
	)
	(via
		(at 68.3181 134.2626)
		(size 0.4064)
		(drill 0.2032)
		(layers "F.Cu" "B.Cu")
		(tenting
			(front yes)
			(back yes)
		)
		(net "GND")
	)
	(via
		(at 173.5261 138.3162)
		(size 0.4064)
		(drill 0.2032)
		(layers "F.Cu" "B.Cu")
		(tenting
			(front yes)
			(back yes)
		)
		(net "GND")
	)
	(via
		(at 120.54609 154.35959)
		(size 0.4064)
		(drill 0.2032)
		(layers "F.Cu" "B.Cu")
		(tenting
			(front yes)
			(back yes)
		)
		(net "GND")
	)
	(via
		(at 77.4621 134.2626)
		(size 0.4064)
		(drill 0.2032)
		(layers "F.Cu" "B.Cu")
		(tenting
			(front yes)
			(back yes)
		)
		(net "GND")
	)
	(via
		(at 90.4761 88.2162)
		(size 0.5)
		(drill 0.2)
		(layers "F.Cu" "B.Cu")
		(net "GND")
	)
	(via
		(at 74.3761 119.3662)
		(size 0.4064)
		(drill 0.2032)
		(layers "F.Cu" "B.Cu")
		(tenting
			(front yes)
			(back yes)
		)
		(net "GND")
	)
	(via
		(at 71.8741 119.0226)
		(size 0.4064)
		(drill 0.2032)
		(layers "F.Cu" "B.Cu")
		(tenting
			(front yes)
			(back yes)
		)
		(net "GND")
	)
	(via
		(at 89.3761 88.2162)
		(size 0.5)
		(drill 0.2)
		(layers "F.Cu" "B.Cu")
		(net "GND")
	)
	(via
		(at 72.8901 114.9586)
		(size 0.4064)
		(drill 0.2032)
		(layers "F.Cu" "B.Cu")
		(tenting
			(front yes)
			(back yes)
		)
		(net "GND")
	)
	(via
		(at 69.8761 129.1162)
		(size 0.4064)
		(drill 0.2032)
		(layers "F.Cu" "B.Cu")
		(tenting
			(front yes)
			(back yes)
		)
		(net "GND")
	)
	(via
		(at 228.9261 97.0162)
		(size 0.4064)
		(drill 0.2032)
		(layers "F.Cu" "B.Cu")
		(net "GND")
	)
	(via
		(at 67.8101 92.6066)
		(size 0.4064)
		(drill 0.2032)
		(layers "F.Cu" "B.Cu")
		(tenting
			(front yes)
			(back yes)
		)
		(net "GND")
	)
	(via
		(at 76.4461 120.0386)
		(size 0.4064)
		(drill 0.2032)
		(layers "F.Cu" "B.Cu")
		(tenting
			(front yes)
			(back yes)
		)
		(net "GND")
	)
	(via
		(at 175.9261 129.7286)
		(size 0.4064)
		(drill 0.2032)
		(layers "F.Cu" "B.Cu")
		(tenting
			(front yes)
			(back yes)
		)
		(net "GND")
	)
	(via
		(at 71.8741 125.1186)
		(size 0.4064)
		(drill 0.2032)
		(layers "F.Cu" "B.Cu")
		(tenting
			(front yes)
			(back yes)
		)
		(net "GND")
	)
	(via
		(at 68.3181 103.7826)
		(size 0.4064)
		(drill 0.2032)
		(layers "F.Cu" "B.Cu")
		(tenting
			(front yes)
			(back yes)
		)
		(net "GND")
	)
	(via
		(at 72.8901 141.3746)
		(size 0.4064)
		(drill 0.2032)
		(layers "F.Cu" "B.Cu")
		(tenting
			(front yes)
			(back yes)
		)
		(net "GND")
	)
	(via
		(at 61.7141 112.9266)
		(size 0.4064)
		(drill 0.2032)
		(layers "F.Cu" "B.Cu")
		(tenting
			(front yes)
			(back yes)
		)
		(net "GND")
	)
	(via
		(at 60.6981 112.9266)
		(size 0.4064)
		(drill 0.2032)
		(layers "F.Cu" "B.Cu")
		(tenting
			(front yes)
			(back yes)
		)
		(net "GND")
	)
	(via
		(at 124.3596 85.29254)
		(size 0.4064)
		(drill 0.2032)
		(layers "F.Cu" "B.Cu")
		(net "GND")
	)
	(via
		(at 74.4141 140.3586)
		(size 0.4064)
		(drill 0.2032)
		(layers "F.Cu" "B.Cu")
		(tenting
			(front yes)
			(back yes)
		)
		(net "GND")
	)
	(via
		(at 76.9541 116.9906)
		(size 0.4064)
		(drill 0.2032)
		(layers "F.Cu" "B.Cu")
		(tenting
			(front yes)
			(back yes)
		)
		(net "GND")
	)
	(via
		(at 67.8101 114.9586)
		(size 0.4064)
		(drill 0.2032)
		(layers "F.Cu" "B.Cu")
		(tenting
			(front yes)
			(back yes)
		)
		(net "GND")
	)
	(via
		(at 66.2861 103.7826)
		(size 0.4064)
		(drill 0.2032)
		(layers "F.Cu" "B.Cu")
		(tenting
			(front yes)
			(back yes)
		)
		(net "GND")
	)
	(via
		(at 74.9221 141.3746)
		(size 0.4064)
		(drill 0.2032)
		(layers "F.Cu" "B.Cu")
		(tenting
			(front yes)
			(back yes)
		)
		(net "GND")
	)
	(via
		(at 65.2701 126.1346)
		(size 0.4064)
		(drill 0.2032)
		(layers "F.Cu" "B.Cu")
		(tenting
			(front yes)
			(back yes)
		)
		(net "GND")
	)
	(via
		(at 126.2261 87.9162)
		(size 0.4064)
		(drill 0.2032)
		(layers "F.Cu" "B.Cu")
		(net "GND")
	)
	(via
		(at 77.4621 105.8146)
		(size 0.4064)
		(drill 0.2032)
		(layers "F.Cu" "B.Cu")
		(tenting
			(front yes)
			(back yes)
		)
		(net "GND")
	)
	(via
		(at 176.0309 133.60446)
		(size 0.4064)
		(drill 0.2032)
		(layers "F.Cu" "B.Cu")
		(tenting
			(front yes)
			(back yes)
		)
		(net "GND")
	)
	(via
		(at 75.9381 114.9586)
		(size 0.4064)
		(drill 0.2032)
		(layers "F.Cu" "B.Cu")
		(tenting
			(front yes)
			(back yes)
		)
		(net "GND")
	)
	(via
		(at 218.4261 118.0162)
		(size 0.4064)
		(drill 0.2032)
		(layers "F.Cu" "B.Cu")
		(net "GND")
	)
	(via
		(at 68.3181 128.1666)
		(size 0.4064)
		(drill 0.2032)
		(layers "F.Cu" "B.Cu")
		(tenting
			(front yes)
			(back yes)
		)
		(net "GND")
	)
	(via
		(at 57.1421 144.4226)
		(size 0.4064)
		(drill 0.2032)
		(layers "F.Cu" "B.Cu")
		(tenting
			(front yes)
			(back yes)
		)
		(net "GND")
	)
	(via
		(at 150.35037 107.35152)
		(size 0.4064)
		(drill 0.2032)
		(layers "F.Cu" "B.Cu")
		(tenting
			(front yes)
			(back yes)
		)
		(net "GND")
	)
	(via
		(at 76.9541 137.3106)
		(size 0.4064)
		(drill 0.2032)
		(layers "F.Cu" "B.Cu")
		(tenting
			(front yes)
			(back yes)
		)
		(net "GND")
	)
	(via
		(at 66.2861 120.0386)
		(size 0.4064)
		(drill 0.2032)
		(layers "F.Cu" "B.Cu")
		(tenting
			(front yes)
			(back yes)
		)
		(net "GND")
	)
	(via
		(at 174.8761 95.2286)
		(size 0.4064)
		(drill 0.2032)
		(layers "F.Cu" "B.Cu")
		(tenting
			(front yes)
			(back yes)
		)
		(net "GND")
	)
	(via
		(at 230.42252 135.01978)
		(size 0.4064)
		(drill 0.2032)
		(layers "F.Cu" "B.Cu")
		(tenting
			(front yes)
			(back yes)
		)
		(net "GND")
	)
	(via
		(at 70.8581 96.6706)
		(size 0.4064)
		(drill 0.2032)
		(layers "F.Cu" "B.Cu")
		(tenting
			(front yes)
			(back yes)
		)
		(net "GND")
	)
	(via
		(at 150.3609 109.821)
		(size 0.4064)
		(drill 0.2032)
		(layers "F.Cu" "B.Cu")
		(tenting
			(front yes)
			(back yes)
		)
		(net "GND")
	)
	(via
		(at 174.13634 133.56736)
		(size 0.4064)
		(drill 0.2032)
		(layers "F.Cu" "B.Cu")
		(tenting
			(front yes)
			(back yes)
		)
		(net "GND")
	)
	(via
		(at 136.26304 116.53826)
		(size 0.4064)
		(drill 0.2032)
		(layers "F.Cu" "B.Cu")
		(tenting
			(front yes)
			(back yes)
		)
		(net "GND")
	)
	(via
		(at 149.0909 122.2924)
		(size 0.4064)
		(drill 0.2032)
		(layers "F.Cu" "B.Cu")
		(tenting
			(front yes)
			(back yes)
		)
		(net "GND")
	)
	(via
		(at 65.7781 116.9906)
		(size 0.4064)
		(drill 0.2032)
		(layers "F.Cu" "B.Cu")
		(tenting
			(front yes)
			(back yes)
		)
		(net "GND")
	)
	(via
		(at 131.1261 86.5162)
		(size 0.4064)
		(drill 0.2032)
		(layers "F.Cu" "B.Cu")
		(tenting
			(front yes)
			(back yes)
		)
		(net "GND")
	)
	(via
		(at 192.51494 142.78121)
		(size 0.4064)
		(drill 0.2032)
		(layers "F.Cu" "B.Cu")
		(tenting
			(front yes)
			(back yes)
		)
		(net "GND")
	)
	(via
		(at 224.6261 102.8162)
		(size 0.4064)
		(drill 0.2032)
		(layers "F.Cu" "B.Cu")
		(net "GND")
	)
	(via
		(at 212.10657 114.76641)
		(size 0.4064)
		(drill 0.2032)
		(layers "F.Cu" "B.Cu")
		(net "GND")
	)
	(via
		(at 174.32611 129.72861)
		(size 0.4064)
		(drill 0.2032)
		(layers "F.Cu" "B.Cu")
		(tenting
			(front yes)
			(back yes)
		)
		(net "GND")
	)
	(via
		(at 60.6981 131.2146)
		(size 0.4064)
		(drill 0.2032)
		(layers "F.Cu" "B.Cu")
		(tenting
			(front yes)
			(back yes)
		)
		(net "GND")
	)
	(via
		(at 77.3261 63.1162)
		(size 0.4064)
		(drill 0.2032)
		(layers "F.Cu" "B.Cu")
		(tenting
			(front yes)
			(back yes)
		)
		(net "GND")
	)
	(via
		(at 84.48221 81.95203)
		(size 0.4064)
		(drill 0.2032)
		(layers "F.Cu" "B.Cu")
		(net "GND")
	)
	(via
		(at 74.2261 62.7162)
		(size 0.4064)
		(drill 0.2032)
		(layers "F.Cu" "B.Cu")
		(tenting
			(front yes)
			(back yes)
		)
		(net "GND")
	)
	(via
		(at 65.7781 90.5746)
		(size 0.4064)
		(drill 0.2032)
		(layers "F.Cu" "B.Cu")
		(tenting
			(front yes)
			(back yes)
		)
		(net "GND")
	)
	(via
		(at 71.8741 92.6066)
		(size 0.4064)
		(drill 0.2032)
		(layers "F.Cu" "B.Cu")
		(tenting
			(front yes)
			(back yes)
		)
		(net "GND")
	)
	(via
		(at 77.4621 132.2306)
		(size 0.4064)
		(drill 0.2032)
		(layers "F.Cu" "B.Cu")
		(tenting
			(front yes)
			(back yes)
		)
		(net "GND")
	)
	(via
		(at 76.4461 138.3266)
		(size 0.4064)
		(drill 0.2032)
		(layers "F.Cu" "B.Cu")
		(tenting
			(front yes)
			(back yes)
		)
		(net "GND")
	)
	(via
		(at 74.3761 133.1162)
		(size 0.4064)
		(drill 0.2032)
		(layers "F.Cu" "B.Cu")
		(tenting
			(front yes)
			(back yes)
		)
		(net "GND")
	)
	(via
		(at 212.9261 100.6162)
		(size 0.4064)
		(drill 0.2032)
		(layers "F.Cu" "B.Cu")
		(net "GND")
	)
	(via
		(at 65.7781 119.0226)
		(size 0.4064)
		(drill 0.2032)
		(layers "F.Cu" "B.Cu")
		(tenting
			(front yes)
			(back yes)
		)
		(net "GND")
	)
	(via
		(at 150.2339 122.2924)
		(size 0.4064)
		(drill 0.2032)
		(layers "F.Cu" "B.Cu")
		(tenting
			(front yes)
			(back yes)
		)
		(net "GND")
	)
	(via
		(at 177.3761 95.2286)
		(size 0.4064)
		(drill 0.2032)
		(layers "F.Cu" "B.Cu")
		(tenting
			(front yes)
			(back yes)
		)
		(net "GND")
	)
	(via
		(at 66.2861 126.1346)
		(size 0.4064)
		(drill 0.2032)
		(layers "F.Cu" "B.Cu")
		(tenting
			(front yes)
			(back yes)
		)
		(net "GND")
	)
	(via
		(at 65.2701 118.0066)
		(size 0.4064)
		(drill 0.2032)
		(layers "F.Cu" "B.Cu")
		(tenting
			(front yes)
			(back yes)
		)
		(net "GND")
	)
	(via
		(at 216.2261 65.2162)
		(size 0.4064)
		(drill 0.2032)
		(layers "F.Cu" "B.Cu")
		(tenting
			(front yes)
			(back yes)
		)
		(net "GND")
	)
	(via
		(at 215.41545 100.56698)
		(size 0.4064)
		(drill 0.2032)
		(layers "F.Cu" "B.Cu")
		(net "GND")
	)
	(via
		(at 219.7261 76.6162)
		(size 0.4064)
		(drill 0.2032)
		(layers "F.Cu" "B.Cu")
		(net "GND")
	)
	(via
		(at 58.1581 122.0706)
		(size 0.4064)
		(drill 0.2032)
		(layers "F.Cu" "B.Cu")
		(tenting
			(front yes)
			(back yes)
		)
		(net "GND")
	)
	(via
		(at 56.6341 108.8626)
		(size 0.4064)
		(drill 0.2032)
		(layers "F.Cu" "B.Cu")
		(tenting
			(front yes)
			(back yes)
		)
		(net "GND")
	)
	(via
		(at 165.32613 129.72863)
		(size 0.4064)
		(drill 0.2032)
		(layers "F.Cu" "B.Cu")
		(tenting
			(front yes)
			(back yes)
		)
		(net "GND")
	)
	(via
		(at 77.4621 124.1026)
		(size 0.4064)
		(drill 0.2032)
		(layers "F.Cu" "B.Cu")
		(tenting
			(front yes)
			(back yes)
		)
		(net "GND")
	)
	(via
		(at 172.3841 96.3286)
		(size 0.4064)
		(drill 0.2032)
		(layers "F.Cu" "B.Cu")
		(tenting
			(front yes)
			(back yes)
		)
		(net "GND")
	)
	(via
		(at 65.7781 112.9266)
		(size 0.4064)
		(drill 0.2032)
		(layers "F.Cu" "B.Cu")
		(tenting
			(front yes)
			(back yes)
		)
		(net "GND")
	)
	(via
		(at 70.3501 91.5906)
		(size 0.4064)
		(drill 0.2032)
		(layers "F.Cu" "B.Cu")
		(tenting
			(front yes)
			(back yes)
		)
		(net "GND")
	)
	(via
		(at 69.3341 91.5906)
		(size 0.4064)
		(drill 0.2032)
		(layers "F.Cu" "B.Cu")
		(tenting
			(front yes)
			(back yes)
		)
		(net "GND")
	)
	(via
		(at 221.5261 73.1162)
		(size 0.4064)
		(drill 0.2032)
		(layers "F.Cu" "B.Cu")
		(tenting
			(front yes)
			(back yes)
		)
		(net "GND")
	)
	(via
		(at 170.4261 129.73857)
		(size 0.4064)
		(drill 0.2032)
		(layers "F.Cu" "B.Cu")
		(tenting
			(front yes)
			(back yes)
		)
		(net "GND")
	)
	(via
		(at 76.4461 142.3906)
		(size 0.4064)
		(drill 0.2032)
		(layers "F.Cu" "B.Cu")
		(tenting
			(front yes)
			(back yes)
		)
		(net "GND")
	)
	(via
		(at 178.6261 138.2162)
		(size 0.4064)
		(drill 0.2032)
		(layers "F.Cu" "B.Cu")
		(tenting
			(front yes)
			(back yes)
		)
		(net "GND")
	)
	(via
		(at 72.3821 140.3586)
		(size 0.4064)
		(drill 0.2032)
		(layers "F.Cu" "B.Cu")
		(tenting
			(front yes)
			(back yes)
		)
		(net "GND")
	)
	(via
		(at 76.4461 134.2626)
		(size 0.4064)
		(drill 0.2032)
		(layers "F.Cu" "B.Cu")
		(tenting
			(front yes)
			(back yes)
		)
		(net "GND")
	)
	(via
		(at 209.1261 104.7162)
		(size 0.4064)
		(drill 0.2032)
		(layers "F.Cu" "B.Cu")
		(net "GND")
	)
	(via
		(at 67.3021 93.6226)
		(size 0.4064)
		(drill 0.2032)
		(layers "F.Cu" "B.Cu")
		(tenting
			(front yes)
			(back yes)
		)
		(net "GND")
	)
	(via
		(at 177.1261 133.6162)
		(size 0.4064)
		(drill 0.2032)
		(layers "F.Cu" "B.Cu")
		(tenting
			(front yes)
			(back yes)
		)
		(net "GND")
	)
	(via
		(at 66.7941 110.8946)
		(size 0.4064)
		(drill 0.2032)
		(layers "F.Cu" "B.Cu")
		(tenting
			(front yes)
			(back yes)
		)
		(net "GND")
	)
	(via
		(at 74.9221 90.5746)
		(size 0.4064)
		(drill 0.2032)
		(layers "F.Cu" "B.Cu")
		(tenting
			(front yes)
			(back yes)
		)
		(net "GND")
	)
	(via
		(at 93.3761 87.13205)
		(size 0.4064)
		(drill 0.2032)
		(layers "F.Cu" "B.Cu")
		(tenting
			(front yes)
			(back yes)
		)
		(net "GND")
	)
	(via
		(at 234.1261 118.9162)
		(size 0.4064)
		(drill 0.2032)
		(layers "F.Cu" "B.Cu")
		(net "GND")
	)
	(via
		(at 167.9261 134.1286)
		(size 0.4064)
		(drill 0.2032)
		(layers "F.Cu" "B.Cu")
		(tenting
			(front yes)
			(back yes)
		)
		(net "GND")
	)
	(via
		(at 228.2261 113.8162)
		(size 0.4064)
		(drill 0.2032)
		(layers "F.Cu" "B.Cu")
		(net "GND")
	)
	(via
		(at 75.4301 142.3906)
		(size 0.4064)
		(drill 0.2032)
		(layers "F.Cu" "B.Cu")
		(tenting
			(front yes)
			(back yes)
		)
		(net "GND")
	)
	(via
		(at 66.2861 109.8786)
		(size 0.4064)
		(drill 0.2032)
		(layers "F.Cu" "B.Cu")
		(tenting
			(front yes)
			(back yes)
		)
		(net "GND")
	)
	(via
		(at 89.3761 86.0162)
		(size 0.5)
		(drill 0.2)
		(layers "F.Cu" "B.Cu")
		(net "GND")
	)
	(via
		(at 198.1261 109.3286)
		(size 0.4064)
		(drill 0.2032)
		(layers "F.Cu" "B.Cu")
		(tenting
			(front yes)
			(back yes)
		)
		(net "GND")
	)
	(via
		(at 69.3341 140.3586)
		(size 0.4064)
		(drill 0.2032)
		(layers "F.Cu" "B.Cu")
		(tenting
			(front yes)
			(back yes)
		)
		(net "GND")
	)
	(via
		(at 68.8261 127.1506)
		(size 0.4064)
		(drill 0.2032)
		(layers "F.Cu" "B.Cu")
		(tenting
			(front yes)
			(back yes)
		)
		(net "GND")
	)
	(via
		(at 69.3341 93.6226)
		(size 0.4064)
		(drill 0.2032)
		(layers "F.Cu" "B.Cu")
		(tenting
			(front yes)
			(back yes)
		)
		(net "GND")
	)
	(via
		(at 66.7941 131.2146)
		(size 0.4064)
		(drill 0.2032)
		(layers "F.Cu" "B.Cu")
		(tenting
			(front yes)
			(back yes)
		)
		(net "GND")
	)
	(via
		(at 72.3821 118.0066)
		(size 0.4064)
		(drill 0.2032)
		(layers "F.Cu" "B.Cu")
		(tenting
			(front yes)
			(back yes)
		)
		(net "GND")
	)
	(via
		(at 237.2979 60.74407)
		(size 0.4064)
		(drill 0.2032)
		(layers "F.Cu" "B.Cu")
		(net "GND")
	)
	(via
		(at 73.3981 111.9106)
		(size 0.4064)
		(drill 0.2032)
		(layers "F.Cu" "B.Cu")
		(tenting
			(front yes)
			(back yes)
		)
		(net "GND")
	)
	(via
		(at 122.6261 89.0866)
		(size 0.4064)
		(drill 0.2032)
		(layers "F.Cu" "B.Cu")
		(tenting
			(front yes)
			(back yes)
		)
		(net "GND")
	)
	(via
		(at 75.4301 118.0066)
		(size 0.4064)
		(drill 0.2032)
		(layers "F.Cu" "B.Cu")
		(tenting
			(front yes)
			(back yes)
		)
		(net "GND")
	)
	(via
		(at 57.1421 122.0706)
		(size 0.4064)
		(drill 0.2032)
		(layers "F.Cu" "B.Cu")
		(tenting
			(front yes)
			(back yes)
		)
		(net "GND")
	)
	(via
		(at 76.9541 119.0226)
		(size 0.4064)
		(drill 0.2032)
		(layers "F.Cu" "B.Cu")
		(tenting
			(front yes)
			(back yes)
		)
		(net "GND")
	)
	(via
		(at 168.4261 90.0162)
		(size 0.4064)
		(drill 0.2032)
		(layers "F.Cu" "B.Cu")
		(net "GND")
	)
	(via
		(at 219.8261 80.5162)
		(size 0.4064)
		(drill 0.2032)
		(layers "F.Cu" "B.Cu")
		(net "GND")
	)
	(via
		(at 196.6261 116.8286)
		(size 0.4064)
		(drill 0.2032)
		(layers "F.Cu" "B.Cu")
		(tenting
			(front yes)
			(back yes)
		)
		(net "GND")
	)
	(via
		(at 75.4301 113.9426)
		(size 0.4064)
		(drill 0.2032)
		(layers "F.Cu" "B.Cu")
		(tenting
			(front yes)
			(back yes)
		)
		(net "GND")
	)
	(via
		(at 149.1261 114.8662)
		(size 0.4064)
		(drill 0.2032)
		(layers "F.Cu" "B.Cu")
		(tenting
			(front yes)
			(back yes)
		)
		(net "GND")
	)
	(via
		(at 222.91764 78.01095)
		(size 0.4064)
		(drill 0.2032)
		(layers "F.Cu" "B.Cu")
		(net "GND")
	)
	(via
		(at 234.81122 73.57966)
		(size 0.4064)
		(drill 0.2032)
		(layers "F.Cu" "B.Cu")
		(net "GND")
	)
	(via
		(at 67.3021 142.3906)
		(size 0.4064)
		(drill 0.2032)
		(layers "F.Cu" "B.Cu")
		(tenting
			(front yes)
			(back yes)
		)
		(net "GND")
	)
	(via
		(at 76.4461 126.1346)
		(size 0.4064)
		(drill 0.2032)
		(layers "F.Cu" "B.Cu")
		(tenting
			(front yes)
			(back yes)
		)
		(net "GND")
	)
	(via
		(at 61.2061 126.1346)
		(size 0.4064)
		(drill 0.2032)
		(layers "F.Cu" "B.Cu")
		(tenting
			(front yes)
			(back yes)
		)
		(net "GND")
	)
	(via
		(at 179.1261 138.2162)
		(size 0.4064)
		(drill 0.2032)
		(layers "F.Cu" "B.Cu")
		(tenting
			(front yes)
			(back yes)
		)
		(net "GND")
	)
	(via
		(at 179.7931 95.22841)
		(size 0.4064)
		(drill 0.2032)
		(layers "F.Cu" "B.Cu")
		(tenting
			(front yes)
			(back yes)
		)
		(net "GND")
	)
	(via
		(at 196.6261 109.3286)
		(size 0.4064)
		(drill 0.2032)
		(layers "F.Cu" "B.Cu")
		(tenting
			(front yes)
			(back yes)
		)
		(net "GND")
	)
	(via
		(at 59.1741 144.4226)
		(size 0.4064)
		(drill 0.2032)
		(layers "F.Cu" "B.Cu")
		(tenting
			(front yes)
			(back yes)
		)
		(net "GND")
	)
	(via
		(at 72.8901 139.3426)
		(size 0.4064)
		(drill 0.2032)
		(layers "F.Cu" "B.Cu")
		(tenting
			(front yes)
			(back yes)
		)
		(net "GND")
	)
	(via
		(at 167.4001 95.2286)
		(size 0.4064)
		(drill 0.2032)
		(layers "F.Cu" "B.Cu")
		(tenting
			(front yes)
			(back yes)
		)
		(net "GND")
	)
	(via
		(at 56.6341 90.5746)
		(size 0.4064)
		(drill 0.2032)
		(layers "F.Cu" "B.Cu")
		(tenting
			(front yes)
			(back yes)
		)
		(net "GND")
	)
	(via
		(at 213.0261 112.6162)
		(size 0.4064)
		(drill 0.2032)
		(layers "F.Cu" "B.Cu")
		(net "GND")
	)
	(via
		(at 218.1261 57.3662)
		(size 0.4064)
		(drill 0.2032)
		(layers "F.Cu" "B.Cu")
		(tenting
			(front yes)
			(back yes)
		)
		(net "GND")
	)
	(via
		(at 73.3981 144.4226)
		(size 0.4064)
		(drill 0.2032)
		(layers "F.Cu" "B.Cu")
		(tenting
			(front yes)
			(back yes)
		)
		(net "GND")
	)
	(via
		(at 60.1901 103.7826)
		(size 0.4064)
		(drill 0.2032)
		(layers "F.Cu" "B.Cu")
		(tenting
			(front yes)
			(back yes)
		)
		(net "GND")
	)
	(via
		(at 74.3761 111.1162)
		(size 0.4064)
		(drill 0.2032)
		(layers "F.Cu" "B.Cu")
		(tenting
			(front yes)
			(back yes)
		)
		(net "GND")
	)
	(via
		(at 68.8261 114.9586)
		(size 0.4064)
		(drill 0.2032)
		(layers "F.Cu" "B.Cu")
		(tenting
			(front yes)
			(back yes)
		)
		(net "GND")
	)
	(via
		(at 165.4261 134.1286)
		(size 0.4064)
		(drill 0.2032)
		(layers "F.Cu" "B.Cu")
		(tenting
			(front yes)
			(back yes)
		)
		(net "GND")
	)
	(via
		(at 69.3341 134.2626)
		(size 0.4064)
		(drill 0.2032)
		(layers "F.Cu" "B.Cu")
		(tenting
			(front yes)
			(back yes)
		)
		(net "GND")
	)
	(via
		(at 62.2221 103.7826)
		(size 0.4064)
		(drill 0.2032)
		(layers "F.Cu" "B.Cu")
		(tenting
			(front yes)
			(back yes)
		)
		(net "GND")
	)
	(via
		(at 66.2861 97.6866)
		(size 0.4064)
		(drill 0.2032)
		(layers "F.Cu" "B.Cu")
		(tenting
			(front yes)
			(back yes)
		)
		(net "GND")
	)
	(via
		(at 233.2261 109.4162)
		(size 0.4064)
		(drill 0.2032)
		(layers "F.Cu" "B.Cu")
		(net "GND")
	)
	(via
		(at 59.6821 116.9906)
		(size 0.4064)
		(drill 0.2032)
		(layers "F.Cu" "B.Cu")
		(tenting
			(front yes)
			(back yes)
		)
		(net "GND")
	)
	(via
		(at 232.9261 97.0162)
		(size 0.4064)
		(drill 0.2032)
		(layers "F.Cu" "B.Cu")
		(net "GND")
	)
	(via
		(at 207.0261 120.1162)
		(size 0.4064)
		(drill 0.2032)
		(layers "F.Cu" "B.Cu")
		(net "GND")
	)
	(via
		(at 209.6261 113.2162)
		(size 0.4064)
		(drill 0.2032)
		(layers "F.Cu" "B.Cu")
		(net "GND")
	)
	(via
		(at 235.72353 61.86053)
		(size 0.4064)
		(drill 0.2032)
		(layers "F.Cu" "B.Cu")
		(net "GND")
	)
	(via
		(at 76.4461 128.1666)
		(size 0.4064)
		(drill 0.2032)
		(layers "F.Cu" "B.Cu")
		(tenting
			(front yes)
			(back yes)
		)
		(net "GND")
	)
	(via
		(at 211.6261 100.5162)
		(size 0.4064)
		(drill 0.2032)
		(layers "F.Cu" "B.Cu")
		(net "GND")
	)
	(via
		(at 68.8261 90.5746)
		(size 0.4064)
		(drill 0.2032)
		(layers "F.Cu" "B.Cu")
		(tenting
			(front yes)
			(back yes)
		)
		(net "GND")
	)
	(via
		(at 237.55511 63.61053)
		(size 0.4064)
		(drill 0.2032)
		(layers "F.Cu" "B.Cu")
		(net "GND")
	)
	(via
		(at 170.5261 134.1286)
		(size 0.4064)
		(drill 0.2032)
		(layers "F.Cu" "B.Cu")
		(tenting
			(front yes)
			(back yes)
		)
		(net "GND")
	)
	(via
		(at 207.6754 82.56045)
		(size 0.4064)
		(drill 0.2032)
		(layers "F.Cu" "B.Cu")
		(net "GND")
	)
	(via
		(at 236.2261 100.7162)
		(size 0.4064)
		(drill 0.2032)
		(layers "F.Cu" "B.Cu")
		(net "GND")
	)
	(via
		(at 74.3761 92.6162)
		(size 0.4064)
		(drill 0.2032)
		(layers "F.Cu" "B.Cu")
		(tenting
			(front yes)
			(back yes)
		)
		(net "GND")
	)
	(via
		(at 70.3501 93.6226)
		(size 0.4064)
		(drill 0.2032)
		(layers "F.Cu" "B.Cu")
		(tenting
			(front yes)
			(back yes)
		)
		(net "GND")
	)
	(via
		(at 75.4301 128.1666)
		(size 0.4064)
		(drill 0.2032)
		(layers "F.Cu" "B.Cu")
		(tenting
			(front yes)
			(back yes)
		)
		(net "GND")
	)
	(via
		(at 150.2847 119.8286)
		(size 0.4064)
		(drill 0.2032)
		(layers "F.Cu" "B.Cu")
		(tenting
			(front yes)
			(back yes)
		)
		(net "GND")
	)
	(via
		(at 73.3981 142.3906)
		(size 0.4064)
		(drill 0.2032)
		(layers "F.Cu" "B.Cu")
		(tenting
			(front yes)
			(back yes)
		)
		(net "GND")
	)
	(via
		(at 82.3761 88.6162)
		(size 0.4064)
		(drill 0.2032)
		(layers "F.Cu" "B.Cu")
		(tenting
			(front yes)
			(back yes)
		)
		(net "GND")
	)
	(via
		(at 167.8261 129.7286)
		(size 0.4064)
		(drill 0.2032)
		(layers "F.Cu" "B.Cu")
		(tenting
			(front yes)
			(back yes)
		)
		(net "GND")
	)
	(via
		(at 196.6261 114.3206)
		(size 0.4064)
		(drill 0.2032)
		(layers "F.Cu" "B.Cu")
		(tenting
			(front yes)
			(back yes)
		)
		(net "GND")
	)
	(via
		(at 71.8741 137.3106)
		(size 0.4064)
		(drill 0.2032)
		(layers "F.Cu" "B.Cu")
		(tenting
			(front yes)
			(back yes)
		)
		(net "GND")
	)
	(via
		(at 239.38037 63.59799)
		(size 0.4064)
		(drill 0.2032)
		(layers "F.Cu" "B.Cu")
		(net "GND")
	)
	(via
		(at 72.8901 119.0226)
		(size 0.4064)
		(drill 0.2032)
		(layers "F.Cu" "B.Cu")
		(tenting
			(front yes)
			(back yes)
		)
		(net "GND")
	)
	(via
		(at 67.8101 137.3106)
		(size 0.4064)
		(drill 0.2032)
		(layers "F.Cu" "B.Cu")
		(tenting
			(front yes)
			(back yes)
		)
		(net "GND")
	)
	(via
		(at 179.3261 133.0162)
		(size 0.4064)
		(drill 0.2032)
		(layers "F.Cu" "B.Cu")
		(tenting
			(front yes)
			(back yes)
		)
		(net "GND")
	)
	(arc
		(start 118.343423 154.653006)
		(mid 118.492607 154.832121)
		(end 118.546089 155.059007)
		(width 0.508)
		(layer "F.Cu")
		(net "GND")
	)
	(arc
		(start 131.306848 154.535981)
		(mid 131.399845 154.691687)
		(end 131.43222 154.870138)
		(width 0.508)
		(layer "F.Cu")
		(net "GND")
	)
	(segment
		(start 133.58245 154.70118)
		(end 134.10503 154.1786)
		(width 0.508)
		(layer "B.Cu")
		(net "GND")
	)
	(segment
		(start 129.50722 157.05975)
		(end 129.52607 157.0786)
		(width 0.508)
		(layer "B.Cu")
		(net "GND")
	)
	(segment
		(start 126.55745 157.04722)
		(end 126.55745 154.59725)
		(width 0.508)
		(layer "B.Cu")
		(net "GND")
	)
	(segment
		(start 114.5461 157.7576)
		(end 114.5461 154.3286)
		(width 0.508)
		(layer "B.Cu")
		(net "GND")
	)
	(segment
		(start 126.55745 154.59725)
		(end 126.9761 154.1786)
		(width 0.508)
		(layer "B.Cu")
		(net "GND")
	)
	(segment
		(start 125.52608 157.0786)
		(end 125.52608 154.47618)
		(width 0.508)
		(layer "B.Cu")
		(net "GND")
	)
	(segment
		(start 125.82366 154.1786)
		(end 126.9761 154.1786)
		(width 0.508)
		(layer "B.Cu")
		(net "GND")
	)
	(segment
		(start 122.54608 154.58842)
		(end 122.8527 154.2818)
		(width 0.508)
		(layer "B.Cu")
		(net "GND")
	)
	(segment
		(start 104.54612 157.7576)
		(end 104.54612 154.36162)
		(width 0.508)
		(layer "B.Cu")
		(net "GND")
	)
	(segment
		(start 122.54608 157.7576)
		(end 122.54608 154.58842)
		(width 0.508)
		(layer "B.Cu")
		(net "GND")
	)
	(segment
		(start 117.7652 154.60117)
		(end 118.03129 154.41678)
		(width 0.508)
		(layer "B.Cu")
		(net "GND")
	)
	(segment
		(start 128.98452 154.23884)
		(end 128.9851 154.23889)
		(width 0.508)
		(layer "B.Cu")
		(net "GND")
	)
	(segment
		(start 120.54609 157.7576)
		(end 120.54609 154.35959)
		(width 0.508)
		(layer "B.Cu")
		(net "GND")
	)
	(segment
		(start 126.52608 157.0786)
		(end 126.55745 157.04722)
		(width 0.508)
		(layer "B.Cu")
		(net "GND")
	)
	(segment
		(start 134.10503 154.1786)
		(end 134.5511 154.1786)
		(width 0.508)
		(layer "B.Cu")
		(net "GND")
	)
	(segment
		(start 133.58245 157.02222)
		(end 133.58245 154.70118)
		(width 0.508)
		(layer "B.Cu")
		(net "GND")
	)
	(segment
		(start 129.30894 154.38644)
		(end 129.50722 154.58472)
		(width 0.508)
		(layer "B.Cu")
		(net "GND")
	)
	(segment
		(start 133.52606 157.0786)
		(end 133.55745 157.04721)
		(width 0.508)
		(layer "B.Cu")
		(net "GND")
	)
	(segment
		(start 133.55745 157.04721)
		(end 133.58245 157.02222)
		(width 0.508)
		(layer "B.Cu")
		(net "GND")
	)
	(segment
		(start 126.9761 154.1786)
		(end 126.99598 154.1786)
		(width 0.508)
		(layer "B.Cu")
		(net "GND")
	)
	(segment
		(start 117.54609 157.7576)
		(end 117.54609 155.01903)
		(width 0.508)
		(layer "B.Cu")
		(net "GND")
	)
	(segment
		(start 130.42447 156.977)
		(end 130.42447 154.8823)
		(width 0.508)
		(layer "B.Cu")
		(net "GND")
	)
	(segment
		(start 130.42447 156.977)
		(end 130.52607 157.0786)
		(width 0.508)
		(layer "B.Cu")
		(net "GND")
	)
	(segment
		(start 133.55745 157.74622)
		(end 133.55745 157.04721)
		(width 0.508)
		(layer "B.Cu")
		(net "GND")
	)
	(segment
		(start 129.30854 154.38605)
		(end 129.30894 154.38644)
		(width 0.508)
		(layer "B.Cu")
		(net "GND")
	)
	(segment
		(start 125.52608 154.47618)
		(end 125.82366 154.1786)
		(width 0.508)
		(layer "B.Cu")
		(net "GND")
	)
	(segment
		(start 130.12689 154.58472)
		(end 130.42447 154.8823)
		(width 0.508)
		(layer "B.Cu")
		(net "GND")
	)
	(segment
		(start 133.54606 157.7576)
		(end 133.55745 157.74622)
		(width 0.508)
		(layer "B.Cu")
		(net "GND")
	)
	(segment
		(start 129.50722 154.58472)
		(end 130.12689 154.58472)
		(width 0.508)
		(layer "B.Cu")
		(net "GND")
	)
	(segment
		(start 129.50722 157.05975)
		(end 129.50722 154.58472)
		(width 0.508)
		(layer "B.Cu")
		(net "GND")
	)
	(segment
		(start 117.54609 155.01903)
		(end 117.54609 155.01902)
		(width 0.508)
		(layer "B.Cu")
		(net "GND")
	)
	(arc
		(start 117.54609 155.019027)
		(mid 117.604189 154.783119)
		(end 117.765194 154.601169)
		(width 0.508)
		(layer "B.Cu")
		(net "GND")
	)
	(arc
		(start 128.985097 154.238883)
		(mid 129.160104 154.283261)
		(end 129.308538 154.386044)
		(width 0.508)
		(layer "B.Cu")
		(net "GND")
	)
	(segment
		(start 146.23056 104.68967)
		(end 146.3532 104.81232)
		(width 0.2032)
		(layer "F.Cu")
		(net "FPGA_TMS")
	)
	(segment
		(start 226.05432 135.14442)
		(end 226.05432 134.84092)
		(width 0.2032)
		(layer "F.Cu")
		(net "FPGA_TMS")
	)
	(segment
		(start 229.5261 138.9162)
		(end 229.6761 138.7662)
		(width 0.2032)
		(layer "F.Cu")
		(net "FPGA_TMS")
	)
	(segment
		(start 146.17557 104.68967)
		(end 146.23056 104.68967)
		(width 0.2032)
		(layer "F.Cu")
		(net "FPGA_TMS")
	)
	(segment
		(start 214.1261 131.5162)
		(end 214.1261 131.40581)
		(width 0.2032)
		(layer "F.Cu")
		(net "FPGA_TMS")
	)
	(segment
		(start 225.49788 134.58798)
		(end 225.80138 134.58798)
		(width 0.2032)
		(layer "F.Cu")
		(net "FPGA_TMS")
	)
	(segment
		(start 225.80138 134.58798)
		(end 226.05432 134.84092)
		(width 0.2032)
		(layer "F.Cu")
		(net "FPGA_TMS")
	)
	(segment
		(start 156.6261 108.4162)
		(end 172.6261 108.4162)
		(width 0.2032)
		(layer "F.Cu")
		(net "FPGA_TMS")
	)
	(segment
		(start 214.1261 131.5162)
		(end 222.4261 131.5162)
		(width 0.2032)
		(layer "F.Cu")
		(net "FPGA_TMS")
	)
	(segment
		(start 227.8261 140.6162)
		(end 227.8261 136.9162)
		(width 0.2032)
		(layer "F.Cu")
		(net "FPGA_TMS")
	)
	(segment
		(start 194.9261 130.7162)
		(end 213.43649 130.7162)
		(width 0.2032)
		(layer "F.Cu")
		(net "FPGA_TMS")
	)
	(segment
		(start 222.4261 131.5162)
		(end 225.49788 134.58798)
		(width 0.2032)
		(layer "F.Cu")
		(net "FPGA_TMS")
	)
	(segment
		(start 229.5261 141.1162)
		(end 229.5261 138.9162)
		(width 0.2032)
		(layer "F.Cu")
		(net "FPGA_TMS")
	)
	(segment
		(start 228.3261 141.1162)
		(end 229.5261 141.1162)
		(width 0.2032)
		(layer "F.Cu")
		(net "FPGA_TMS")
	)
	(segment
		(start 154.9261 106.7162)
		(end 156.6261 108.4162)
		(width 0.2032)
		(layer "F.Cu")
		(net "FPGA_TMS")
	)
	(segment
		(start 227.8261 140.6162)
		(end 228.3261 141.1162)
		(width 0.2032)
		(layer "F.Cu")
		(net "FPGA_TMS")
	)
	(segment
		(start 146.3532 104.81232)
		(end 147.69091 104.81232)
		(width 0.2032)
		(layer "F.Cu")
		(net "FPGA_TMS")
	)
	(segment
		(start 172.6261 108.4162)
		(end 194.9261 130.7162)
		(width 0.2032)
		(layer "F.Cu")
		(net "FPGA_TMS")
	)
	(segment
		(start 213.43649 130.7162)
		(end 214.1261 131.40581)
		(width 0.2032)
		(layer "F.Cu")
		(net "FPGA_TMS")
	)
	(segment
		(start 226.05432 135.14442)
		(end 227.8261 136.9162)
		(width 0.2032)
		(layer "F.Cu")
		(net "FPGA_TMS")
	)
	(via
		(at 146.17557 104.68967)
		(size 0.4064)
		(drill 0.2032)
		(layers "F.Cu" "B.Cu")
		(tenting
			(front yes)
			(back yes)
		)
		(net "FPGA_TMS")
	)
	(via
		(at 154.9261 106.7162)
		(size 0.4064)
		(drill 0.2032)
		(layers "F.Cu" "B.Cu")
		(tenting
			(front yes)
			(back yes)
		)
		(net "FPGA_TMS")
	)
	(segment
		(start 150.9261 106.7162)
		(end 154.9261 106.7162)
		(width 0.2032)
		(layer "In2.Cu")
		(net "FPGA_TMS")
	)
	(segment
		(start 148.89957 104.68967)
		(end 150.9261 106.7162)
		(width 0.2032)
		(layer "In2.Cu")
		(net "FPGA_TMS")
	)
	(segment
		(start 146.17557 104.68967)
		(end 148.89957 104.68967)
		(width 0.2032)
		(layer "In2.Cu")
		(net "FPGA_TMS")
	)
	(segment
		(start 179.1761 89.9536)
		(end 179.1761 88.14481)
		(width 0.2032)
		(layer "F.Cu")
		(net "+3.3V")
	)
	(segment
		(start 96.5761 73.5286)
		(end 96.6261 73.5786)
		(width 0.508)
		(layer "F.Cu")
		(net "+3.3V")
	)
	(segment
		(start 193.1011 87.1536)
		(end 193.7011 87.1536)
		(width 0.2032)
		(layer "F.Cu")
		(net "+3.3V")
	)
	(segment
		(start 228.3261 111.2162)
		(end 228.9261 110.6162)
		(width 0.2032)
		(layer "F.Cu")
		(net "+3.3V")
	)
	(segment
		(start 82.1261 141.3662)
		(end 82.1261 140.3662)
		(width 0.254)
		(layer "F.Cu")
		(net "+3.3V")
	)
	(segment
		(start 69.91734 127.1162)
		(end 70.01734 127.0162)
		(width 0.254)
		(layer "F.Cu")
		(net "+3.3V")
	)
	(segment
		(start 84.0761 86.3662)
		(end 84.1261 86.4162)
		(width 0.254)
		(layer "F.Cu")
		(net "+3.3V")
	)
	(segment
		(start 121.3687 84.1736)
		(end 122.6261 82.9162)
		(width 0.2032)
		(layer "F.Cu")
		(net "+3.3V")
	)
	(segment
		(start 221.4261 78.8162)
		(end 222.16056 78.8162)
		(width 0.2032)
		(layer "F.Cu")
		(net "+3.3V")
	)
	(segment
		(start 58.33026 116.33704)
		(end 58.4511 116.2162)
		(width 0.254)
		(layer "F.Cu")
		(net "+3.3V")
	)
	(segment
		(start 80.7991 138.4932)
		(end 81.3761 137.9162)
		(width 0.254)
		(layer "F.Cu")
		(net "+3.3V")
	)
	(segment
		(start 92.19855 73.75616)
		(end 93.14029 73.75616)
		(width 0.508)
		(layer "F.Cu")
		(net "+3.3V")
	)
	(segment
		(start 197.4136 85.0161)
		(end 198.73112 85.0161)
		(width 0.2032)
		(layer "F.Cu")
		(net "+3.3V")
	)
	(segment
		(start 224.2261 135.05744)
		(end 224.2261 135.0162)
		(width 0.254)
		(layer "F.Cu")
		(net "+3.3V")
	)
	(segment
		(start 178.1261 90.0786)
		(end 179.0511 90.0786)
		(width 0.2032)
		(layer "F.Cu")
		(net "+3.3V")
	)
	(segment
		(start 57.1261 143.1162)
		(end 57.15526 143.14536)
		(width 0.254)
		(layer "F.Cu")
		(net "+3.3V")
	)
	(segment
		(start 79.3761 125.1162)
		(end 80.5761 125.1162)
		(width 0.254)
		(layer "F.Cu")
		(net "+3.3V")
	)
	(segment
		(start 70.01734 127.0162)
		(end 70.9261 127.0162)
		(width 0.254)
		(layer "F.Cu")
		(net "+3.3V")
	)
	(segment
		(start 75.1261 51.3662)
		(end 75.1261 50.1162)
		(width 0.2032)
		(layer "F.Cu")
		(net "+3.3V")
	)
	(segment
		(start 182.4261 89.0162)
		(end 182.7261 89.3162)
		(width 0.2032)
		(layer "F.Cu")
		(net "+3.3V")
	)
	(segment
		(start 182.7261 89.3162)
		(end 183.2261 89.3162)
		(width 0.2032)
		(layer "F.Cu")
		(net "+3.3V")
	)
	(segment
		(start 219.8761 60.5786)
		(end 219.8761 59.08385)
		(width 0.762)
		(layer "F.Cu")
		(net "+3.3V")
	)
	(segment
		(start 57.1261 129.8662)
		(end 57.1511 129.8412)
		(width 0.254)
		(layer "F.Cu")
		(net "+3.3V")
	)
	(segment
		(start 223.46369 66.5162)
		(end 223.6261 66.67861)
		(width 0.762)
		(layer "F.Cu")
		(net "+3.3V")
	)
	(segment
		(start 79.5761 98.1662)
		(end 80.3761 98.1662)
		(width 0.254)
		(layer "F.Cu")
		(net "+3.3V")
	)
	(segment
		(start 219.47085 58.6786)
		(end 219.8761 59.08385)
		(width 0.762)
		(layer "F.Cu")
		(net "+3.3V")
	)
	(segment
		(start 182.6261 84.5162)
		(end 183.1261 84.0162)
		(width 0.2032)
		(layer "F.Cu")
		(net "+3.3V")
	)
	(segment
		(start 228.3261 111.5162)
		(end 230.1211 111.5162)
		(width 0.2032)
		(layer "F.Cu")
		(net "+3.3V")
	)
	(segment
		(start 106.1761 82.9162)
		(end 108.8761 85.6162)
		(width 0.2032)
		(layer "F.Cu")
		(net "+3.3V")
	)
	(segment
		(start 217.6261 66.5162)
		(end 217.9261 66.8162)
		(width 0.762)
		(layer "F.Cu")
		(net "+3.3V")
	)
	(segment
		(start 193.3761 83.4786)
		(end 193.4761 83.5786)
		(width 0.2032)
		(layer "F.Cu")
		(net "+3.3V")
	)
	(segment
		(start 185.9261 82.00437)
		(end 185.93101 81.99946)
		(width 0.2032)
		(layer "F.Cu")
		(net "+3.3V")
	)
	(segment
		(start 79.12464 83.76811)
		(end 79.37273 84.0162)
		(width 0.2032)
		(layer "F.Cu")
		(net "+3.3V")
	)
	(segment
		(start 217.9261 68.8162)
		(end 217.9261 66.8162)
		(width 0.762)
		(layer "F.Cu")
		(net "+3.3V")
	)
	(segment
		(start 227.8611 132.5162)
		(end 228.4261 131.9512)
		(width 0.2032)
		(layer "F.Cu")
		(net "+3.3V")
	)
	(segment
		(start 120.9761 84.1736)
		(end 121.3687 84.1736)
		(width 0.2032)
		(layer "F.Cu")
		(net "+3.3V")
	)
	(segment
		(start 193.1011 85.8536)
		(end 193.1261 85.8286)
		(width 0.2032)
		(layer "F.Cu")
		(net "+3.3V")
	)
	(segment
		(start 80.6261 111.4162)
		(end 80.6511 111.4162)
		(width 0.254)
		(layer "F.Cu")
		(net "+3.3V")
	)
	(segment
		(start 82.3761 112.8662)
		(end 82.3761 112.8662)
		(width 0.254)
		(layer "F.Cu")
		(net "+3.3V")
	)
	(segment
		(start 80.8011 109.8662)
		(end 81.6261 109.8662)
		(width 0.254)
		(layer "F.Cu")
		(net "+3.3V")
	)
	(segment
		(start 236.8261 134.0162)
		(end 236.8261 134.0162)
		(width 0.2032)
		(layer "F.Cu")
		(net "+3.3V")
	)
	(segment
		(start 84.1261 99.6162)
		(end 84.1261 99.6162)
		(width 0.254)
		(layer "F.Cu")
		(net "+3.3V")
	)
	(segment
		(start 84.1261 99.6162)
		(end 85.1261 99.6162)
		(width 0.254)
		(layer "F.Cu")
		(net "+3.3V")
	)
	(segment
		(start 79.3761 100.6162)
		(end 79.3761 98.3662)
		(width 0.254)
		(layer "F.Cu")
		(net "+3.3V")
	)
	(segment
		(start 84.1261 112.8662)
		(end 85.1261 112.8662)
		(width 0.254)
		(layer "F.Cu")
		(net "+3.3V")
	)
	(segment
		(start 217.6261 66.5162)
		(end 219.2261 66.5162)
		(width 0.762)
		(layer "F.Cu")
		(net "+3.3V")
	)
	(segment
		(start 81.8761 123.9412)
		(end 81.8761 123.3662)
		(width 0.254)
		(layer "F.Cu")
		(net "+3.3V")
	)
	(segment
		(start 202.1261 106.7162)
		(end 202.3261 106.9162)
		(width 0.2032)
		(layer "F.Cu")
		(net "+3.3V")
	)
	(segment
		(start 105.0761 81.8162)
		(end 106.1761 82.9162)
		(width 0.2032)
		(layer "F.Cu")
		(net "+3.3V")
	)
	(segment
		(start 191.6261 85.5162)
		(end 192.2261 84.9162)
		(width 0.2032)
		(layer "F.Cu")
		(net "+3.3V")
	)
	(segment
		(start 93.32866 73.56779)
		(end 94.33692 73.56779)
		(width 0.508)
		(layer "F.Cu")
		(net "+3.3V")
	)
	(segment
		(start 80.4011 98.1662)
		(end 81.3761 97.1912)
		(width 0.254)
		(layer "F.Cu")
		(net "+3.3V")
	)
	(segment
		(start 80.8011 123.1162)
		(end 81.6261 123.1162)
		(width 0.254)
		(layer "F.Cu")
		(net "+3.3V")
	)
	(segment
		(start 224.2261 135.05744)
		(end 224.2761 135.10744)
		(width 0.254)
		(layer "F.Cu")
		(net "+3.3V")
	)
	(segment
		(start 57.1511 73.0912)
		(end 58.4261 73.0912)
		(width 0.254)
		(layer "F.Cu")
		(net "+3.3V")
	)
	(segment
		(start 83.1341 115.5866)
		(end 85.9965 115.5866)
		(width 0.508)
		(layer "F.Cu")
		(net "+3.3V")
	)
	(segment
		(start 80.4011 138.9162)
		(end 80.7991 138.5182)
		(width 0.254)
		(layer "F.Cu")
		(net "+3.3V")
	)
	(segment
		(start 70.8761 98.40744)
		(end 70.8761 98.3662)
		(width 0.254)
		(layer "F.Cu")
		(net "+3.3V")
	)
	(segment
		(start 82.3761 114.1162)
		(end 82.3761 112.8662)
		(width 0.254)
		(layer "F.Cu")
		(net "+3.3V")
	)
	(segment
		(start 210.2661 132.1762)
		(end 210.3261 132.1162)
		(width 0.508)
		(layer "F.Cu")
		(net "+3.3V")
	)
	(segment
		(start 192.41136 140.37763)
		(end 192.4526 140.37763)
		(width 0.254)
		(layer "F.Cu")
		(net "+3.3V")
	)
	(segment
		(start 192.4526 140.37763)
		(end 192.8026 140.02763)
		(width 0.254)
		(layer "F.Cu")
		(net "+3.3V")
	)
	(segment
		(start 57.15526 116.33704)
		(end 58.33026 116.33704)
		(width 0.254)
		(layer "F.Cu")
		(net "+3.3V")
	)
	(segment
		(start 224.5261 131.5162)
		(end 224.5261 128.7162)
		(width 0.2032)
		(layer "F.Cu")
		(net "+3.3V")
	)
	(segment
		(start 227.0861 111.5162)
		(end 228.3261 111.5162)
		(width 0.2032)
		(layer "F.Cu")
		(net "+3.3V")
	)
	(segment
		(start 219.3761 57.42119)
		(end 219.46876 57.51385)
		(width 0.762)
		(layer "F.Cu")
		(net "+3.3V")
	)
	(segment
		(start 80.6511 125.1662)
		(end 81.8761 123.9412)
		(width 0.254)
		(layer "F.Cu")
		(net "+3.3V")
	)
	(segment
		(start 108.8761 85.6162)
		(end 109.2261 85.6162)
		(width 0.2032)
		(layer "F.Cu")
		(net "+3.3V")
	)
	(segment
		(start 84.3761 126.6162)
		(end 85.3761 126.6162)
		(width 0.254)
		(layer "F.Cu")
		(net "+3.3V")
	)
	(segment
		(start 219.46876 58.67651)
		(end 219.47085 58.6786)
		(width 0.762)
		(layer "F.Cu")
		(net "+3.3V")
	)
	(segment
		(start 189.6386 86.4662)
		(end 190.7161 86.4662)
		(width 0.2032)
		(layer "F.Cu")
		(net "+3.3V")
	)
	(segment
		(start 226.5261 129.3162)
		(end 228.4261 129.3162)
		(width 0.2032)
		(layer "F.Cu")
		(net "+3.3V")
	)
	(segment
		(start 174.0261 89.8162)
		(end 174.0261 88.7662)
		(width 0.2032)
		(layer "F.Cu")
		(net "+3.3V")
	)
	(segment
		(start 81.79589 110.27141)
		(end 81.79589 110.03599)
		(width 0.254)
		(layer "F.Cu")
		(net "+3.3V")
	)
	(segment
		(start 226.6261 111.9762)
		(end 227.0861 111.5162)
		(width 0.2032)
		(layer "F.Cu")
		(net "+3.3V")
	)
	(segment
		(start 126.7261 83.9162)
		(end 126.7261 83.58174)
		(width 0.2032)
		(layer "F.Cu")
		(net "+3.3V")
	)
	(segment
		(start 174.8011 83.3162)
		(end 175.7261 83.3162)
		(width 0.2032)
		(layer "F.Cu")
		(net "+3.3V")
	)
	(segment
		(start 88.9261 65.8162)
		(end 89.2261 66.1162)
		(width 0.762)
		(layer "F.Cu")
		(net "+3.3V")
	)
	(segment
		(start 232.23929 135.3162)
		(end 233.2761 135.3162)
		(width 0.2032)
		(layer "F.Cu")
		(net "+3.3V")
	)
	(segment
		(start 220.5261 78.8162)
		(end 221.4261 78.8162)
		(width 0.2032)
		(layer "F.Cu")
		(net "+3.3V")
	)
	(segment
		(start 92.1011 73.8536)
		(end 92.19855 73.75616)
		(width 0.508)
		(layer "F.Cu")
		(net "+3.3V")
	)
	(segment
		(start 232.02738 135.52811)
		(end 232.23929 135.3162)
		(width 0.2032)
		(layer "F.Cu")
		(net "+3.3V")
	)
	(segment
		(start 212.7261 132.0162)
		(end 212.8061 132.0962)
		(width 0.508)
		(layer "F.Cu")
		(net "+3.3V")
	)
	(segment
		(start 205.3261 106.9162)
		(end 205.7261 107.3162)
		(width 0.2032)
		(layer "F.Cu")
		(net "+3.3V")
	)
	(segment
		(start 86.3761 65.82859)
		(end 88.91371 65.82859)
		(width 0.762)
		(layer "F.Cu")
		(net "+3.3V")
	)
	(segment
		(start 85.3761 86.6162)
		(end 87.0511 86.6162)
		(width 0.254)
		(layer "F.Cu")
		(net "+3.3V")
	)
	(segment
		(start 228.4261 129.4112)
		(end 228.4261 129.3162)
		(width 0.2032)
		(layer "F.Cu")
		(net "+3.3V")
	)
	(segment
		(start 57.1261 84.1162)
		(end 57.1511 84.0912)
		(width 0.254)
		(layer "F.Cu")
		(net "+3.3V")
	)
	(segment
		(start 83.1261 115.5786)
		(end 83.1341 115.5866)
		(width 0.508)
		(layer "F.Cu")
		(net "+3.3V")
	)
	(segment
		(start 131.5761 82.1286)
		(end 131.6261 82.0786)
		(width 0.508)
		(layer "F.Cu")
		(net "+3.3V")
	)
	(segment
		(start 79.37273 84.0162)
		(end 79.9261 84.0162)
		(width 0.2032)
		(layer "F.Cu")
		(net "+3.3V")
	)
	(segment
		(start 193.93636 144.15263)
		(end 193.96136 144.12763)
		(width 0.254)
		(layer "F.Cu")
		(net "+3.3V")
	)
	(segment
		(start 219.46876 58.67651)
		(end 219.46876 57.51385)
		(width 0.762)
		(layer "F.Cu")
		(net "+3.3V")
	)
	(segment
		(start 179.0511 90.0786)
		(end 179.1761 89.9536)
		(width 0.2032)
		(layer "F.Cu")
		(net "+3.3V")
	)
	(segment
		(start 214.76056 78.8162)
		(end 214.8261 78.88173)
		(width 0.2032)
		(layer "F.Cu")
		(net "+3.3V")
	)
	(segment
		(start 199.2661 91.0162)
		(end 199.2661 89.4762)
		(width 0.2032)
		(layer "F.Cu")
		(net "+3.3V")
	)
	(segment
		(start 131.61799 83.62049)
		(end 132.8631 83.62049)
		(width 0.508)
		(layer "F.Cu")
		(net "+3.3V")
	)
	(segment
		(start 57.15526 143.14536)
		(end 58.38026 143.14536)
		(width 0.254)
		(layer "F.Cu")
		(net "+3.3V")
	)
	(segment
		(start 224.5261 128.7162)
		(end 225.1261 128.1162)
		(width 0.2032)
		(layer "F.Cu")
		(net "+3.3V")
	)
	(segment
		(start 126.2261 84.4162)
		(end 126.7261 83.9162)
		(width 0.2032)
		(layer "F.Cu")
		(net "+3.3V")
	)
	(segment
		(start 189.6261 88.7162)
		(end 189.9261 89.0162)
		(width 0.2032)
		(layer "F.Cu")
		(net "+3.3V")
	)
	(segment
		(start 200.26661 90.87068)
		(end 201.2211 89.9162)
		(width 0.2032)
		(layer "F.Cu")
		(net "+3.3V")
	)
	(segment
		(start 193.1261 85.3536)
		(end 193.4761 85.0036)
		(width 0.2032)
		(layer "F.Cu")
		(net "+3.3V")
	)
	(segment
		(start 176.8761 88.8286)
		(end 178.1261 90.0786)
		(width 0.2032)
		(layer "F.Cu")
		(net "+3.3V")
	)
	(segment
		(start 121.24733 81.74808)
		(end 122.11545 82.6162)
		(width 0.2032)
		(layer "F.Cu")
		(net "+3.3V")
	)
	(segment
		(start 81.41734 86.3662)
		(end 84.0761 86.3662)
		(width 0.254)
		(layer "F.Cu")
		(net "+3.3V")
	)
	(segment
		(start 192.8026 140.02763)
		(end 193.98636 140.02763)
		(width 0.254)
		(layer "F.Cu")
		(net "+3.3V")
	)
	(segment
		(start 81.22731 96.3662)
		(end 81.3761 96.51499)
		(width 0.254)
		(layer "F.Cu")
		(net "+3.3V")
	)
	(segment
		(start 80.6511 111.4162)
		(end 81.79589 110.27141)
		(width 0.254)
		(layer "F.Cu")
		(net "+3.3V")
	)
	(segment
		(start 165.41661 83.64891)
		(end 165.84933 83.2162)
		(width 0.2032)
		(layer "F.Cu")
		(net "+3.3V")
	)
	(segment
		(start 86.3761 73.8286)
		(end 86.4011 73.8536)
		(width 0.508)
		(layer "F.Cu")
		(net "+3.3V")
	)
	(segment
		(start 194.3511 86.5036)
		(end 195.1511 86.5036)
		(width 0.2032)
		(layer "F.Cu")
		(net "+3.3V")
	)
	(segment
		(start 193.4761 85.0036)
		(end 193.4761 83.5786)
		(width 0.2032)
		(layer "F.Cu")
		(net "+3.3V")
	)
	(segment
		(start 81.3761 97.1912)
		(end 81.3761 96.51499)
		(width 0.254)
		(layer "F.Cu")
		(net "+3.3V")
	)
	(segment
		(start 210.2661 135.5162)
		(end 210.2661 132.1762)
		(width 0.508)
		(layer "F.Cu")
		(net "+3.3V")
	)
	(segment
		(start 189.0761 88.1662)
		(end 189.0761 87.7787)
		(width 0.2032)
		(layer "F.Cu")
		(net "+3.3V")
	)
	(segment
		(start 69.8761 51.3662)
		(end 69.8761 50.1162)
		(width 0.2032)
		(layer "F.Cu")
		(net "+3.3V")
	)
	(segment
		(start 80.3761 138.9162)
		(end 80.4011 138.9162)
		(width 0.254)
		(layer "F.Cu")
		(net "+3.3V")
	)
	(segment
		(start 193.3761 81.5866)
		(end 193.3761 81.5786)
		(width 0.2032)
		(layer "F.Cu")
		(net "+3.3V")
	)
	(segment
		(start 84.1261 140.3662)
		(end 85.3761 140.3662)
		(width 0.254)
		(layer "F.Cu")
		(net "+3.3V")
	)
	(segment
		(start 73.3761 51.3662)
		(end 73.3761 50.1162)
		(width 0.2032)
		(layer "F.Cu")
		(net "+3.3V")
	)
	(segment
		(start 81.1261 86.1162)
		(end 81.16734 86.1162)
		(width 0.254)
		(layer "F.Cu")
		(net "+3.3V")
	)
	(segment
		(start 197.3511 85.0036)
		(end 197.3761 84.9786)
		(width 0.2032)
		(layer "F.Cu")
		(net "+3.3V")
	)
	(segment
		(start 190.7161 86.4662)
		(end 190.8261 86.5762)
		(width 0.2032)
		(layer "F.Cu")
		(net "+3.3V")
	)
	(segment
		(start 80.5511 136.8662)
		(end 81.22731 136.8662)
		(width 0.254)
		(layer "F.Cu")
		(net "+3.3V")
	)
	(segment
		(start 226.5261 129.3162)
		(end 226.5261 127.9162)
		(width 0.2032)
		(layer "F.Cu")
		(net "+3.3V")
	)
	(segment
		(start 193.7011 87.1536)
		(end 194.3511 86.5036)
		(width 0.2032)
		(layer "F.Cu")
		(net "+3.3V")
	)
	(segment
		(start 80.5761 125.1162)
		(end 80.6261 125.1662)
		(width 0.254)
		(layer "F.Cu")
		(net "+3.3V")
	)
	(segment
		(start 91.8261 66.5162)
		(end 94.7261 66.5162)
		(width 0.762)
		(layer "F.Cu")
		(net "+3.3V")
	)
	(segment
		(start 189.9261 89.0162)
		(end 190.6861 89.0162)
		(width 0.2032)
		(layer "F.Cu")
		(net "+3.3V")
	)
	(segment
		(start 80.3261 138.8662)
		(end 80.3761 138.9162)
		(width 0.254)
		(layer "F.Cu")
		(net "+3.3V")
	)
	(segment
		(start 82.3761 127.6162)
		(end 82.3761 126.6162)
		(width 0.254)
		(layer "F.Cu")
		(net "+3.3V")
	)
	(segment
		(start 226.5261 127.9162)
		(end 226.6261 127.9162)
		(width 0.2032)
		(layer "F.Cu")
		(net "+3.3V")
	)
	(segment
		(start 90.1261 122.0786)
		(end 91.2461 122.0786)
		(width 0.508)
		(layer "F.Cu")
		(net "+3.3V")
	)
	(segment
		(start 192.53636 144.15263)
		(end 193.93636 144.15263)
		(width 0.254)
		(layer "F.Cu")
		(net "+3.3V")
	)
	(segment
		(start 230.1211 111.5162)
		(end 230.4261 111.2112)
		(width 0.2032)
		(layer "F.Cu")
		(net "+3.3V")
	)
	(segment
		(start 162.0261 90.7162)
		(end 162.94002 89.80228)
		(width 0.2032)
		(layer "F.Cu")
		(net "+3.3V")
	)
	(segment
		(start 81.6261 123.1162)
		(end 81.8761 123.3662)
		(width 0.254)
		(layer "F.Cu")
		(net "+3.3V")
	)
	(segment
		(start 191.3261 83.0162)
		(end 192.3261 83.0162)
		(width 0.2032)
		(layer "F.Cu")
		(net "+3.3V")
	)
	(segment
		(start 190.8261 86.5762)
		(end 191.5661 86.5762)
		(width 0.2032)
		(layer "F.Cu")
		(net "+3.3V")
	)
	(segment
		(start 81.16734 86.1162)
		(end 81.41734 86.3662)
		(width 0.254)
		(layer "F.Cu")
		(net "+3.3V")
	)
	(segment
		(start 202.3261 106.9162)
		(end 205.3261 106.9162)
		(width 0.2032)
		(layer "F.Cu")
		(net "+3.3V")
	)
	(segment
		(start 79.3761 111.3662)
		(end 79.41734 111.3662)
		(width 0.254)
		(layer "F.Cu")
		(net "+3.3V")
	)
	(segment
		(start 90.1261 122.0786)
		(end 90.1261 119.7162)
		(width 0.508)
		(layer "F.Cu")
		(net "+3.3V")
	)
	(segment
		(start 85.1261 86.3662)
		(end 85.3761 86.6162)
		(width 0.254)
		(layer "F.Cu")
		(net "+3.3V")
	)
	(segment
		(start 185.9261 82.8162)
		(end 185.9261 82.00437)
		(width 0.2032)
		(layer "F.Cu")
		(net "+3.3V")
	)
	(segment
		(start 197.0511 86.5036)
		(end 197.3511 86.2036)
		(width 0.2032)
		(layer "F.Cu")
		(net "+3.3V")
	)
	(segment
		(start 167.2261 89.7877)
		(end 167.2261 88.8662)
		(width 0.2032)
		(layer "F.Cu")
		(net "+3.3V")
	)
	(segment
		(start 80.5511 96.3662)
		(end 81.22731 96.3662)
		(width 0.254)
		(layer "F.Cu")
		(net "+3.3V")
	)
	(segment
		(start 131.5761 83.5786)
		(end 131.61799 83.62049)
		(width 0.508)
		(layer "F.Cu")
		(net "+3.3V")
	)
	(segment
		(start 225.5261 132.5162)
		(end 227.8611 132.5162)
		(width 0.2032)
		(layer "F.Cu")
		(net "+3.3V")
	)
	(segment
		(start 89.2261 66.1162)
		(end 91.4261 66.1162)
		(width 0.762)
		(layer "F.Cu")
		(net "+3.3V")
	)
	(segment
		(start 81.6261 109.8662)
		(end 81.79589 110.03599)
		(width 0.254)
		(layer "F.Cu")
		(net "+3.3V")
	)
	(segment
		(start 84.1761 86.3662)
		(end 85.1261 86.3662)
		(width 0.254)
		(layer "F.Cu")
		(net "+3.3V")
	)
	(segment
		(start 229.0261 136.5162)
		(end 229.0261 135.0162)
		(width 0.254)
		(layer "F.Cu")
		(net "+3.3V")
	)
	(segment
		(start 58.4261 73.0912)
		(end 58.4511 73.0662)
		(width 0.254)
		(layer "F.Cu")
		(net "+3.3V")
	)
	(segment
		(start 82.1261 100.6162)
		(end 82.1261 99.6162)
		(width 0.254)
		(layer "F.Cu")
		(net "+3.3V")
	)
	(segment
		(start 79.41734 111.3662)
		(end 79.46734 111.4162)
		(width 0.254)
		(layer "F.Cu")
		(net "+3.3V")
	)
	(segment
		(start 94.33692 73.56779)
		(end 94.3761 73.5286)
		(width 0.508)
		(layer "F.Cu")
		(net "+3.3V")
	)
	(segment
		(start 197.3761 84.9786)
		(end 197.4136 85.0161)
		(width 0.2032)
		(layer "F.Cu")
		(net "+3.3V")
	)
	(segment
		(start 79.1261 138.8662)
		(end 80.3261 138.8662)
		(width 0.254)
		(layer "F.Cu")
		(net "+3.3V")
	)
	(segment
		(start 103.4761 81.8162)
		(end 105.0761 81.8162)
		(width 0.2032)
		(layer "F.Cu")
		(net "+3.3V")
	)
	(segment
		(start 225.1261 128.1162)
		(end 226.8738 128.1162)
		(width 0.2032)
		(layer "F.Cu")
		(net "+3.3V")
	)
	(segment
		(start 176.8761 88.8286)
		(end 176.8761 87.7786)
		(width 0.2032)
		(layer "F.Cu")
		(net "+3.3V")
	)
	(segment
		(start 57.1511 84.0912)
		(end 58.4261 84.0912)
		(width 0.254)
		(layer "F.Cu")
		(net "+3.3V")
	)
	(segment
		(start 81.22731 136.8662)
		(end 81.3761 137.01499)
		(width 0.254)
		(layer "F.Cu")
		(net "+3.3V")
	)
	(segment
		(start 219.2261 66.5162)
		(end 223.46369 66.5162)
		(width 0.762)
		(layer "F.Cu")
		(net "+3.3V")
	)
	(segment
		(start 182.6261 84.8162)
		(end 182.6261 84.5162)
		(width 0.2032)
		(layer "F.Cu")
		(net "+3.3V")
	)
	(segment
		(start 219.3761 57.42119)
		(end 219.3761 57.3662)
		(width 0.762)
		(layer "F.Cu")
		(net "+3.3V")
	)
	(segment
		(start 175.88849 88.7662)
		(end 176.8761 87.7786)
		(width 0.2032)
		(layer "F.Cu")
		(net "+3.3V")
	)
	(segment
		(start 201.6261 123.9162)
		(end 202.5261 123.9162)
		(width 0.2032)
		(layer "F.Cu")
		(net "+3.3V")
	)
	(segment
		(start 85.9965 115.5866)
		(end 90.1261 119.7162)
		(width 0.508)
		(layer "F.Cu")
		(net "+3.3V")
	)
	(segment
		(start 79.9261 84.0162)
		(end 79.9261 83.1162)
		(width 0.2032)
		(layer "F.Cu")
		(net "+3.3V")
	)
	(segment
		(start 160.2261 90.7162)
		(end 162.0261 90.7162)
		(width 0.2032)
		(layer "F.Cu")
		(net "+3.3V")
	)
	(segment
		(start 57.1261 73.1162)
		(end 57.1511 73.0912)
		(width 0.254)
		(layer "F.Cu")
		(net "+3.3V")
	)
	(segment
		(start 230.9261 118.9162)
		(end 232.4261 117.4162)
		(width 0.2032)
		(layer "F.Cu")
		(net "+3.3V")
	)
	(segment
		(start 57.1261 102.8662)
		(end 57.1511 102.8412)
		(width 0.254)
		(layer "F.Cu")
		(net "+3.3V")
	)
	(segment
		(start 161.7261 90.0162)
		(end 165.41661 86.32569)
		(width 0.2032)
		(layer "F.Cu")
		(net "+3.3V")
	)
	(segment
		(start 133.30121 84.0586)
		(end 134.1261 84.0586)
		(width 0.508)
		(layer "F.Cu")
		(net "+3.3V")
	)
	(segment
		(start 84.1261 86.4162)
		(end 84.1761 86.3662)
		(width 0.254)
		(layer "F.Cu")
		(net "+3.3V")
	)
	(segment
		(start 58.4261 84.0912)
		(end 58.4511 84.0662)
		(width 0.254)
		(layer "F.Cu")
		(net "+3.3V")
	)
	(segment
		(start 57.1511 129.8412)
		(end 58.4261 129.8412)
		(width 0.254)
		(layer "F.Cu")
		(net "+3.3V")
	)
	(segment
		(start 165.41661 86.32569)
		(end 165.41661 83.64891)
		(width 0.2032)
		(layer "F.Cu")
		(net "+3.3V")
	)
	(segment
		(start 70.9261 99.6662)
		(end 70.9261 98.45744)
		(width 0.254)
		(layer "F.Cu")
		(net "+3.3V")
	)
	(segment
		(start 88.91371 65.82859)
		(end 88.9261 65.8162)
		(width 0.762)
		(layer "F.Cu")
		(net "+3.3V")
	)
	(segment
		(start 228.3261 111.5162)
		(end 228.3261 111.2162)
		(width 0.2032)
		(layer "F.Cu")
		(net "+3.3V")
	)
	(segment
		(start 191.5661 86.5762)
		(end 191.6261 86.5162)
		(width 0.2032)
		(layer "F.Cu")
		(net "+3.3V")
	)
	(segment
		(start 232.4261 117.4162)
		(end 232.7261 117.4162)
		(width 0.2032)
		(layer "F.Cu")
		(net "+3.3V")
	)
	(segment
		(start 86.4011 73.8536)
		(end 92.1011 73.8536)
		(width 0.508)
		(layer "F.Cu")
		(net "+3.3V")
	)
	(segment
		(start 199.2661 89.4762)
		(end 199.6261 89.1162)
		(width 0.2032)
		(layer "F.Cu")
		(net "+3.3V")
	)
	(segment
		(start 79.3761 98.3662)
		(end 79.5761 98.1662)
		(width 0.254)
		(layer "F.Cu")
		(net "+3.3V")
	)
	(segment
		(start 195.1511 86.5036)
		(end 197.0511 86.5036)
		(width 0.2032)
		(layer "F.Cu")
		(net "+3.3V")
	)
	(segment
		(start 167.2261 89.7877)
		(end 167.24068 89.80228)
		(width 0.2032)
		(layer "F.Cu")
		(net "+3.3V")
	)
	(segment
		(start 93.14029 73.75616)
		(end 93.32866 73.56779)
		(width 0.508)
		(layer "F.Cu")
		(net "+3.3V")
	)
	(segment
		(start 58.38026 143.14536)
		(end 58.4511 143.2162)
		(width 0.254)
		(layer "F.Cu")
		(net "+3.3V")
	)
	(segment
		(start 219.47085 58.6786)
		(end 223.6261 58.6786)
		(width 0.762)
		(layer "F.Cu")
		(net "+3.3V")
	)
	(segment
		(start 193.3761 83.4786)
		(end 193.3761 81.5866)
		(width 0.2032)
		(layer "F.Cu")
		(net "+3.3V")
	)
	(segment
		(start 191.3261 83.0162)
		(end 191.3261 82.21628)
		(width 0.2032)
		(layer "F.Cu")
		(net "+3.3V")
	)
	(segment
		(start 80.3761 98.1662)
		(end 80.4011 98.1662)
		(width 0.254)
		(layer "F.Cu")
		(net "+3.3V")
	)
	(segment
		(start 70.8761 98.40744)
		(end 70.9261 98.45744)
		(width 0.254)
		(layer "F.Cu")
		(net "+3.3V")
	)
	(segment
		(start 236.8261 134.0162)
		(end 236.8261 132.9162)
		(width 0.2032)
		(layer "F.Cu")
		(net "+3.3V")
	)
	(segment
		(start 224.2761 136.4912)
		(end 224.2761 135.10744)
		(width 0.254)
		(layer "F.Cu")
		(net "+3.3V")
	)
	(segment
		(start 81.3761 137.9162)
		(end 81.3761 137.01499)
		(width 0.254)
		(layer "F.Cu")
		(net "+3.3V")
	)
	(segment
		(start 102.3761 82.9162)
		(end 103.4761 81.8162)
		(width 0.2032)
		(layer "F.Cu")
		(net "+3.3V")
	)
	(segment
		(start 91.4261 66.1162)
		(end 91.8261 66.5162)
		(width 0.762)
		(layer "F.Cu")
		(net "+3.3V")
	)
	(segment
		(start 213.6261 78.8162)
		(end 214.76056 78.8162)
		(width 0.2032)
		(layer "F.Cu")
		(net "+3.3V")
	)
	(segment
		(start 57.1511 102.8412)
		(end 58.4261 102.8412)
		(width 0.254)
		(layer "F.Cu")
		(net "+3.3V")
	)
	(segment
		(start 126.7261 83.58174)
		(end 127.5356 83.58174)
		(width 0.2032)
		(layer "F.Cu")
		(net "+3.3V")
	)
	(segment
		(start 131.5761 83.5786)
		(end 131.5761 82.1286)
		(width 0.508)
		(layer "F.Cu")
		(net "+3.3V")
	)
	(segment
		(start 200.11524 91.0162)
		(end 200.26076 90.87068)
		(width 0.2032)
		(layer "F.Cu")
		(net "+3.3V")
	)
	(segment
		(start 174.0261 88.7662)
		(end 175.88849 88.7662)
		(width 0.2032)
		(layer "F.Cu")
		(net "+3.3V")
	)
	(segment
		(start 189.0761 88.1662)
		(end 189.6261 88.7162)
		(width 0.2032)
		(layer "F.Cu")
		(net "+3.3V")
	)
	(segment
		(start 193.1261 85.8286)
		(end 193.1261 85.3536)
		(width 0.2032)
		(layer "F.Cu")
		(net "+3.3V")
	)
	(segment
		(start 212.8061 135.5162)
		(end 212.8061 132.0962)
		(width 0.508)
		(layer "F.Cu")
		(net "+3.3V")
	)
	(segment
		(start 94.3761 73.5286)
		(end 96.5761 73.5286)
		(width 0.508)
		(layer "F.Cu")
		(net "+3.3V")
	)
	(segment
		(start 199.2661 91.0162)
		(end 200.11524 91.0162)
		(width 0.2032)
		(layer "F.Cu")
		(net "+3.3V")
	)
	(segment
		(start 224.5261 131.5162)
		(end 225.5261 132.5162)
		(width 0.2032)
		(layer "F.Cu")
		(net "+3.3V")
	)
	(segment
		(start 79.46734 111.4162)
		(end 80.6261 111.4162)
		(width 0.254)
		(layer "F.Cu")
		(net "+3.3V")
	)
	(segment
		(start 122.11545 82.6162)
		(end 122.6261 82.6162)
		(width 0.2032)
		(layer "F.Cu")
		(net "+3.3V")
	)
	(segment
		(start 127.5356 83.58174)
		(end 127.56334 83.554)
		(width 0.2032)
		(layer "F.Cu")
		(net "+3.3V")
	)
	(segment
		(start 192.51136 144.17763)
		(end 192.53636 144.15263)
		(width 0.254)
		(layer "F.Cu")
		(net "+3.3V")
	)
	(segment
		(start 80.7991 138.5182)
		(end 80.7991 138.4932)
		(width 0.254)
		(layer "F.Cu")
		(net "+3.3V")
	)
	(segment
		(start 212.1761 78.8162)
		(end 213.6261 78.8162)
		(width 0.2032)
		(layer "F.Cu")
		(net "+3.3V")
	)
	(segment
		(start 58.4261 129.8412)
		(end 58.4511 129.8162)
		(width 0.254)
		(layer "F.Cu")
		(net "+3.3V")
	)
	(segment
		(start 191.32077 82.21095)
		(end 191.3261 82.21628)
		(width 0.2032)
		(layer "F.Cu")
		(net "+3.3V")
	)
	(segment
		(start 162.94002 89.80228)
		(end 167.24068 89.80228)
		(width 0.2032)
		(layer "F.Cu")
		(net "+3.3V")
	)
	(segment
		(start 165.84933 83.2162)
		(end 166.4261 83.2162)
		(width 0.2032)
		(layer "F.Cu")
		(net "+3.3V")
	)
	(segment
		(start 132.8631 83.62049)
		(end 133.30121 84.0586)
		(width 0.508)
		(layer "F.Cu")
		(net "+3.3V")
	)
	(segment
		(start 200.26076 90.87068)
		(end 200.26661 90.87068)
		(width 0.2032)
		(layer "F.Cu")
		(net "+3.3V")
	)
	(segment
		(start 58.4261 102.8412)
		(end 58.4511 102.8162)
		(width 0.254)
		(layer "F.Cu")
		(net "+3.3V")
	)
	(segment
		(start 126.2261 85.2662)
		(end 126.2261 84.4162)
		(width 0.2032)
		(layer "F.Cu")
		(net "+3.3V")
	)
	(segment
		(start 69.8761 127.1162)
		(end 69.91734 127.1162)
		(width 0.254)
		(layer "F.Cu")
		(net "+3.3V")
	)
	(segment
		(start 57.1261 116.3662)
		(end 57.15526 116.33704)
		(width 0.254)
		(layer "F.Cu")
		(net "+3.3V")
	)
	(segment
		(start 160.1261 90.0162)
		(end 161.7261 90.0162)
		(width 0.2032)
		(layer "F.Cu")
		(net "+3.3V")
	)
	(segment
		(start 80.6261 125.1662)
		(end 80.6511 125.1662)
		(width 0.254)
		(layer "F.Cu")
		(net "+3.3V")
	)
	(segment
		(start 197.3511 86.2036)
		(end 197.3511 85.0036)
		(width 0.2032)
		(layer "F.Cu")
		(net "+3.3V")
	)
	(segment
		(start 71.6261 51.3662)
		(end 71.6261 50.0786)
		(width 0.2032)
		(layer "F.Cu")
		(net "+3.3V")
	)
	(via
		(at 85.3761 126.6162)
		(size 0.4064)
		(drill 0.2032)
		(layers "F.Cu" "B.Cu")
		(tenting
			(front yes)
			(back yes)
		)
		(net "+3.3V")
	)
	(via
		(at 159.4261 90.1162)
		(size 0.4064)
		(drill 0.2032)
		(layers "F.Cu" "B.Cu")
		(tenting
			(front yes)
			(back yes)
		)
		(net "+3.3V")
	)
	(via
		(at 228.8261 126.1162)
		(size 0.4064)
		(drill 0.2032)
		(layers "F.Cu" "B.Cu")
		(net "+3.3V")
	)
	(via
		(at 235.8261 95.8162)
		(size 0.4064)
		(drill 0.2032)
		(layers "F.Cu" "B.Cu")
		(net "+3.3V")
	)
	(via
		(at 57.1261 116.3662)
		(size 0.4064)
		(drill 0.2032)
		(layers "F.Cu" "B.Cu")
		(tenting
			(front yes)
			(back yes)
		)
		(net "+3.3V")
	)
	(via
		(at 79.3761 125.1162)
		(size 0.4064)
		(drill 0.2032)
		(layers "F.Cu" "B.Cu")
		(tenting
			(front yes)
			(back yes)
		)
		(net "+3.3V")
	)
	(via
		(at 88.9261 65.8162)
		(size 0.4064)
		(drill 0.2032)
		(layers "F.Cu" "B.Cu")
		(tenting
			(front yes)
			(back yes)
		)
		(net "+3.3V")
	)
	(via
		(at 175.7261 83.3162)
		(size 0.4064)
		(drill 0.2032)
		(layers "F.Cu" "B.Cu")
		(net "+3.3V")
	)
	(via
		(at 82.1261 100.6162)
		(size 0.4064)
		(drill 0.2032)
		(layers "F.Cu" "B.Cu")
		(tenting
			(front yes)
			(back yes)
		)
		(net "+3.3V")
	)
	(via
		(at 237.0261 96.2162)
		(size 0.4064)
		(drill 0.2032)
		(layers "F.Cu" "B.Cu")
		(net "+3.3V")
	)
	(via
		(at 156.3261 77.8162)
		(size 0.4064)
		(drill 0.2032)
		(layers "F.Cu" "B.Cu")
		(tenting
			(front yes)
			(back yes)
		)
		(net "+3.3V")
	)
	(via
		(at 82.3761 114.1162)
		(size 0.4064)
		(drill 0.2032)
		(layers "F.Cu" "B.Cu")
		(tenting
			(front yes)
			(back yes)
		)
		(net "+3.3V")
	)
	(via
		(at 224.2261 135.0162)
		(size 0.4064)
		(drill 0.2032)
		(layers "F.Cu" "B.Cu")
		(tenting
			(front yes)
			(back yes)
		)
		(net "+3.3V")
	)
	(via
		(at 75.1261 50.1162)
		(size 0.4064)
		(drill 0.2032)
		(layers "F.Cu" "B.Cu")
		(tenting
			(front yes)
			(back yes)
		)
		(net "+3.3V")
	)
	(via
		(at 159.0261 91.2162)
		(size 0.4064)
		(drill 0.2032)
		(layers "F.Cu" "B.Cu")
		(tenting
			(front yes)
			(back yes)
		)
		(net "+3.3V")
	)
	(via
		(at 79.12464 83.76811)
		(size 0.4064)
		(drill 0.2032)
		(layers "F.Cu" "B.Cu")
		(net "+3.3V")
	)
	(via
		(at 156.3261 74.4162)
		(size 0.4064)
		(drill 0.2032)
		(layers "F.Cu" "B.Cu")
		(tenting
			(front yes)
			(back yes)
		)
		(net "+3.3V")
	)
	(via
		(at 79.3761 111.3662)
		(size 0.4064)
		(drill 0.2032)
		(layers "F.Cu" "B.Cu")
		(tenting
			(front yes)
			(back yes)
		)
		(net "+3.3V")
	)
	(via
		(at 227.9261 125.9162)
		(size 0.4064)
		(drill 0.2032)
		(layers "F.Cu" "B.Cu")
		(net "+3.3V")
	)
	(via
		(at 85.1261 99.6162)
		(size 0.4064)
		(drill 0.2032)
		(layers "F.Cu" "B.Cu")
		(tenting
			(front yes)
			(back yes)
		)
		(net "+3.3V")
	)
	(via
		(at 160.1261 90.0162)
		(size 0.4064)
		(drill 0.2032)
		(layers "F.Cu" "B.Cu")
		(tenting
			(front yes)
			(back yes)
		)
		(net "+3.3V")
	)
	(via
		(at 160.0261 90.9162)
		(size 0.4064)
		(drill 0.2032)
		(layers "F.Cu" "B.Cu")
		(tenting
			(front yes)
			(back yes)
		)
		(net "+3.3V")
	)
	(via
		(at 213.6261 78.8162)
		(size 0.4064)
		(drill 0.2032)
		(layers "F.Cu" "B.Cu")
		(net "+3.3V")
	)
	(via
		(at 90.1261 122.0786)
		(size 0.4064)
		(drill 0.2032)
		(layers "F.Cu" "B.Cu")
		(tenting
			(front yes)
			(back yes)
		)
		(net "+3.3V")
	)
	(via
		(at 57.1261 84.1162)
		(size 0.4064)
		(drill 0.2032)
		(layers "F.Cu" "B.Cu")
		(tenting
			(front yes)
			(back yes)
		)
		(net "+3.3V")
	)
	(via
		(at 85.3761 140.3662)
		(size 0.4064)
		(drill 0.2032)
		(layers "F.Cu" "B.Cu")
		(tenting
			(front yes)
			(back yes)
		)
		(net "+3.3V")
	)
	(via
		(at 192.51136 144.17763)
		(size 0.4064)
		(drill 0.2032)
		(layers "F.Cu" "B.Cu")
		(tenting
			(front yes)
			(back yes)
		)
		(net "+3.3V")
	)
	(via
		(at 210.3261 132.1162)
		(size 0.4064)
		(drill 0.2032)
		(layers "F.Cu" "B.Cu")
		(tenting
			(front yes)
			(back yes)
		)
		(net "+3.3V")
	)
	(via
		(at 82.3761 127.6162)
		(size 0.4064)
		(drill 0.2032)
		(layers "F.Cu" "B.Cu")
		(tenting
			(front yes)
			(back yes)
		)
		(net "+3.3V")
	)
	(via
		(at 202.1261 106.7162)
		(size 0.4064)
		(drill 0.2032)
		(layers "F.Cu" "B.Cu")
		(net "+3.3V")
	)
	(via
		(at 221.4261 78.8162)
		(size 0.4064)
		(drill 0.2032)
		(layers "F.Cu" "B.Cu")
		(net "+3.3V")
	)
	(via
		(at 79.1261 138.8662)
		(size 0.4064)
		(drill 0.2032)
		(layers "F.Cu" "B.Cu")
		(tenting
			(front yes)
			(back yes)
		)
		(net "+3.3V")
	)
	(via
		(at 193.3761 81.5866)
		(size 0.4064)
		(drill 0.2032)
		(layers "F.Cu" "B.Cu")
		(tenting
			(front yes)
			(back yes)
		)
		(net "+3.3V")
	)
	(via
		(at 57.1261 102.8662)
		(size 0.4064)
		(drill 0.2032)
		(layers "F.Cu" "B.Cu")
		(tenting
			(front yes)
			(back yes)
		)
		(net "+3.3V")
	)
	(via
		(at 228.6261 125.0162)
		(size 0.4064)
		(drill 0.2032)
		(layers "F.Cu" "B.Cu")
		(net "+3.3V")
	)
	(via
		(at 228.2261 127.2162)
		(size 0.4064)
		(drill 0.2032)
		(layers "F.Cu" "B.Cu")
		(net "+3.3V")
	)
	(via
		(at 71.6261 50.0786)
		(size 0.4064)
		(drill 0.2032)
		(layers "F.Cu" "B.Cu")
		(tenting
			(front yes)
			(back yes)
		)
		(net "+3.3V")
	)
	(via
		(at 192.41136 140.37763)
		(size 0.4064)
		(drill 0.2032)
		(layers "F.Cu" "B.Cu")
		(tenting
			(front yes)
			(back yes)
		)
		(net "+3.3V")
	)
	(via
		(at 198.73112 85.0161)
		(size 0.4064)
		(drill 0.2032)
		(layers "F.Cu" "B.Cu")
		(tenting
			(front yes)
			(back yes)
		)
		(net "+3.3V")
	)
	(via
		(at 69.8761 127.1162)
		(size 0.4064)
		(drill 0.2032)
		(layers "F.Cu" "B.Cu")
		(tenting
			(front yes)
			(back yes)
		)
		(net "+3.3V")
	)
	(via
		(at 230.0261 126.1162)
		(size 0.4064)
		(drill 0.2032)
		(layers "F.Cu" "B.Cu")
		(net "+3.3V")
	)
	(via
		(at 238.3261 96.9162)
		(size 0.4064)
		(drill 0.2032)
		(layers "F.Cu" "B.Cu")
		(net "+3.3V")
	)
	(via
		(at 156.3261 77.1162)
		(size 0.4064)
		(drill 0.2032)
		(layers "F.Cu" "B.Cu")
		(tenting
			(front yes)
			(back yes)
		)
		(net "+3.3V")
	)
	(via
		(at 85.1261 112.8662)
		(size 0.4064)
		(drill 0.2032)
		(layers "F.Cu" "B.Cu")
		(tenting
			(front yes)
			(back yes)
		)
		(net "+3.3V")
	)
	(via
		(at 238.2261 96.1162)
		(size 0.4064)
		(drill 0.2032)
		(layers "F.Cu" "B.Cu")
		(net "+3.3V")
	)
	(via
		(at 156.3261 75.3162)
		(size 0.4064)
		(drill 0.2032)
		(layers "F.Cu" "B.Cu")
		(tenting
			(front yes)
			(back yes)
		)
		(net "+3.3V")
	)
	(via
		(at 127.56334 83.554)
		(size 0.4064)
		(drill 0.2032)
		(layers "F.Cu" "B.Cu")
		(net "+3.3V")
	)
	(via
		(at 232.02738 135.52811)
		(size 0.4064)
		(drill 0.2032)
		(layers "F.Cu" "B.Cu")
		(net "+3.3V")
	)
	(via
		(at 191.32077 82.21095)
		(size 0.4064)
		(drill 0.2032)
		(layers "F.Cu" "B.Cu")
		(net "+3.3V")
	)
	(via
		(at 212.7261 132.0162)
		(size 0.4064)
		(drill 0.2032)
		(layers "F.Cu" "B.Cu")
		(tenting
			(front yes)
			(back yes)
		)
		(net "+3.3V")
	)
	(via
		(at 156.3261 76.2162)
		(size 0.4064)
		(drill 0.2032)
		(layers "F.Cu" "B.Cu")
		(tenting
			(front yes)
			(back yes)
		)
		(net "+3.3V")
	)
	(via
		(at 121.24733 81.74808)
		(size 0.4064)
		(drill 0.2032)
		(layers "F.Cu" "B.Cu")
		(net "+3.3V")
	)
	(via
		(at 159.0261 89.5162)
		(size 0.4064)
		(drill 0.2032)
		(layers "F.Cu" "B.Cu")
		(tenting
			(front yes)
			(back yes)
		)
		(net "+3.3V")
	)
	(via
		(at 96.6261 73.5786)
		(size 0.4064)
		(drill 0.2032)
		(layers "F.Cu" "B.Cu")
		(tenting
			(front yes)
			(back yes)
		)
		(net "+3.3V")
	)
	(via
		(at 131.6261 82.0786)
		(size 0.4064)
		(drill 0.2032)
		(layers "F.Cu" "B.Cu")
		(tenting
			(front yes)
			(back yes)
		)
		(net "+3.3V")
	)
	(via
		(at 82.1261 141.3662)
		(size 0.4064)
		(drill 0.2032)
		(layers "F.Cu" "B.Cu")
		(tenting
			(front yes)
			(back yes)
		)
		(net "+3.3V")
	)
	(via
		(at 185.93101 81.99946)
		(size 0.4064)
		(drill 0.2032)
		(layers "F.Cu" "B.Cu")
		(net "+3.3V")
	)
	(via
		(at 81.1261 86.1162)
		(size 0.4064)
		(drill 0.2032)
		(layers "F.Cu" "B.Cu")
		(tenting
			(front yes)
			(back yes)
		)
		(net "+3.3V")
	)
	(via
		(at 183.1261 84.0162)
		(size 0.4064)
		(drill 0.2032)
		(layers "F.Cu" "B.Cu")
		(net "+3.3V")
	)
	(via
		(at 236.8261 134.0162)
		(size 0.4064)
		(drill 0.2032)
		(layers "F.Cu" "B.Cu")
		(net "+3.3V")
	)
	(via
		(at 57.1261 143.1162)
		(size 0.4064)
		(drill 0.2032)
		(layers "F.Cu" "B.Cu")
		(tenting
			(front yes)
			(back yes)
		)
		(net "+3.3V")
	)
	(via
		(at 182.4261 89.0162)
		(size 0.4064)
		(drill 0.2032)
		(layers "F.Cu" "B.Cu")
		(net "+3.3V")
	)
	(via
		(at 79.3761 100.6162)
		(size 0.4064)
		(drill 0.2032)
		(layers "F.Cu" "B.Cu")
		(tenting
			(front yes)
			(back yes)
		)
		(net "+3.3V")
	)
	(via
		(at 167.24068 89.80228)
		(size 0.4064)
		(drill 0.2032)
		(layers "F.Cu" "B.Cu")
		(net "+3.3V")
	)
	(via
		(at 69.8761 50.1162)
		(size 0.4064)
		(drill 0.2032)
		(layers "F.Cu" "B.Cu")
		(tenting
			(front yes)
			(back yes)
		)
		(net "+3.3V")
	)
	(via
		(at 219.2261 66.5162)
		(size 0.4064)
		(drill 0.2032)
		(layers "F.Cu" "B.Cu")
		(tenting
			(front yes)
			(back yes)
		)
		(net "+3.3V")
	)
	(via
		(at 219.3761 57.3662)
		(size 0.4064)
		(drill 0.2032)
		(layers "F.Cu" "B.Cu")
		(tenting
			(front yes)
			(back yes)
		)
		(net "+3.3V")
	)
	(via
		(at 73.3761 50.1162)
		(size 0.4064)
		(drill 0.2032)
		(layers "F.Cu" "B.Cu")
		(tenting
			(front yes)
			(back yes)
		)
		(net "+3.3V")
	)
	(via
		(at 201.6261 123.9162)
		(size 0.4064)
		(drill 0.2032)
		(layers "F.Cu" "B.Cu")
		(net "+3.3V")
	)
	(via
		(at 70.8761 98.3662)
		(size 0.4064)
		(drill 0.2032)
		(layers "F.Cu" "B.Cu")
		(tenting
			(front yes)
			(back yes)
		)
		(net "+3.3V")
	)
	(via
		(at 229.0261 135.0162)
		(size 0.4064)
		(drill 0.2032)
		(layers "F.Cu" "B.Cu")
		(tenting
			(front yes)
			(back yes)
		)
		(net "+3.3V")
	)
	(via
		(at 57.1261 129.8662)
		(size 0.4064)
		(drill 0.2032)
		(layers "F.Cu" "B.Cu")
		(tenting
			(front yes)
			(back yes)
		)
		(net "+3.3V")
	)
	(via
		(at 229.3261 127.2162)
		(size 0.4064)
		(drill 0.2032)
		(layers "F.Cu" "B.Cu")
		(net "+3.3V")
	)
	(via
		(at 174.0261 89.8162)
		(size 0.4064)
		(drill 0.2032)
		(layers "F.Cu" "B.Cu")
		(net "+3.3V")
	)
	(via
		(at 192.2261 84.9162)
		(size 0.4064)
		(drill 0.2032)
		(layers "F.Cu" "B.Cu")
		(net "+3.3V")
	)
	(via
		(at 238.3261 97.8162)
		(size 0.4064)
		(drill 0.2032)
		(layers "F.Cu" "B.Cu")
		(net "+3.3V")
	)
	(via
		(at 228.9261 110.6162)
		(size 0.4064)
		(drill 0.2032)
		(layers "F.Cu" "B.Cu")
		(net "+3.3V")
	)
	(via
		(at 83.1261 115.5786)
		(size 0.4064)
		(drill 0.2032)
		(layers "F.Cu" "B.Cu")
		(tenting
			(front yes)
			(back yes)
		)
		(net "+3.3V")
	)
	(via
		(at 200.26076 90.87068)
		(size 0.4064)
		(drill 0.2032)
		(layers "F.Cu" "B.Cu")
		(net "+3.3V")
	)
	(via
		(at 165.41661 83.64891)
		(size 0.4064)
		(drill 0.2032)
		(layers "F.Cu" "B.Cu")
		(net "+3.3V")
	)
	(via
		(at 57.1261 73.1162)
		(size 0.4064)
		(drill 0.2032)
		(layers "F.Cu" "B.Cu")
		(tenting
			(front yes)
			(back yes)
		)
		(net "+3.3V")
	)
	(via
		(at 227.3261 127.2162)
		(size 0.4064)
		(drill 0.2032)
		(layers "F.Cu" "B.Cu")
		(net "+3.3V")
	)
	(via
		(at 191.6261 86.5162)
		(size 0.4064)
		(drill 0.2032)
		(layers "F.Cu" "B.Cu")
		(net "+3.3V")
	)
	(via
		(at 189.6261 88.7162)
		(size 0.4064)
		(drill 0.2032)
		(layers "F.Cu" "B.Cu")
		(net "+3.3V")
	)
	(segment
		(start 201.2261 96.9162)
		(end 201.2261 91.83602)
		(width 0.508)
		(layer "B.Cu")
		(net "+3.3V")
	)
	(segment
		(start 199.9261 106.4162)
		(end 199.9261 98.2162)
		(width 0.508)
		(layer "B.Cu")
		(net "+3.3V")
	)
	(segment
		(start 200.26076 90.87068)
		(end 201.2261 91.83602)
		(width 0.508)
		(layer "B.Cu")
		(net "+3.3V")
	)
	(segment
		(start 201.5261 107.3162)
		(end 202.1261 106.7162)
		(width 0.508)
		(layer "B.Cu")
		(net "+3.3V")
	)
	(segment
		(start 199.9261 106.4162)
		(end 200.8261 107.3162)
		(width 0.508)
		(layer "B.Cu")
		(net "+3.3V")
	)
	(segment
		(start 199.9261 98.2162)
		(end 201.2261 96.9162)
		(width 0.508)
		(layer "B.Cu")
		(net "+3.3V")
	)
	(segment
		(start 200.8261 107.3162)
		(end 201.5261 107.3162)
		(width 0.508)
		(layer "B.Cu")
		(net "+3.3V")
	)
	(segment
		(start 201.6261 108.1162)
		(end 201.6261 107.2162)
		(width 0.508)
		(layer "In2.Cu")
		(net "+3.3V")
	)
	(segment
		(start 201.6261 108.1162)
		(end 203.3261 109.8162)
		(width 0.508)
		(layer "In2.Cu")
		(net "+3.3V")
	)
	(segment
		(start 228.9261 110.6162)
		(end 230.4261 112.1162)
		(width 0.508)
		(layer "In2.Cu")
		(net "+3.3V")
	)
	(segment
		(start 167.24068 89.80228)
		(end 168.22675 88.8162)
		(width 0.2032)
		(layer "In2.Cu")
		(net "+3.3V")
	)
	(segment
		(start 224.2261 135.0162)
		(end 225.3261 133.9162)
		(width 0.508)
		(layer "In2.Cu")
		(net "+3.3V")
	)
	(segment
		(start 201.6261 107.2162)
		(end 202.1261 106.7162)
		(width 0.508)
		(layer "In2.Cu")
		(net "+3.3V")
	)
	(segment
		(start 83.1261 99.6162)
		(end 85.1261 99.6162)
		(width 0.254)
		(layer "In2.Cu")
		(net "+3.3V")
	)
	(segment
		(start 165.54933 83.5162)
		(end 175.5261 83.5162)
		(width 0.2032)
		(layer "In2.Cu")
		(net "+3.3V")
	)
	(segment
		(start 192.41136 141.10146)
		(end 193.5261 142.2162)
		(width 0.508)
		(layer "In2.Cu")
		(net "+3.3V")
	)
	(segment
		(start 173.0261 88.8162)
		(end 174.0261 89.8162)
		(width 0.2032)
		(layer "In2.Cu")
		(net "+3.3V")
	)
	(segment
		(start 192.41136 141.10146)
		(end 192.41136 140.37763)
		(width 0.508)
		(layer "In2.Cu")
		(net "+3.3V")
	)
	(segment
		(start 192.51136 144.17763)
		(end 193.5261 143.16289)
		(width 0.508)
		(layer "In2.Cu")
		(net "+3.3V")
	)
	(segment
		(start 231.53929 136.0162)
		(end 232.02738 135.52811)
		(width 0.508)
		(layer "In2.Cu")
		(net "+3.3V")
	)
	(segment
		(start 233.53929 134.0162)
		(end 236.8261 134.0162)
		(width 0.508)
		(layer "In2.Cu")
		(net "+3.3V")
	)
	(segment
		(start 203.3261 122.2162)
		(end 203.3261 109.8162)
		(width 0.508)
		(layer "In2.Cu")
		(net "+3.3V")
	)
	(segment
		(start 165.41661 83.64891)
		(end 165.54933 83.5162)
		(width 0.2032)
		(layer "In2.Cu")
		(net "+3.3V")
	)
	(segment
		(start 193.5261 143.16289)
		(end 193.5261 142.2162)
		(width 0.508)
		(layer "In2.Cu")
		(net "+3.3V")
	)
	(segment
		(start 168.22675 88.8162)
		(end 173.0261 88.8162)
		(width 0.2032)
		(layer "In2.Cu")
		(net "+3.3V")
	)
	(segment
		(start 175.5261 83.5162)
		(end 175.7261 83.3162)
		(width 0.2032)
		(layer "In2.Cu")
		(net "+3.3V")
	)
	(segment
		(start 227.92609 133.9162)
		(end 229.0261 135.0162)
		(width 0.508)
		(layer "In2.Cu")
		(net "+3.3V")
	)
	(segment
		(start 193.8261 138.96289)
		(end 193.8261 131.7162)
		(width 0.508)
		(layer "In2.Cu")
		(net "+3.3V")
	)
	(segment
		(start 82.1261 100.6162)
		(end 83.1261 99.6162)
		(width 0.254)
		(layer "In2.Cu")
		(net "+3.3V")
	)
	(segment
		(start 225.3261 133.9162)
		(end 227.92609 133.9162)
		(width 0.508)
		(layer "In2.Cu")
		(net "+3.3V")
	)
	(segment
		(start 192.41136 140.37763)
		(end 193.8261 138.96289)
		(width 0.508)
		(layer "In2.Cu")
		(net "+3.3V")
	)
	(segment
		(start 193.8261 131.7162)
		(end 201.6261 123.9162)
		(width 0.508)
		(layer "In2.Cu")
		(net "+3.3V")
	)
	(segment
		(start 232.02738 135.52811)
		(end 233.53929 134.0162)
		(width 0.508)
		(layer "In2.Cu")
		(net "+3.3V")
	)
	(segment
		(start 230.4261 124.0162)
		(end 230.4261 112.1162)
		(width 0.508)
		(layer "In2.Cu")
		(net "+3.3V")
	)
	(segment
		(start 229.0261 135.0162)
		(end 230.02609 136.0162)
		(width 0.508)
		(layer "In2.Cu")
		(net "+3.3V")
	)
	(segment
		(start 230.02609 136.0162)
		(end 231.53929 136.0162)
		(width 0.508)
		(layer "In2.Cu")
		(net "+3.3V")
	)
	(segment
		(start 201.6261 123.9162)
		(end 203.3261 122.2162)
		(width 0.508)
		(layer "In2.Cu")
		(net "+3.3V")
	)
	(segment
		(start 57.1261 102.8662)
		(end 80.2261 102.8662)
		(width 0.254)
		(layer "In3.Cu")
		(net "+3.3V")
	)
	(segment
		(start 79.1761 116.3662)
		(end 79.21036 116.33194)
		(width 0.254)
		(layer "In3.Cu")
		(net "+3.3V")
	)
	(segment
		(start 79.4761 98.3662)
		(end 79.5261 98.3162)
		(width 0.254)
		(layer "In3.Cu")
		(net "+3.3V")
	)
	(segment
		(start 69.8761 50.8662)
		(end 69.8761 50.1162)
		(width 0.2032)
		(layer "In3.Cu")
		(net "+3.3V")
	)
	(segment
		(start 75.1261 51.1162)
		(end 75.1261 50.1162)
		(width 0.2032)
		(layer "In3.Cu")
		(net "+3.3V")
	)
	(segment
		(start 70.8761 98.3662)
		(end 79.4761 98.3662)
		(width 0.254)
		(layer "In3.Cu")
		(net "+3.3V")
	)
	(segment
		(start 73.3761 50.8662)
		(end 73.6261 51.1162)
		(width 0.2032)
		(layer "In3.Cu")
		(net "+3.3V")
	)
	(segment
		(start 73.3761 50.8662)
		(end 73.3761 50.1162)
		(width 0.2032)
		(layer "In3.Cu")
		(net "+3.3V")
	)
	(segment
		(start 183.8511 89.0536)
		(end 184.3261 88.5786)
		(width 0.2032)
		(layer "In3.Cu")
		(net "+3.3V")
	)
	(segment
		(start 193.3681 81.5866)
		(end 193.3761 81.5866)
		(width 0.2032)
		(layer "In3.Cu")
		(net "+3.3V")
	)
	(segment
		(start 71.1261 73.1162)
		(end 71.6261 72.6162)
		(width 0.254)
		(layer "In3.Cu")
		(net "+3.3V")
	)
	(segment
		(start 71.6261 51.1162)
		(end 71.6261 50.0786)
		(width 0.2032)
		(layer "In3.Cu")
		(net "+3.3V")
	)
	(segment
		(start 191.6261 86.5162)
		(end 191.6261 83.3286)
		(width 0.2032)
		(layer "In3.Cu")
		(net "+3.3V")
	)
	(segment
		(start 57.1261 84.1162)
		(end 71.1261 84.1162)
		(width 0.254)
		(layer "In3.Cu")
		(net "+3.3V")
	)
	(segment
		(start 57.1261 116.3662)
		(end 79.1761 116.3662)
		(width 0.254)
		(layer "In3.Cu")
		(net "+3.3V")
	)
	(segment
		(start 57.1261 129.8662)
		(end 79.90753 129.8662)
		(width 0.254)
		(layer "In3.Cu")
		(net "+3.3V")
	)
	(segment
		(start 57.1261 143.1162)
		(end 80.2261 143.1162)
		(width 0.254)
		(layer "In3.Cu")
		(net "+3.3V")
	)
	(segment
		(start 191.6261 83.3286)
		(end 193.3681 81.5866)
		(width 0.2032)
		(layer "In3.Cu")
		(net "+3.3V")
	)
	(segment
		(start 71.1261 84.1162)
		(end 71.6261 84.6162)
		(width 0.254)
		(layer "In3.Cu")
		(net "+3.3V")
	)
	(segment
		(start 69.8761 127.1162)
		(end 79.3261 127.1162)
		(width 0.254)
		(layer "In3.Cu")
		(net "+3.3V")
	)
	(segment
		(start 57.1261 73.1162)
		(end 71.1261 73.1162)
		(width 0.254)
		(layer "In3.Cu")
		(net "+3.3V")
	)
	(segment
		(start 79.3261 127.1162)
		(end 79.6261 126.8162)
		(width 0.254)
		(layer "In3.Cu")
		(net "+3.3V")
	)
	(segment
		(start 153.5261 108.5162)
		(end 156.9261 111.9162)
		(width 0.2032)
		(layer "F.Cu")
		(net "FPGA_TDO")
	)
	(segment
		(start 182.3261 129.4162)
		(end 182.9261 129.4162)
		(width 0.2032)
		(layer "F.Cu")
		(net "FPGA_TDO")
	)
	(segment
		(start 198.3261 144.8162)
		(end 198.3261 143.49237)
		(width 0.2032)
		(layer "F.Cu")
		(net "FPGA_TDO")
	)
	(segment
		(start 190.85479 144.83735)
		(end 191.83364 145.8162)
		(width 0.2032)
		(layer "F.Cu")
		(net "FPGA_TDO")
	)
	(segment
		(start 151.13797 104.80882)
		(end 153.2392 104.80882)
		(width 0.2032)
		(layer "F.Cu")
		(net "FPGA_TDO")
	)
	(segment
		(start 156.9261 111.9162)
		(end 164.8261 111.9162)
		(width 0.2032)
		(layer "F.Cu")
		(net "FPGA_TDO")
	)
	(segment
		(start 198.31136 143.47763)
		(end 198.3261 143.49237)
		(width 0.2032)
		(layer "F.Cu")
		(net "FPGA_TDO")
	)
	(segment
		(start 191.83364 145.8162)
		(end 197.3261 145.8162)
		(width 0.2032)
		(layer "F.Cu")
		(net "FPGA_TDO")
	)
	(segment
		(start 182.9261 129.4162)
		(end 190.85479 137.34489)
		(width 0.2032)
		(layer "F.Cu")
		(net "FPGA_TDO")
	)
	(segment
		(start 196.21136 143.47763)
		(end 198.31136 143.47763)
		(width 0.2032)
		(layer "F.Cu")
		(net "FPGA_TDO")
	)
	(segment
		(start 153.2392 104.80882)
		(end 153.53182 104.5162)
		(width 0.2032)
		(layer "F.Cu")
		(net "FPGA_TDO")
	)
	(segment
		(start 197.3261 145.8162)
		(end 198.3261 144.8162)
		(width 0.2032)
		(layer "F.Cu")
		(net "FPGA_TDO")
	)
	(segment
		(start 153.5261 105.5162)
		(end 155.2261 105.5162)
		(width 0.2032)
		(layer "F.Cu")
		(net "FPGA_TDO")
	)
	(segment
		(start 153.53182 104.5162)
		(end 154.2261 104.5162)
		(width 0.2032)
		(layer "F.Cu")
		(net "FPGA_TDO")
	)
	(segment
		(start 155.2261 105.5162)
		(end 156.2261 106.5162)
		(width 0.2032)
		(layer "F.Cu")
		(net "FPGA_TDO")
	)
	(segment
		(start 164.8261 111.9162)
		(end 182.3261 129.4162)
		(width 0.2032)
		(layer "F.Cu")
		(net "FPGA_TDO")
	)
	(segment
		(start 190.85479 144.83735)
		(end 190.85479 137.34489)
		(width 0.2032)
		(layer "F.Cu")
		(net "FPGA_TDO")
	)
	(segment
		(start 153.5261 108.5162)
		(end 153.5261 105.5162)
		(width 0.2032)
		(layer "F.Cu")
		(net "FPGA_TDO")
	)
	(via
		(at 156.2261 106.5162)
		(size 0.4064)
		(drill 0.2032)
		(layers "F.Cu" "B.Cu")
		(tenting
			(front yes)
			(back yes)
		)
		(net "FPGA_TDO")
	)
	(via
		(at 154.2261 104.5162)
		(size 0.4064)
		(drill 0.2032)
		(layers "F.Cu" "B.Cu")
		(tenting
			(front yes)
			(back yes)
		)
		(net "FPGA_TDO")
	)
	(segment
		(start 154.2261 104.5162)
		(end 156.2261 106.5162)
		(width 0.2032)
		(layer "In2.Cu")
		(net "FPGA_TDO")
	)
	(segment
		(start 166.2261 110.9162)
		(end 192.0261 136.7162)
		(width 0.2032)
		(layer "F.Cu")
		(net "FPGA_TCK")
	)
	(segment
		(start 197.32386 139.37763)
		(end 198.41136 139.37763)
		(width 0.2032)
		(layer "F.Cu")
		(net "FPGA_TCK")
	)
	(segment
		(start 154.2261 108.1162)
		(end 157.0261 110.9162)
		(width 0.2032)
		(layer "F.Cu")
		(net "FPGA_TCK")
	)
	(segment
		(start 154.2261 108.1162)
		(end 154.2261 106.2162)
		(width 0.2032)
		(layer "F.Cu")
		(net "FPGA_TCK")
	)
	(segment
		(start 153.22985 105.31244)
		(end 153.4261 105.1162)
		(width 0.2032)
		(layer "F.Cu")
		(net "FPGA_TCK")
	)
	(segment
		(start 192.0261 136.7162)
		(end 196.6261 136.7162)
		(width 0.2032)
		(layer "F.Cu")
		(net "FPGA_TCK")
	)
	(segment
		(start 153.4261 105.1162)
		(end 155.8261 105.1162)
		(width 0.2032)
		(layer "F.Cu")
		(net "FPGA_TCK")
	)
	(segment
		(start 155.8261 105.1162)
		(end 157.1261 106.4162)
		(width 0.2032)
		(layer "F.Cu")
		(net "FPGA_TCK")
	)
	(segment
		(start 154.2261 106.2162)
		(end 155.2261 106.2162)
		(width 0.2032)
		(layer "F.Cu")
		(net "FPGA_TCK")
	)
	(segment
		(start 198.41136 139.37763)
		(end 198.41136 138.50146)
		(width 0.2032)
		(layer "F.Cu")
		(net "FPGA_TCK")
	)
	(segment
		(start 157.1261 107.5162)
		(end 157.1261 106.4162)
		(width 0.2032)
		(layer "F.Cu")
		(net "FPGA_TCK")
	)
	(segment
		(start 196.23636 139.37763)
		(end 197.32386 139.37763)
		(width 0.2032)
		(layer "F.Cu")
		(net "FPGA_TCK")
	)
	(segment
		(start 196.6261 136.7162)
		(end 198.41136 138.50146)
		(width 0.2032)
		(layer "F.Cu")
		(net "FPGA_TCK")
	)
	(segment
		(start 154.2261 106.2162)
		(end 154.2261 106.2162)
		(width 0.2032)
		(layer "F.Cu")
		(net "FPGA_TCK")
	)
	(segment
		(start 157.0261 110.9162)
		(end 166.2261 110.9162)
		(width 0.2032)
		(layer "F.Cu")
		(net "FPGA_TCK")
	)
	(segment
		(start 156.5261 107.5162)
		(end 157.1261 107.5162)
		(width 0.2032)
		(layer "F.Cu")
		(net "FPGA_TCK")
	)
	(segment
		(start 155.2261 106.2162)
		(end 156.5261 107.5162)
		(width 0.2032)
		(layer "F.Cu")
		(net "FPGA_TCK")
	)
	(segment
		(start 151.74069 105.31244)
		(end 153.22985 105.31244)
		(width 0.2032)
		(layer "F.Cu")
		(net "FPGA_TCK")
	)
	(segment
		(start 202.6261 107.9162)
		(end 203.5511 108.8412)
		(width 0.254)
		(layer "F.Cu")
		(net "+12V")
	)
	(segment
		(start 203.7611 89.9162)
		(end 203.7611 88.8812)
		(width 0.2032)
		(layer "F.Cu")
		(net "+12V")
	)
	(segment
		(start 202.6261 107.9162)
		(end 203.1261 107.4162)
		(width 0.2032)
		(layer "F.Cu")
		(net "+12V")
	)
	(segment
		(start 206.0261 91.6162)
		(end 206.0261 89.2162)
		(width 0.2032)
		(layer "F.Cu")
		(net "+12V")
	)
	(segment
		(start 204.1261 88.5162)
		(end 205.3261 88.5162)
		(width 0.2032)
		(layer "F.Cu")
		(net "+12V")
	)
	(segment
		(start 208.3011 92.0162)
		(end 209.6261 90.6912)
		(width 0.2032)
		(layer "F.Cu")
		(net "+12V")
	)
	(segment
		(start 206.0261 91.6162)
		(end 206.4261 92.0162)
		(width 0.2032)
		(layer "F.Cu")
		(net "+12V")
	)
	(segment
		(start 201.53299 128.12512)
		(end 202.14191 127.5162)
		(width 0.254)
		(layer "F.Cu")
		(net "+12V")
	)
	(segment
		(start 201.6261 125.0162)
		(end 201.7261 124.9162)
		(width 0.2032)
		(layer "F.Cu")
		(net "+12V")
	)
	(segment
		(start 207.4261 88.5162)
		(end 207.6261 88.7162)
		(width 0.2032)
		(layer "F.Cu")
		(net "+12V")
	)
	(segment
		(start 205.3261 88.5162)
		(end 206.0261 89.2162)
		(width 0.2032)
		(layer "F.Cu")
		(net "+12V")
	)
	(segment
		(start 201.7261 124.9162)
		(end 202.5261 124.9162)
		(width 0.2032)
		(layer "F.Cu")
		(net "+12V")
	)
	(segment
		(start 203.1261 107.4162)
		(end 204.9261 107.4162)
		(width 0.2032)
		(layer "F.Cu")
		(net "+12V")
	)
	(segment
		(start 204.9261 107.4162)
		(end 205.7261 108.2162)
		(width 0.2032)
		(layer "F.Cu")
		(net "+12V")
	)
	(segment
		(start 202.14191 127.5162)
		(end 202.3761 127.5162)
		(width 0.254)
		(layer "F.Cu")
		(net "+12V")
	)
	(segment
		(start 206.4261 92.0162)
		(end 208.3011 92.0162)
		(width 0.2032)
		(layer "F.Cu")
		(net "+12V")
	)
	(segment
		(start 203.5511 108.8412)
		(end 204.0261 108.8412)
		(width 0.254)
		(layer "F.Cu")
		(net "+12V")
	)
	(segment
		(start 203.7611 88.8812)
		(end 204.1261 88.5162)
		(width 0.2032)
		(layer "F.Cu")
		(net "+12V")
	)
	(via
		(at 210.5261 88.1162)
		(size 0.4064)
		(drill 0.2032)
		(layers "F.Cu" "B.Cu")
		(net "+12V")
	)
	(via
		(at 209.5261 88.1162)
		(size 0.4064)
		(drill 0.2032)
		(layers "F.Cu" "B.Cu")
		(net "+12V")
	)
	(via
		(at 212.5261 122.0162)
		(size 0.4064)
		(drill 0.2032)
		(layers "F.Cu" "B.Cu")
		(net "+12V")
	)
	(via
		(at 209.0261 89.0162)
		(size 0.4064)
		(drill 0.2032)
		(layers "F.Cu" "B.Cu")
		(net "+12V")
	)
	(via
		(at 208.1261 74.0162)
		(size 0.4064)
		(drill 0.2032)
		(layers "F.Cu" "B.Cu")
		(tenting
			(front yes)
			(back yes)
		)
		(net "+12V")
	)
	(via
		(at 208.0261 90.1162)
		(size 0.4064)
		(drill 0.2032)
		(layers "F.Cu" "B.Cu")
		(net "+12V")
	)
	(via
		(at 210.4261 89.0162)
		(size 0.4064)
		(drill 0.2032)
		(layers "F.Cu" "B.Cu")
		(net "+12V")
	)
	(via
		(at 160.5261 82.4162)
		(size 0.4064)
		(drill 0.2032)
		(layers "F.Cu" "B.Cu")
		(tenting
			(front yes)
			(back yes)
		)
		(net "+12V")
	)
	(via
		(at 209.9261 120.5162)
		(size 0.4064)
		(drill 0.2032)
		(layers "F.Cu" "B.Cu")
		(net "+12V")
	)
	(via
		(at 158.9261 82.3662)
		(size 0.4064)
		(drill 0.2032)
		(layers "F.Cu" "B.Cu")
		(tenting
			(front yes)
			(back yes)
		)
		(net "+12V")
	)
	(via
		(at 201.53299 128.12512)
		(size 0.4064)
		(drill 0.2032)
		(layers "F.Cu" "B.Cu")
		(net "+12V")
	)
	(via
		(at 208.9261 74.0162)
		(size 0.4064)
		(drill 0.2032)
		(layers "F.Cu" "B.Cu")
		(tenting
			(front yes)
			(back yes)
		)
		(net "+12V")
	)
	(via
		(at 202.6261 107.9162)
		(size 0.4064)
		(drill 0.2032)
		(layers "F.Cu" "B.Cu")
		(net "+12V")
	)
	(via
		(at 211.8261 119.6162)
		(size 0.4064)
		(drill 0.2032)
		(layers "F.Cu" "B.Cu")
		(net "+12V")
	)
	(via
		(at 159.73211 82.37564)
		(size 0.4064)
		(drill 0.2032)
		(layers "F.Cu" "B.Cu")
		(tenting
			(front yes)
			(back yes)
		)
		(net "+12V")
	)
	(via
		(at 210.8261 120.5162)
		(size 0.4064)
		(drill 0.2032)
		(layers "F.Cu" "B.Cu")
		(net "+12V")
	)
	(via
		(at 211.7261 118.5162)
		(size 0.4064)
		(drill 0.2032)
		(layers "F.Cu" "B.Cu")
		(net "+12V")
	)
	(via
		(at 213.5261 105.6162)
		(size 0.4064)
		(drill 0.2032)
		(layers "F.Cu" "B.Cu")
		(net "+12V")
	)
	(via
		(at 208.1261 73.5162)
		(size 0.4064)
		(drill 0.2032)
		(layers "F.Cu" "B.Cu")
		(tenting
			(front yes)
			(back yes)
		)
		(net "+12V")
	)
	(via
		(at 208.9261 73.5162)
		(size 0.4064)
		(drill 0.2032)
		(layers "F.Cu" "B.Cu")
		(tenting
			(front yes)
			(back yes)
		)
		(net "+12V")
	)
	(via
		(at 208.9261 73.0162)
		(size 0.4064)
		(drill 0.2032)
		(layers "F.Cu" "B.Cu")
		(tenting
			(front yes)
			(back yes)
		)
		(net "+12V")
	)
	(via
		(at 214.3261 105.6162)
		(size 0.4064)
		(drill 0.2032)
		(layers "F.Cu" "B.Cu")
		(net "+12V")
	)
	(via
		(at 213.1261 122.8162)
		(size 0.4064)
		(drill 0.2032)
		(layers "F.Cu" "B.Cu")
		(net "+12V")
	)
	(via
		(at 212.9261 105.6162)
		(size 0.4064)
		(drill 0.2032)
		(layers "F.Cu" "B.Cu")
		(net "+12V")
	)
	(via
		(at 211.8261 120.5162)
		(size 0.4064)
		(drill 0.2032)
		(layers "F.Cu" "B.Cu")
		(net "+12V")
	)
	(via
		(at 215.1261 105.6162)
		(size 0.4064)
		(drill 0.2032)
		(layers "F.Cu" "B.Cu")
		(net "+12V")
	)
	(via
		(at 208.1261 73.0162)
		(size 0.4064)
		(drill 0.2032)
		(layers "F.Cu" "B.Cu")
		(tenting
			(front yes)
			(back yes)
		)
		(net "+12V")
	)
	(via
		(at 212.2261 105.6162)
		(size 0.4064)
		(drill 0.2032)
		(layers "F.Cu" "B.Cu")
		(net "+12V")
	)
	(via
		(at 208.4261 88.1162)
		(size 0.4064)
		(drill 0.2032)
		(layers "F.Cu" "B.Cu")
		(net "+12V")
	)
	(via
		(at 208.1261 89.0162)
		(size 0.4064)
		(drill 0.2032)
		(layers "F.Cu" "B.Cu")
		(net "+12V")
	)
	(via
		(at 201.6261 125.0162)
		(size 0.4064)
		(drill 0.2032)
		(layers "F.Cu" "B.Cu")
		(net "+12V")
	)
	(segment
		(start 212.2261 122.3162)
		(end 212.5261 122.0162)
		(width 0.2032)
		(layer "In2.Cu")
		(net "+12V")
	)
	(segment
		(start 201.6261 125.0162)
		(end 204.3261 122.3162)
		(width 0.2032)
		(layer "In2.Cu")
		(net "+12V")
	)
	(segment
		(start 204.3261 122.3162)
		(end 212.2261 122.3162)
		(width 0.2032)
		(layer "In2.Cu")
		(net "+12V")
	)
	(segment
		(start 209.5261 122.7162)
		(end 209.5261 122.5162)
		(width 0.2032)
		(layer "In3.Cu")
		(net "+12V")
	)
	(segment
		(start 208.2261 125.4162)
		(end 210.3261 123.3162)
		(width 0.254)
		(layer "In3.Cu")
		(net "+12V")
	)
	(segment
		(start 201.53299 128.12512)
		(end 202.61718 128.12512)
		(width 0.254)
		(layer "In3.Cu")
		(net "+12V")
	)
	(segment
		(start 209.5261 122.5162)
		(end 209.6261 122.4162)
		(width 0.2032)
		(layer "In3.Cu")
		(net "+12V")
	)
	(segment
		(start 201.6261 125.0162)
		(end 207.2261 125.0162)
		(width 0.2032)
		(layer "In3.Cu")
		(net "+12V")
	)
	(segment
		(start 210.3261 123.3162)
		(end 210.3261 122.8162)
		(width 0.254)
		(layer "In3.Cu")
		(net "+12V")
	)
	(segment
		(start 202.61718 128.12512)
		(end 205.3261 125.4162)
		(width 0.254)
		(layer "In3.Cu")
		(net "+12V")
	)
	(segment
		(start 203.7261 109.0162)
		(end 213.2261 109.0162)
		(width 0.2032)
		(layer "In3.Cu")
		(net "+12V")
	)
	(segment
		(start 207.2261 125.0162)
		(end 209.5261 122.7162)
		(width 0.2032)
		(layer "In3.Cu")
		(net "+12V")
	)
	(segment
		(start 205.3261 125.4162)
		(end 208.2261 125.4162)
		(width 0.254)
		(layer "In3.Cu")
		(net "+12V")
	)
	(segment
		(start 202.6261 107.9162)
		(end 203.7261 109.0162)
		(width 0.2032)
		(layer "In3.Cu")
		(net "+12V")
	)
	(segment
		(start 151.74863 118.81069)
		(end 151.75053 118.80879)
		(width 0.2032)
		(layer "F.Cu")
		(net "KEY1")
	)
	(segment
		(start 227.3261 111.0162)
		(end 228.3261 110.0162)
		(width 0.254)
		(layer "F.Cu")
		(net "+5.0V")
	)
	(segment
		(start 201.36847 105.82096)
		(end 201.3761 105.8286)
		(width 0.2032)
		(layer "F.Cu")
		(net "+5.0V")
	)
	(segment
		(start 192.6261 106.3286)
		(end 192.63367 106.32103)
		(width 0.2032)
		(layer "F.Cu")
		(net "+5.0V")
	)
	(segment
		(start 228.0711 66.67861)
		(end 229.68851 66.67861)
		(width 0.635)
		(layer "F.Cu")
		(net "+5.0V")
	)
	(segment
		(start 195.30599 105.82096)
		(end 195.31363 105.81333)
		(width 0.2032)
		(layer "F.Cu")
		(net "+5.0V")
	)
	(segment
		(start 199.3634 104.81333)
		(end 199.37104 104.82097)
		(width 0.2032)
		(layer "F.Cu")
		(net "+5.0V")
	)
	(segment
		(start 230.5885 58.6786)
		(end 230.8261 58.9162)
		(width 0.635)
		(layer "F.Cu")
		(net "+5.0V")
	)
	(segment
		(start 229.68851 66.67861)
		(end 230.6261 67.6162)
		(width 0.635)
		(layer "F.Cu")
		(net "+5.0V")
	)
	(segment
		(start 199.3634 106.31346)
		(end 199.37097 106.32103)
		(width 0.2032)
		(layer "F.Cu")
		(net "+5.0V")
	)
	(segment
		(start 232.0261 137.9162)
		(end 232.5761 137.9162)
		(width 0.254)
		(layer "F.Cu")
		(net "+5.0V")
	)
	(segment
		(start 232.2261 61.1162)
		(end 232.3261 61.0162)
		(width 0.635)
		(layer "F.Cu")
		(net "+5.0V")
	)
	(segment
		(start 225.8261 114.0162)
		(end 226.2261 114.4162)
		(width 0.254)
		(layer "F.Cu")
		(net "+5.0V")
	)
	(segment
		(start 228.0711 58.6786)
		(end 230.5885 58.6786)
		(width 0.635)
		(layer "F.Cu")
		(net "+5.0V")
	)
	(segment
		(start 230.8261 58.9162)
		(end 232.0261 58.9162)
		(width 0.635)
		(layer "F.Cu")
		(net "+5.0V")
	)
	(segment
		(start 199.37097 105.32103)
		(end 201.36853 105.32103)
		(width 0.2032)
		(layer "F.Cu")
		(net "+5.0V")
	)
	(segment
		(start 77.1261 66.1162)
		(end 77.3261 65.9162)
		(width 0.635)
		(layer "F.Cu")
		(net "+5.0V")
	)
	(segment
		(start 199.3634 105.31346)
		(end 199.37097 105.32103)
		(width 0.2032)
		(layer "F.Cu")
		(net "+5.0V")
	)
	(segment
		(start 85.7261 78.1786)
		(end 85.8761 78.1786)
		(width 0.508)
		(layer "F.Cu")
		(net "+5.0V")
	)
	(segment
		(start 230.6261 67.6162)
		(end 231.1011 67.6162)
		(width 0.635)
		(layer "F.Cu")
		(net "+5.0V")
	)
	(segment
		(start 77.3261 65.9162)
		(end 79.4261 65.9162)
		(width 0.635)
		(layer "F.Cu")
		(net "+5.0V")
	)
	(segment
		(start 192.6261 104.8286)
		(end 192.63373 104.82097)
		(width 0.2032)
		(layer "F.Cu")
		(net "+5.0V")
	)
	(segment
		(start 85.9761 78.0786)
		(end 87.1261 78.0786)
		(width 0.508)
		(layer "F.Cu")
		(net "+5.0V")
	)
	(segment
		(start 225.8261 114.0162)
		(end 225.8261 111.6162)
		(width 0.254)
		(layer "F.Cu")
		(net "+5.0V")
	)
	(segment
		(start 88.2261 78.5286)
		(end 89.6761 78.5286)
		(width 0.508)
		(layer "F.Cu")
		(net "+5.0V")
	)
	(segment
		(start 199.37104 104.82097)
		(end 201.36847 104.82097)
		(width 0.2032)
		(layer "F.Cu")
		(net "+5.0V")
	)
	(segment
		(start 87.1261 78.0786)
		(end 87.4051 78.3576)
		(width 0.508)
		(layer "F.Cu")
		(net "+5.0V")
	)
	(segment
		(start 226.2261 114.4162)
		(end 228.7261 114.4162)
		(width 0.254)
		(layer "F.Cu")
		(net "+5.0V")
	)
	(segment
		(start 228.7261 114.4162)
		(end 229.3911 113.7512)
		(width 0.254)
		(layer "F.Cu")
		(net "+5.0V")
	)
	(segment
		(start 229.3911 113.7512)
		(end 230.4261 113.7512)
		(width 0.254)
		(layer "F.Cu")
		(net "+5.0V")
	)
	(segment
		(start 232.5761 137.9162)
		(end 233.2761 137.2162)
		(width 0.254)
		(layer "F.Cu")
		(net "+5.0V")
	)
	(segment
		(start 79.4261 65.9162)
		(end 79.51371 65.82859)
		(width 0.635)
		(layer "F.Cu")
		(net "+5.0V")
	)
	(segment
		(start 225.8261 111.6162)
		(end 226.4261 111.0162)
		(width 0.254)
		(layer "F.Cu")
		(net "+5.0V")
	)
	(segment
		(start 228.3261 110.0162)
		(end 228.3261 108.5162)
		(width 0.254)
		(layer "F.Cu")
		(net "+5.0V")
	)
	(segment
		(start 192.6261 105.3286)
		(end 192.63367 105.32103)
		(width 0.2032)
		(layer "F.Cu")
		(net "+5.0V")
	)
	(segment
		(start 81.9311 73.8286)
		(end 83.8761 73.8286)
		(width 0.508)
		(layer "F.Cu")
		(net "+5.0V")
	)
	(segment
		(start 199.3634 105.81333)
		(end 199.37104 105.82096)
		(width 0.2032)
		(layer "F.Cu")
		(net "+5.0V")
	)
	(segment
		(start 88.1261 78.6286)
		(end 88.2261 78.5286)
		(width 0.508)
		(layer "F.Cu")
		(net "+5.0V")
	)
	(segment
		(start 195.30606 106.32103)
		(end 195.31363 106.31346)
		(width 0.2032)
		(layer "F.Cu")
		(net "+5.0V")
	)
	(segment
		(start 87.4051 78.3576)
		(end 87.8551 78.3576)
		(width 0.508)
		(layer "F.Cu")
		(net "+5.0V")
	)
	(segment
		(start 195.30599 104.82097)
		(end 195.31363 104.81333)
		(width 0.2032)
		(layer "F.Cu")
		(net "+5.0V")
	)
	(segment
		(start 201.36853 105.32103)
		(end 201.3761 105.3286)
		(width 0.2032)
		(layer "F.Cu")
		(net "+5.0V")
	)
	(segment
		(start 199.37097 106.32103)
		(end 201.36853 106.32103)
		(width 0.2032)
		(layer "F.Cu")
		(net "+5.0V")
	)
	(segment
		(start 79.4261 65.9162)
		(end 79.4261 65.9162)
		(width 0.635)
		(layer "F.Cu")
		(net "+5.0V")
	)
	(segment
		(start 231.7261 69.5162)
		(end 232.1261 69.1162)
		(width 0.635)
		(layer "F.Cu")
		(net "+5.0V")
	)
	(segment
		(start 231.1011 67.6162)
		(end 231.6011 67.1162)
		(width 0.635)
		(layer "F.Cu")
		(net "+5.0V")
	)
	(segment
		(start 192.6261 105.8286)
		(end 192.63374 105.82096)
		(width 0.2032)
		(layer "F.Cu")
		(net "+5.0V")
	)
	(segment
		(start 75.1261 66.1162)
		(end 77.1261 66.1162)
		(width 0.635)
		(layer "F.Cu")
		(net "+5.0V")
	)
	(segment
		(start 232.0261 58.9162)
		(end 232.3261 59.2162)
		(width 0.635)
		(layer "F.Cu")
		(net "+5.0V")
	)
	(segment
		(start 87.8551 78.3576)
		(end 88.1261 78.6286)
		(width 0.508)
		(layer "F.Cu")
		(net "+5.0V")
	)
	(segment
		(start 231.6011 67.1162)
		(end 232.1261 67.1162)
		(width 0.635)
		(layer "F.Cu")
		(net "+5.0V")
	)
	(segment
		(start 201.36853 106.32103)
		(end 201.3761 106.3286)
		(width 0.2032)
		(layer "F.Cu")
		(net "+5.0V")
	)
	(segment
		(start 79.51371 65.82859)
		(end 81.9311 65.82859)
		(width 0.635)
		(layer "F.Cu")
		(net "+5.0V")
	)
	(segment
		(start 201.36847 104.82097)
		(end 201.3761 104.8286)
		(width 0.2032)
		(layer "F.Cu")
		(net "+5.0V")
	)
	(segment
		(start 232.3261 61.0162)
		(end 232.3261 59.2162)
		(width 0.635)
		(layer "F.Cu")
		(net "+5.0V")
	)
	(segment
		(start 84.3761 76.8286)
		(end 85.7261 78.1786)
		(width 0.508)
		(layer "F.Cu")
		(net "+5.0V")
	)
	(segment
		(start 85.8761 78.1786)
		(end 85.9761 78.0786)
		(width 0.508)
		(layer "F.Cu")
		(net "+5.0V")
	)
	(segment
		(start 232.1261 69.1162)
		(end 232.1261 67.1162)
		(width 0.635)
		(layer "F.Cu")
		(net "+5.0V")
	)
	(segment
		(start 192.63374 105.82096)
		(end 195.30599 105.82096)
		(width 0.2032)
		(layer "F.Cu")
		(net "+5.0V")
	)
	(segment
		(start 226.4261 111.0162)
		(end 227.3261 111.0162)
		(width 0.254)
		(layer "F.Cu")
		(net "+5.0V")
	)
	(segment
		(start 192.63367 105.32103)
		(end 195.30606 105.32103)
		(width 0.2032)
		(layer "F.Cu")
		(net "+5.0V")
	)
	(segment
		(start 84.3761 76.8286)
		(end 84.3761 74.3286)
		(width 0.508)
		(layer "F.Cu")
		(net "+5.0V")
	)
	(segment
		(start 192.63367 106.32103)
		(end 195.30606 106.32103)
		(width 0.2032)
		(layer "F.Cu")
		(net "+5.0V")
	)
	(segment
		(start 199.37104 105.82096)
		(end 201.36847 105.82096)
		(width 0.2032)
		(layer "F.Cu")
		(net "+5.0V")
	)
	(segment
		(start 195.30606 105.32103)
		(end 195.31363 105.31346)
		(width 0.2032)
		(layer "F.Cu")
		(net "+5.0V")
	)
	(segment
		(start 83.8761 73.8286)
		(end 84.3761 74.3286)
		(width 0.508)
		(layer "F.Cu")
		(net "+5.0V")
	)
	(segment
		(start 192.63373 104.82097)
		(end 195.30599 104.82097)
		(width 0.2032)
		(layer "F.Cu")
		(net "+5.0V")
	)
	(via
		(at 234.6261 105.9162)
		(size 0.4064)
		(drill 0.2032)
		(layers "F.Cu" "B.Cu")
		(net "+5.0V")
	)
	(via
		(at 79.4261 65.9162)
		(size 0.4064)
		(drill 0.2032)
		(layers "F.Cu" "B.Cu")
		(tenting
			(front yes)
			(back yes)
		)
		(net "+5.0V")
	)
	(via
		(at 232.0261 137.9162)
		(size 0.4064)
		(drill 0.2032)
		(layers "F.Cu" "B.Cu")
		(net "+5.0V")
	)
	(via
		(at 192.6261 104.8286)
		(size 0.4064)
		(drill 0.2032)
		(layers "F.Cu" "B.Cu")
		(tenting
			(front yes)
			(back yes)
		)
		(net "+5.0V")
	)
	(via
		(at 89.6761 78.5286)
		(size 0.4064)
		(drill 0.2032)
		(layers "F.Cu" "B.Cu")
		(tenting
			(front yes)
			(back yes)
		)
		(net "+5.0V")
	)
	(via
		(at 192.6261 105.8286)
		(size 0.4064)
		(drill 0.2032)
		(layers "F.Cu" "B.Cu")
		(tenting
			(front yes)
			(back yes)
		)
		(net "+5.0V")
	)
	(via
		(at 235.5261 105.1162)
		(size 0.4064)
		(drill 0.2032)
		(layers "F.Cu" "B.Cu")
		(net "+5.0V")
	)
	(via
		(at 201.3761 105.8286)
		(size 0.4064)
		(drill 0.2032)
		(layers "F.Cu" "B.Cu")
		(tenting
			(front yes)
			(back yes)
		)
		(net "+5.0V")
	)
	(via
		(at 158.5261 87.4162)
		(size 0.4064)
		(drill 0.2032)
		(layers "F.Cu" "B.Cu")
		(tenting
			(front yes)
			(back yes)
		)
		(net "+5.0V")
	)
	(via
		(at 236.3261 105.1162)
		(size 0.4064)
		(drill 0.2032)
		(layers "F.Cu" "B.Cu")
		(net "+5.0V")
	)
	(via
		(at 230.8261 58.9162)
		(size 0.4064)
		(drill 0.2032)
		(layers "F.Cu" "B.Cu")
		(tenting
			(front yes)
			(back yes)
		)
		(net "+5.0V")
	)
	(via
		(at 201.3761 105.3286)
		(size 0.4064)
		(drill 0.2032)
		(layers "F.Cu" "B.Cu")
		(tenting
			(front yes)
			(back yes)
		)
		(net "+5.0V")
	)
	(via
		(at 159.3261 87.4162)
		(size 0.4064)
		(drill 0.2032)
		(layers "F.Cu" "B.Cu")
		(tenting
			(front yes)
			(back yes)
		)
		(net "+5.0V")
	)
	(via
		(at 201.3761 104.8286)
		(size 0.4064)
		(drill 0.2032)
		(layers "F.Cu" "B.Cu")
		(tenting
			(front yes)
			(back yes)
		)
		(net "+5.0V")
	)
	(via
		(at 234.7261 105.0162)
		(size 0.4064)
		(drill 0.2032)
		(layers "F.Cu" "B.Cu")
		(net "+5.0V")
	)
	(via
		(at 230.6261 67.6162)
		(size 0.4064)
		(drill 0.2032)
		(layers "F.Cu" "B.Cu")
		(tenting
			(front yes)
			(back yes)
		)
		(net "+5.0V")
	)
	(via
		(at 236.3261 105.9162)
		(size 0.4064)
		(drill 0.2032)
		(layers "F.Cu" "B.Cu")
		(net "+5.0V")
	)
	(via
		(at 192.6261 105.3286)
		(size 0.4064)
		(drill 0.2032)
		(layers "F.Cu" "B.Cu")
		(tenting
			(front yes)
			(back yes)
		)
		(net "+5.0V")
	)
	(via
		(at 160.0261 87.4162)
		(size 0.4064)
		(drill 0.2032)
		(layers "F.Cu" "B.Cu")
		(tenting
			(front yes)
			(back yes)
		)
		(net "+5.0V")
	)
	(via
		(at 159.3261 86.5162)
		(size 0.4064)
		(drill 0.2032)
		(layers "F.Cu" "B.Cu")
		(tenting
			(front yes)
			(back yes)
		)
		(net "+5.0V")
	)
	(via
		(at 235.5261 105.9162)
		(size 0.4064)
		(drill 0.2032)
		(layers "F.Cu" "B.Cu")
		(net "+5.0V")
	)
	(via
		(at 158.51129 86.51308)
		(size 0.4064)
		(drill 0.2032)
		(layers "F.Cu" "B.Cu")
		(tenting
			(front yes)
			(back yes)
		)
		(net "+5.0V")
	)
	(via
		(at 192.6261 106.3286)
		(size 0.4064)
		(drill 0.2032)
		(layers "F.Cu" "B.Cu")
		(tenting
			(front yes)
			(back yes)
		)
		(net "+5.0V")
	)
	(via
		(at 201.3761 106.3286)
		(size 0.4064)
		(drill 0.2032)
		(layers "F.Cu" "B.Cu")
		(tenting
			(front yes)
			(back yes)
		)
		(net "+5.0V")
	)
	(segment
		(start 237.3261 125.6162)
		(end 237.3261 106.9162)
		(width 0.508)
		(layer "B.Cu")
		(net "+5.0V")
	)
	(segment
		(start 236.3261 105.9162)
		(end 237.3261 106.9162)
		(width 0.508)
		(layer "B.Cu")
		(net "+5.0V")
	)
	(segment
		(start 234.4261 128.5162)
		(end 237.3261 125.6162)
		(width 0.508)
		(layer "B.Cu")
		(net "+5.0V")
	)
	(segment
		(start 234.4261 135.5162)
		(end 234.4261 128.5162)
		(width 0.508)
		(layer "B.Cu")
		(net "+5.0V")
	)
	(segment
		(start 232.0261 137.9162)
		(end 234.4261 135.5162)
		(width 0.508)
		(layer "B.Cu")
		(net "+5.0V")
	)
	(segment
		(start 155.0261 107.7162)
		(end 156.7261 109.4162)
		(width 0.2032)
		(layer "F.Cu")
		(net "FPGA_TDI")
	)
	(segment
		(start 222.3261 140.0162)
		(end 222.3261 132.6162)
		(width 0.2032)
		(layer "F.Cu")
		(net "FPGA_TDI")
	)
	(segment
		(start 146.1761 105.2998)
		(end 146.18242 105.30612)
		(width 0.2032)
		(layer "F.Cu")
		(net "FPGA_TDI")
	)
	(segment
		(start 214.00944 131.9662)
		(end 221.6761 131.9662)
		(width 0.2032)
		(layer "F.Cu")
		(net "FPGA_TDI")
	)
	(segment
		(start 156.7261 109.4162)
		(end 168.7261 109.4162)
		(width 0.2032)
		(layer "F.Cu")
		(net "FPGA_TDI")
	)
	(segment
		(start 168.7261 109.4162)
		(end 190.6261 131.3162)
		(width 0.2032)
		(layer "F.Cu")
		(net "FPGA_TDI")
	)
	(segment
		(start 221.6761 131.9662)
		(end 222.3261 132.6162)
		(width 0.2032)
		(layer "F.Cu")
		(net "FPGA_TDI")
	)
	(segment
		(start 223.5261 141.2162)
		(end 224.9261 141.2162)
		(width 0.2032)
		(layer "F.Cu")
		(net "FPGA_TDI")
	)
	(segment
		(start 190.6261 131.3162)
		(end 213.35944 131.3162)
		(width 0.2032)
		(layer "F.Cu")
		(net "FPGA_TDI")
	)
	(segment
		(start 146.18242 105.30612)
		(end 147.68459 105.30612)
		(width 0.2032)
		(layer "F.Cu")
		(net "FPGA_TDI")
	)
	(segment
		(start 147.68459 105.30612)
		(end 147.69091 105.31244)
		(width 0.2032)
		(layer "F.Cu")
		(net "FPGA_TDI")
	)
	(segment
		(start 213.35944 131.3162)
		(end 214.00944 131.9662)
		(width 0.2032)
		(layer "F.Cu")
		(net "FPGA_TDI")
	)
	(segment
		(start 224.9261 141.2162)
		(end 224.9261 138.7412)
		(width 0.2032)
		(layer "F.Cu")
		(net "FPGA_TDI")
	)
	(segment
		(start 222.3261 140.0162)
		(end 223.5261 141.2162)
		(width 0.2032)
		(layer "F.Cu")
		(net "FPGA_TDI")
	)
	(via
		(at 155.0261 107.7162)
		(size 0.4064)
		(drill 0.2032)
		(layers "F.Cu" "B.Cu")
		(tenting
			(front yes)
			(back yes)
		)
		(net "FPGA_TDI")
	)
	(via
		(at 146.1761 105.2998)
		(size 0.4064)
		(drill 0.2032)
		(layers "F.Cu" "B.Cu")
		(tenting
			(front yes)
			(back yes)
		)
		(net "FPGA_TDI")
	)
	(segment
		(start 146.1761 105.2998)
		(end 148.9097 105.2998)
		(width 0.2032)
		(layer "In2.Cu")
		(net "FPGA_TDI")
	)
	(segment
		(start 151.3261 107.7162)
		(end 155.0261 107.7162)
		(width 0.2032)
		(layer "In2.Cu")
		(net "FPGA_TDI")
	)
	(segment
		(start 148.9097 105.2998)
		(end 151.3261 107.7162)
		(width 0.2032)
		(layer "In2.Cu")
		(net "FPGA_TDI")
	)
	(zone
		(net "GND")
		(layer "F.Cu")
		(hatch edge 0.5)
		(priority 43)
		(connect_pads yes
			(clearance 0.5)
		)
		(min_thickness 0.25)
		(fill yes
			(thermal_gap 0.2032)
			(thermal_bridge_width 0.254)
			(island_removal_mode 0)
		)
		(polygon
			(pts
				(xy 208.4261 119.7162) (xy 208.4261 121.6162) (xy 207.7011 121.6162) (xy 207.7011 122.3662) (xy 208.0761 122.3662)
				(xy 208.0761 126.06619) (xy 206.4761 126.06619) (xy 206.4761 122.7412) (xy 204.5261 122.7412) (xy 204.5261 119.7162)
			)
		)
	)
	(zone
		(net "GND")
		(layer "F.Cu")
		(hatch edge 0.5)
		(priority 74)
		(connect_pads yes
			(clearance 0.5)
		)
		(min_thickness 0.25)
		(fill yes
			(thermal_gap 0.2032)
			(thermal_bridge_width 0.254)
			(island_removal_mode 0)
		)
		(polygon
			(pts
				(xy 55.8761 89.1162) (xy 55.8761 145.1162) (xy 86.1261 145.1162) (xy 86.1261 89.1162)
			)
		)
	)
	(zone
		(net "+5.0V")
		(layer "F.Cu")
		(hatch edge 0.5)
		(priority 27)
		(connect_pads yes
			(clearance 0.5)
		)
		(min_thickness 0.25)
		(fill yes
			(thermal_gap 0.2032)
			(thermal_bridge_width 0.254)
			(island_removal_mode 0)
		)
		(polygon
			(pts
				(xy 225.0011 106.8412) (xy 227.7261 106.8412) (xy 227.7261 109.3162) (xy 231.5261 109.3162) (xy 231.5261 107.7162)
				(xy 232.86234 107.7162) (xy 232.86234 107.4662) (xy 236.07003 107.4662) (xy 236.07003 107.67566)
				(xy 236.7261 107.67566) (xy 236.7261 106.3162) (xy 237.0362 106.3162) (xy 237.0362 102.2727) (xy 235.8261 102.2727)
				(xy 235.8261 103.2162) (xy 233.6261 103.2162) (xy 233.6261 103.7162) (xy 225.0011 103.7162)
			)
		)
	)
	(zone
		(net "P3V3_SENSE")
		(layer "F.Cu")
		(hatch edge 0.5)
		(priority 36)
		(connect_pads yes
			(clearance 0.5)
		)
		(min_thickness 0.25)
		(fill yes
			(thermal_gap 0.2032)
			(thermal_bridge_width 0.254)
			(island_removal_mode 0)
		)
		(polygon
			(pts
				(xy 224.9511 122.5912) (xy 224.9511 126.9307) (xy 220.5406 126.9307) (xy 220.5406 122.5912) (xy 223.9213 122.5912)
			)
		)
	)
	(zone
		(net "NetD12_1")
		(layer "F.Cu")
		(hatch edge 0.5)
		(priority 20)
		(connect_pads yes
			(clearance 0.5)
		)
		(min_thickness 0.25)
		(fill yes
			(thermal_gap 0.2032)
			(thermal_bridge_width 0.254)
			(island_removal_mode 0)
		)
		(polygon
			(pts
				(xy 219.3711 99.4862) (xy 215.0761 99.4862) (xy 215.0761 96.5162) (xy 214.4261 96.5162) (xy 214.4261 94.0162)
				(xy 212.9561 94.0162) (xy 212.9561 91.7712) (xy 216.8261 91.7712) (xy 216.8261 93.5162) (xy 219.3711 93.5162)
				(xy 219.3711 96.7148)
			)
		)
	)
	(zone
		(net "GND")
		(layer "F.Cu")
		(hatch edge 0.5)
		(priority 34)
		(connect_pads yes
			(clearance 0.5)
		)
		(min_thickness 0.25)
		(fill yes
			(thermal_gap 0.2032)
			(thermal_bridge_width 0.254)
			(island_removal_mode 0)
		)
		(polygon
			(pts
				(xy 232.0261 127.3362) (xy 232.0261 124.4162) (xy 233.2261 124.4162) (xy 233.2261 122.0162) (xy 232.6261 122.0162)
				(xy 232.6261 118.5162) (xy 235.6261 118.5162) (xy 235.6261 127.3162) (xy 234.8261 127.3162)
			)
		)
	)
	(zone
		(net "GND")
		(layer "F.Cu")
		(hatch edge 0.5)
		(priority 23)
		(connect_pads yes
			(clearance 0.5)
		)
		(min_thickness 0.25)
		(fill yes
			(thermal_gap 0.2032)
			(thermal_bridge_width 0.254)
			(island_removal_mode 0)
		)
		(polygon
			(pts
				(xy 236.5261 108.1662) (xy 236.5261 109.7162) (xy 231.8261 109.7162) (xy 231.8261 108.1662)
			)
		)
	)
	(zone
		(net "MAC_VCC")
		(layer "F.Cu")
		(hatch edge 0.5)
		(priority 58)
		(connect_pads yes
			(clearance 0.5)
		)
		(min_thickness 0.25)
		(fill yes
			(thermal_gap 0.2032)
			(thermal_bridge_width 0.254)
			(island_removal_mode 0)
		)
		(polygon
			(pts
				(xy 151.0261 90.6162) (xy 151.0261 81.4162) (xy 155.0261 81.4162) (xy 155.0261 90.6162)
			)
		)
	)
	(zone
		(layer "F.Cu")
		(hatch edge 0.5)
		(connect_pads
			(clearance 0)
		)
		(min_thickness 0.25)
		(keepout
			(tracks not_allowed)
			(vias not_allowed)
			(pads not_allowed)
			(copperpour not_allowed)
			(footprints allowed)
		)
		(placement
			(enabled no)
			(sheetname "")
		)
		(fill
			(thermal_gap 0.5)
			(thermal_bridge_width 0.5)
			(island_removal_mode 0)
		)
		(polygon
			(pts
				(arc
					(start 55.82572 156.0786)
					(mid 55.840476 156.114224)
					(end 55.8761 156.12898)
				)
				(arc
					(start 70.8761 156.12898)
					(mid 70.911724 156.114224)
					(end 70.92648 156.0786)
				)
				(xy 70.92648 147.87898) (xy 89.17572 147.87898)
				(arc
					(start 89.17572 152.6286)
					(mid 89.190476 152.664224)
					(end 89.2261 152.67898)
				)
				(arc
					(start 97.2261 152.67898)
					(mid 97.261724 152.664224)
					(end 97.27648 152.6286)
				)
				(xy 97.276477 152.628094) (xy 97.27648 152.62809)
				(arc
					(start 97.27648 149.6536)
					(mid 99.0511 147.87898)
					(end 100.82572 149.6536)
				)
				(arc
					(start 100.82572 149.6536)
					(mid 100.8761 149.70398)
					(end 100.92648 149.6536)
				)
				(arc
					(start 100.92648 146.8286)
					(mid 100.911724 146.792976)
					(end 100.8761 146.77822)
				)
				(arc
					(start 55.8761 146.77822)
					(mid 55.840476 146.792976)
					(end 55.82572 146.8286)
				)
			)
		)
	)
	(zone
		(net "+12V_SENS")
		(layer "F.Cu")
		(hatch edge 0.5)
		(priority 19)
		(connect_pads yes
			(clearance 0.5)
		)
		(min_thickness 0.25)
		(fill yes
			(thermal_gap 0.2032)
			(thermal_bridge_width 0.254)
			(island_removal_mode 0)
		)
		(polygon
			(pts
				(xy 213.5761 98.6662) (xy 213.5761 96.3162) (xy 213.9261 96.3162) (xy 213.9261 94.5162) (xy 210.5511 94.5162)
				(xy 210.5511 92.5912) (xy 208.1261 92.5912) (xy 208.1261 96.4662) (xy 208.7261 96.4662) (xy 208.7261 99.7662)
				(xy 211.1261 99.7662) (xy 211.1261 99.1162) (xy 213.6261 99.1162)
			)
		)
	)
	(zone
		(net "GND")
		(layer "F.Cu")
		(hatch edge 0.5)
		(priority 24)
		(connect_pads yes
			(clearance 0.5)
		)
		(min_thickness 0.25)
		(fill yes
			(thermal_gap 0.2032)
			(thermal_bridge_width 0.254)
			(island_removal_mode 0)
		)
		(polygon
			(pts
				(xy 215.3792 102.31774) (xy 215.3792 101.1162) (xy 216.2261 101.1162) (xy 216.2261 100.2162) (xy 211.1261 100.2162)
				(xy 211.1261 102.31774)
			)
		)
	)
	(zone
		(net "+12V")
		(layer "F.Cu")
		(hatch edge 0.5)
		(priority 18)
		(connect_pads yes
			(clearance 0.5)
		)
		(min_thickness 0.25)
		(fill yes
			(thermal_gap 0.2032)
			(thermal_bridge_width 0.254)
			(island_removal_mode 0)
		)
		(polygon
			(pts
				(xy 210.5511 91.4412) (xy 210.5511 89.3162) (xy 210.8261 89.3162) (xy 210.8261 86.1412) (xy 206.4261 86.1412)
				(xy 206.4261 91.4162) (xy 207.5261 91.4162)
			)
		)
	)
	(zone
		(net "+12V_PCIE")
		(layer "F.Cu")
		(hatch edge 0.5)
		(priority 21)
		(connect_pads yes
			(clearance 0.5)
		)
		(min_thickness 0.25)
		(fill yes
			(thermal_gap 0.2032)
			(thermal_bridge_width 0.254)
			(island_removal_mode 0)
		)
		(polygon
			(pts
				(xy 224.4811 99.4862) (xy 227.6261 99.4862) (xy 227.6261 95.5162) (xy 228.6261 95.5162) (xy 228.6261 94.6162)
				(xy 224.4811 94.6162)
			)
		)
	)
	(zone
		(net "GND")
		(layer "F.Cu")
		(hatch edge 0.5)
		(priority 77)
		(connect_pads yes
			(clearance 0.5)
		)
		(min_thickness 0.25)
		(fill yes
			(thermal_gap 0.2032)
			(thermal_bridge_width 0.254)
			(island_removal_mode 0)
		)
		(polygon
			(pts
				(xy 145.045 89.71569) (xy 94.295 89.71569) (xy 94.295 140.46569) (xy 145.045 140.46569)
			)
		)
	)
	(zone
		(net "GND")
		(layer "F.Cu")
		(hatch edge 0.5)
		(priority 26)
		(connect_pads yes
			(clearance 0.5)
		)
		(min_thickness 0.25)
		(fill yes
			(thermal_gap 0.2032)
			(thermal_bridge_width 0.254)
			(island_removal_mode 0)
		)
		(polygon
			(pts
				(xy 237.4261 101.9162) (xy 235.8261 101.9162) (xy 235.8261 100.9162) (xy 233.3261 100.9162) (xy 233.3261 99.7012)
				(xy 229.6611 99.7012) (xy 229.6611 98.1162) (xy 228.4261 98.1162) (xy 228.4261 95.9162) (xy 237.4261 95.9162)
				(xy 237.4261 96.5162)
			)
		)
	)
	(zone
		(net "NetL2_1")
		(layer "F.Cu")
		(hatch edge 0.5)
		(priority 41)
		(connect_pads yes
			(clearance 0.5)
		)
		(min_thickness 0.25)
		(fill yes
			(thermal_gap 0.2032)
			(thermal_bridge_width 0.254)
			(island_removal_mode 0)
		)
		(polygon
			(pts
				(xy 210.3261 123.7412) (xy 210.3261 125.8162) (xy 211.2561 125.8162) (xy 211.2561 125.9912) (xy 212.84026 125.9912)
				(xy 212.84026 126.8412) (xy 217.1116 126.8412) (xy 217.1116 123.5017) (xy 214.6986 123.5017) (xy 214.6986 123.7412)
			)
		)
	)
	(zone
		(layer "F.Cu")
		(hatch edge 0.5)
		(connect_pads
			(clearance 0)
		)
		(min_thickness 0.25)
		(keepout
			(tracks allowed)
			(vias allowed)
			(pads allowed)
			(copperpour not_allowed)
			(footprints allowed)
		)
		(placement
			(enabled no)
			(sheetname "")
		)
		(fill
			(thermal_gap 0.5)
			(thermal_bridge_width 0.5)
			(island_removal_mode 0)
		)
		(polygon
			(pts
				(arc
					(start 138.18668 115.1786)
					(mid 138.730556 116.491634)
					(end 140.04359 117.03551)
				)
				(arc
					(start 140.04359 117.03551)
					(mid 141.356624 116.491634)
					(end 141.9005 115.1786)
				)
				(arc
					(start 141.9005 115.1786)
					(mid 141.356624 113.865566)
					(end 140.04359 113.32169)
				)
				(arc
					(start 140.04359 113.32169)
					(mid 138.730556 113.865566)
					(end 138.18668 115.1786)
				)
			)
		)
	)
	(zone
		(layer "F.Cu")
		(hatch edge 0.5)
		(connect_pads
			(clearance 0)
		)
		(min_thickness 0.25)
		(keepout
			(tracks allowed)
			(vias allowed)
			(pads allowed)
			(copperpour not_allowed)
			(footprints allowed)
		)
		(placement
			(enabled no)
			(sheetname "")
		)
		(fill
			(thermal_gap 0.5)
			(thermal_bridge_width 0.5)
			(island_removal_mode 0)
		)
		(polygon
			(pts
				(arc
					(start 97.58668 135.4786)
					(mid 98.130556 136.791634)
					(end 99.44359 137.33551)
				)
				(arc
					(start 99.44359 137.33551)
					(mid 100.756624 136.791634)
					(end 101.3005 135.4786)
				)
				(arc
					(start 101.3005 135.4786)
					(mid 100.756624 134.165566)
					(end 99.44359 133.62169)
				)
				(arc
					(start 99.44359 133.62169)
					(mid 98.130556 134.165566)
					(end 97.58668 135.4786)
				)
			)
		)
	)
	(zone
		(net "GND")
		(layer "F.Cu")
		(hatch edge 0.5)
		(priority 25)
		(connect_pads yes
			(clearance 0.5)
		)
		(min_thickness 0.25)
		(fill yes
			(thermal_gap 0.2032)
			(thermal_bridge_width 0.254)
			(island_removal_mode 0)
		)
		(polygon
			(pts
				(xy 223.9311 104.8812) (xy 223.9311 103.4162) (xy 225.5261 103.4162) (xy 225.5261 101.3162) (xy 221.9411 101.3162)
				(xy 221.9411 104.8812)
			)
		)
	)
	(zone
		(layer "F.Cu")
		(hatch edge 0.5)
		(connect_pads
			(clearance 0)
		)
		(min_thickness 0.25)
		(keepout
			(tracks allowed)
			(vias allowed)
			(pads allowed)
			(copperpour not_allowed)
			(footprints allowed)
		)
		(placement
			(enabled no)
			(sheetname "")
		)
		(fill
			(thermal_gap 0.5)
			(thermal_bridge_width 0.5)
			(island_removal_mode 0)
		)
		(polygon
			(pts
				(arc
					(start 138.18668 94.8786)
					(mid 138.730556 96.191634)
					(end 140.04359 96.73551)
				)
				(arc
					(start 140.04359 96.73551)
					(mid 141.356624 96.191634)
					(end 141.9005 94.8786)
				)
				(arc
					(start 141.9005 94.8786)
					(mid 141.356624 93.565566)
					(end 140.04359 93.02169)
				)
				(arc
					(start 140.04359 93.02169)
					(mid 138.730556 93.565566)
					(end 138.18668 94.8786)
				)
			)
		)
	)
	(zone
		(net "GND")
		(layer "F.Cu")
		(hatch edge 0.5)
		(priority 32)
		(connect_pads yes
			(clearance 0.5)
		)
		(min_thickness 0.25)
		(fill yes
			(thermal_gap 0.2032)
			(thermal_bridge_width 0.254)
			(island_removal_mode 0)
		)
		(polygon
			(pts
				(xy 210.9144 104.3162) (xy 210.9144 112.3162) (xy 211.8394 112.3162) (xy 211.8394 111.53006) (xy 214.08939 111.53006)
				(xy 214.08939 112.5162) (xy 213.5261 112.5162) (xy 213.5261 114.0162) (xy 209.2261 114.0162) (xy 209.2261 112.8162)
				(xy 209.88939 112.8162) (xy 209.88939 111.18005) (xy 209.31439 111.18005) (xy 209.31439 107.85506)
				(xy 207.4261 107.85506) (xy 207.4261 105.2162) (xy 207.8261 105.2162) (xy 207.8261 104.3162)
			)
		)
	)
	(zone
		(net "GND")
		(layer "F.Cu")
		(hatch edge 0.5)
		(priority 17)
		(connect_pads yes
			(clearance 0.5)
		)
		(min_thickness 0.25)
		(fill yes
			(thermal_gap 0.2032)
			(thermal_bridge_width 0.254)
			(island_removal_mode 0)
		)
		(polygon
			(pts
				(xy 204.5261 96.4662) (xy 202.9261 96.4662) (xy 202.9261 94.4162) (xy 201.1261 94.4162) (xy 201.1261 102.6162)
				(xy 204.5261 102.6162) (xy 204.5261 98.1162)
			)
		)
	)
	(zone
		(net "+5.0V")
		(layer "F.Cu")
		(hatch edge 0.5)
		(priority 59)
		(connect_pads yes
			(clearance 0.5)
		)
		(min_thickness 0.25)
		(fill yes
			(thermal_gap 0.2032)
			(thermal_bridge_width 0.254)
			(island_removal_mode 0)
		)
		(polygon
			(pts
				(xy 156.7261 85.2162) (xy 160.5261 85.2162) (xy 160.5261 88.1162) (xy 156.7261 88.1162)
			)
		)
	)
	(zone
		(net "+3.3V")
		(layer "F.Cu")
		(hatch edge 0.5)
		(priority 53)
		(connect_pads yes
			(clearance 0.5)
		)
		(min_thickness 0.25)
		(fill yes
			(thermal_gap 0.2032)
			(thermal_bridge_width 0.254)
			(island_removal_mode 0)
		)
		(polygon
			(pts
				(xy 156.9261 88.8162) (xy 160.4261 88.8162) (xy 160.4261 91.9162) (xy 156.9261 91.9162)
			)
		)
	)
	(zone
		(net "+12V")
		(layer "F.Cu")
		(hatch edge 0.5)
		(priority 45)
		(connect_pads yes
			(clearance 0.5)
		)
		(min_thickness 0.25)
		(fill yes
			(thermal_gap 0.2032)
			(thermal_bridge_width 0.254)
			(island_removal_mode 0)
		)
		(polygon
			(pts
				(xy 156.6761 84.6662) (xy 161.0261 84.6662) (xy 161.0261 81.4162) (xy 156.7261 81.4162) (xy 156.7261 82.3162)
			)
		)
	)
	(zone
		(net "P5V_SENSE")
		(layer "F.Cu")
		(hatch edge 0.5)
		(priority 29)
		(connect_pads yes
			(clearance 0.5)
		)
		(min_thickness 0.25)
		(fill yes
			(thermal_gap 0.2032)
			(thermal_bridge_width 0.254)
			(island_removal_mode 0)
		)
		(polygon
			(pts
				(xy 225.5492 111.6307) (xy 225.5492 110.4912) (xy 227.1261 110.4912) (xy 227.1261 107.8162) (xy 221.4406 107.8162)
				(xy 221.4406 111.6307)
			)
		)
	)
	(zone
		(net "GND")
		(layer "F.Cu")
		(hatch edge 0.5)
		(priority 42)
		(connect_pads yes
			(clearance 0.5)
		)
		(min_thickness 0.25)
		(fill yes
			(thermal_gap 0.2032)
			(thermal_bridge_width 0.254)
			(island_removal_mode 0)
		)
		(polygon
			(pts
				(xy 206.4761 125.4902) (xy 206.4761 128.2162) (xy 210.4261 128.2162) (xy 210.4261 127.1162) (xy 211.6261 127.1162)
				(xy 211.6261 126.4162) (xy 208.6511 126.4162) (xy 208.6511 126.8162) (xy 208.0761 126.8162) (xy 208.0761 125.49572)
			)
		)
	)
	(zone
		(net "GND")
		(layer "F.Cu")
		(hatch edge 0.5)
		(connect_pads yes
			(clearance 0.5)
		)
		(min_thickness 0.25)
		(fill yes
			(thermal_gap 0.2032)
			(thermal_bridge_width 0.254)
			(island_removal_mode 0)
		)
		(polygon
			(pts
				(xy 206.6261 85.4162) (xy 212.0261 85.4162) (xy 212.0261 82.9162) (xy 208.2261 82.9162) (xy 208.2261 82.2162)
				(xy 206.9261 82.2162) (xy 206.9261 84.0162) (xy 206.6261 84.0162)
			)
		)
	)
	(zone
		(net "GND")
		(layer "F.Cu")
		(hatch edge 0.5)
		(priority 33)
		(connect_pads yes
			(clearance 0.5)
		)
		(min_thickness 0.25)
		(fill yes
			(thermal_gap 0.2032)
			(thermal_bridge_width 0.254)
			(island_removal_mode 0)
		)
		(polygon
			(pts
				(xy 213.273 117.1662) (xy 216.3261 117.1662) (xy 216.3261 117.0162) (xy 224.5111 117.0162) (xy 224.5111 120.8812)
				(xy 218.1261 120.8812) (xy 218.1261 118.9162) (xy 216.073 118.9162) (xy 216.073 118.69006) (xy 213.273 118.69006)
				(xy 213.273 118.24042)
			)
		)
	)
	(zone
		(net "+3.3V")
		(layer "F.Cu")
		(hatch edge 0.5)
		(priority 35)
		(connect_pads yes
			(clearance 0.5)
		)
		(min_thickness 0.25)
		(fill yes
			(thermal_gap 0.2032)
			(thermal_bridge_width 0.254)
			(island_removal_mode 0)
		)
		(polygon
			(pts
				(xy 226.1011 122.5912) (xy 228.5411 122.5912) (xy 228.5411 118.5512) (xy 232.03571 118.5512) (xy 232.03571 120.1162)
				(xy 231.7761 120.1162) (xy 231.7761 122.4162) (xy 230.7261 122.4162) (xy 230.7261 124.5162) (xy 231.8261 124.5162)
				(xy 231.8261 128.2162) (xy 226.2261 128.2162) (xy 226.19037 125.96154)
			)
		)
	)
	(zone
		(net "+12V")
		(layer "F.Cu")
		(hatch edge 0.5)
		(priority 31)
		(connect_pads yes
			(clearance 0.5)
		)
		(min_thickness 0.25)
		(fill yes
			(thermal_gap 0.2032)
			(thermal_bridge_width 0.254)
			(island_removal_mode 0)
		)
		(polygon
			(pts
				(xy 211.273 105.1162) (xy 211.6261 105.1162) (xy 211.6261 106.4162) (xy 211.2261 106.4162) (xy 211.2261 107.1162)
				(xy 214.36439 107.1162) (xy 214.36439 108.50506) (xy 215.3261 108.50506) (xy 215.3261 106.2162)
				(xy 217.9111 106.2162) (xy 217.9111 102.5512) (xy 215.6261 102.5512) (xy 215.6261 103.71466) (xy 211.273 103.71466)
			)
		)
	)
	(zone
		(net "NetD12_2")
		(layer "F.Cu")
		(hatch edge 0.5)
		(priority 22)
		(connect_pads yes
			(clearance 0.5)
		)
		(min_thickness 0.25)
		(fill yes
			(thermal_gap 0.2032)
			(thermal_bridge_width 0.254)
			(island_removal_mode 0)
		)
		(polygon
			(pts
				(xy 222.8261 82.2162) (xy 212.3261 82.2162) (xy 212.3261 86.8162) (xy 217.7261 86.8162) (xy 217.7261 93.1162)
				(xy 222.8261 93.1162)
			)
		)
	)
	(zone
		(net "NetL1_1")
		(layer "F.Cu")
		(hatch edge 0.5)
		(priority 30)
		(connect_pads yes
			(clearance 0.5)
		)
		(min_thickness 0.25)
		(fill yes
			(thermal_gap 0.2032)
			(thermal_bridge_width 0.254)
			(island_removal_mode 0)
		)
		(polygon
			(pts
				(xy 214.56439 108.85506) (xy 216.0556 108.85506) (xy 216.0556 108.2017) (xy 218.0116 108.2017) (xy 218.0116 111.6307)
				(xy 216.2261 111.6307) (xy 216.2261 113.2162) (xy 213.8761 113.2162) (xy 213.8761 112.8662) (xy 214.36439 112.8662)
				(xy 214.36439 110.93005) (xy 213.0261 110.93005) (xy 213.0261 109.0162)
			)
		)
	)
	(zone
		(net "GND")
		(layer "F.Cu")
		(hatch edge 0.5)
		(priority 37)
		(connect_pads yes
			(clearance 0.5)
		)
		(min_thickness 0.25)
		(fill yes
			(thermal_gap 0.2032)
			(thermal_bridge_width 0.254)
			(island_removal_mode 0)
		)
		(polygon
			(pts
				(xy 204.7111 116.1512) (xy 204.7111 119.0162) (xy 202.8261 119.0162) (xy 202.8261 120.1162) (xy 201.2261 120.1162)
				(xy 201.2261 116.1512) (xy 202.92985 116.1512)
			)
		)
	)
	(zone
		(net "+12V")
		(layer "F.Cu")
		(hatch edge 0.5)
		(priority 38)
		(connect_pads yes
			(clearance 0.5)
		)
		(min_thickness 0.25)
		(fill yes
			(thermal_gap 0.2032)
			(thermal_bridge_width 0.254)
			(island_removal_mode 0)
		)
		(polygon
			(pts
				(xy 217.7792 120.31466) (xy 213.273 120.31466) (xy 213.273 120.21466) (xy 212.4261 120.21466) (xy 212.4261 116.1512)
				(xy 209.21084 116.1512) (xy 209.21084 118.4812) (xy 210.7311 118.4812) (xy 210.7311 120.0162) (xy 209.3261 120.0162)
				(xy 209.3261 121.3162) (xy 208.3511 121.3162) (xy 208.3511 122.0162) (xy 211.5261 122.0162) (xy 211.5261 123.3912)
				(xy 213.9261 123.3912) (xy 213.9261 121.4693) (xy 217.77324 121.4693)
			)
		)
	)
	(zone
		(layers "F.Cu" "B.Cu" "In1.Cu" "In2.Cu" "In3.Cu" "In4.Cu")
		(hatch edge 0.5)
		(connect_pads
			(clearance 0)
		)
		(min_thickness 0.25)
		(keepout
			(tracks not_allowed)
			(vias not_allowed)
			(pads not_allowed)
			(copperpour not_allowed)
			(footprints allowed)
		)
		(placement
			(enabled no)
			(sheetname "")
		)
		(fill
			(thermal_gap 0.5)
			(thermal_bridge_width 0.5)
			(island_removal_mode 0)
		)
		(polygon
			(pts
				(xy 89.2261 156.0786) (xy 97.2261 156.0786) (xy 97.2261 152.6286) (xy 89.2261 152.6286)
			)
		)
	)
	(zone
		(layer "F.Mask")
		(hatch edge 0.5)
		(priority 115)
		(connect_pads yes
			(clearance 0.5)
		)
		(min_thickness 0.25)
		(fill yes
			(thermal_gap 0.2032)
			(thermal_bridge_width 0.254)
			(island_removal_mode 0)
		)
		(polygon
			(pts
				(xy 145.1261 89.7036) (xy 94.3761 89.7036) (xy 94.3761 140.4536) (xy 145.1261 140.4536)
			)
		)
	)
	(zone
		(net "+5.0V")
		(layer "B.Cu")
		(hatch edge 0.5)
		(priority 3)
		(connect_pads yes
			(clearance 0.5)
		)
		(min_thickness 0.25)
		(fill yes
			(thermal_gap 0.2032)
			(thermal_bridge_width 0.254)
			(island_removal_mode 0)
		)
		(polygon
			(pts
				(xy 158.0261 83.0162) (xy 158.0261 88.8162) (xy 161.7261 88.8162) (xy 161.7261 98.7162) (xy 184.7261 98.7162)
				(xy 184.7261 108.1162) (xy 198.1261 108.1162) (xy 198.1261 101.6162) (xy 195.1261 101.6162) (xy 195.1261 90.4162)
				(xy 173.8261 90.4162) (xy 173.8261 83.0162)
			)
		)
	)
	(zone
		(net "MAC_VCC")
		(layer "B.Cu")
		(hatch edge 0.5)
		(priority 51)
		(connect_pads yes
			(clearance 0.5)
		)
		(min_thickness 0.25)
		(fill yes
			(thermal_gap 0.2032)
			(thermal_bridge_width 0.254)
			(island_removal_mode 0)
		)
		(polygon
			(pts
				(xy 153.5261 82.7162) (xy 153.5261 92.4162) (xy 143.3261 92.4162) (xy 143.3261 96.8162) (xy 137.1261 96.8162)
				(xy 137.1261 88.4162) (xy 144.7261 88.4162) (xy 144.7261 82.7162)
			)
		)
	)
	(zone
		(net "+3.3V")
		(layer "B.Cu")
		(hatch edge 0.5)
		(priority 6)
		(connect_pads yes
			(clearance 0.5)
		)
		(min_thickness 0.25)
		(fill yes
			(thermal_gap 0.2032)
			(thermal_bridge_width 0.254)
			(island_removal_mode 0)
		)
		(polygon
			(pts
				(xy 160.8261 88.9162) (xy 160.8261 92.6162) (xy 154.3261 92.6162) (xy 154.3261 79.2162) (xy 154.9261 79.2162)
				(xy 154.9261 73.6162) (xy 164.2261 73.6162) (xy 164.2261 81.8162) (xy 157.8261 81.8162) (xy 157.8261 88.9162)
			)
		)
	)
	(zone
		(layer "B.Cu")
		(hatch edge 0.5)
		(connect_pads
			(clearance 0)
		)
		(min_thickness 0.25)
		(keepout
			(tracks not_allowed)
			(vias not_allowed)
			(pads not_allowed)
			(copperpour not_allowed)
			(footprints allowed)
		)
		(placement
			(enabled no)
			(sheetname "")
		)
		(fill
			(thermal_gap 0.5)
			(thermal_bridge_width 0.5)
			(island_removal_mode 0)
		)
		(polygon
			(pts
				(arc
					(start 55.82572 156.0786)
					(mid 55.840476 156.114224)
					(end 55.8761 156.12898)
				)
				(arc
					(start 70.8761 156.12898)
					(mid 70.911724 156.114224)
					(end 70.92648 156.0786)
				)
				(xy 70.92648 147.87898) (xy 89.17572 147.87898)
				(arc
					(start 89.17572 152.6286)
					(mid 89.190476 152.664224)
					(end 89.2261 152.67898)
				)
				(arc
					(start 97.2261 152.67898)
					(mid 97.261724 152.664224)
					(end 97.27648 152.6286)
				)
				(xy 97.276477 152.628094) (xy 97.27648 152.62809)
				(arc
					(start 97.27648 149.6536)
					(mid 99.0511 147.87898)
					(end 100.82572 149.6536)
				)
				(arc
					(start 100.82572 149.6536)
					(mid 100.8761 149.70398)
					(end 100.92648 149.6536)
				)
				(arc
					(start 100.92648 146.8286)
					(mid 100.911724 146.792976)
					(end 100.8761 146.77822)
				)
				(arc
					(start 55.8761 146.77822)
					(mid 55.840476 146.792976)
					(end 55.82572 146.8286)
				)
			)
		)
	)
	(zone
		(net "+3.3V")
		(layer "B.Cu")
		(hatch edge 0.5)
		(priority 9)
		(connect_pads yes
			(clearance 0.5)
		)
		(min_thickness 0.25)
		(fill yes
			(thermal_gap 0.2032)
			(thermal_bridge_width 0.254)
			(island_removal_mode 0)
		)
		(polygon
			(pts
				(xy 230.4261 127.7162) (xy 224.8261 133.3162) (xy 224.8261 136.1162) (xy 206.3261 136.1162) (xy 198.4261 128.2162)
				(xy 198.4261 122.7162) (xy 200.0261 121.1162) (xy 202.3261 121.1162) (xy 208.2261 115.2162) (xy 229.1261 115.2162)
				(xy 230.4261 116.5162) (xy 230.4261 120.8162)
			)
		)
	)
	(zone
		(net "+5.0V")
		(layer "B.Cu")
		(hatch edge 0.5)
		(priority 1)
		(connect_pads yes
			(clearance 0.5)
		)
		(min_thickness 0.25)
		(fill yes
			(thermal_gap 0.2032)
			(thermal_bridge_width 0.254)
			(island_removal_mode 0)
		)
		(polygon
			(pts
				(xy 228.9261 56.7162) (xy 228.9261 60.4162) (xy 230.8261 60.4162) (xy 230.8261 63.1162) (xy 227.0261 66.7162)
				(xy 227.0261 72.7162) (xy 223.9261 72.7162) (xy 223.9261 85.6162) (xy 229.1261 85.6162) (xy 229.1261 96.26926)
				(xy 233.36104 96.26926) (xy 233.36104 106.9162) (xy 238.8261 106.9162) (xy 238.8261 98.2162) (xy 237.7261 98.2162)
				(xy 237.7261 96.4162) (xy 235.6261 96.4162) (xy 235.6261 92.0162) (xy 231.9261 92.0162) (xy 231.9261 82.5162)
				(xy 225.8261 82.5162) (xy 225.8261 76.2162) (xy 232.3261 76.2162) (xy 232.3261 70.6162) (xy 234.3261 70.6162)
				(xy 234.3261 57.9162) (xy 233.8261 57.9162) (xy 233.8261 56.7162) (xy 232.7261 56.7162)
			)
		)
	)
	(zone
		(layer "In1.Cu")
		(hatch edge 0.5)
		(connect_pads
			(clearance 0)
		)
		(min_thickness 0.25)
		(keepout
			(tracks allowed)
			(vias allowed)
			(pads allowed)
			(copperpour not_allowed)
			(footprints allowed)
		)
		(placement
			(enabled no)
			(sheetname "")
		)
		(fill
			(thermal_gap 0.5)
			(thermal_bridge_width 0.5)
			(island_removal_mode 0)
		)
		(polygon
			(pts
				(xy 100.7261 160.9286) (xy 100.7261 154.8536) (xy 135.4761 154.8536) (xy 135.4761 161.1786)
			)
		)
	)
	(zone
		(net "GND")
		(layer "In1.Cu")
		(hatch edge 0.5)
		(priority 99)
		(connect_pads yes
			(clearance 0.5)
		)
		(min_thickness 0.25)
		(fill yes
			(thermal_gap 0.2032)
			(thermal_bridge_width 0.254)
			(island_removal_mode 0)
		)
		(polygon
			(pts
				(xy 70.6549 155.8018) (xy 70.6549 147.5722) (xy 89.4509 147.5722) (xy 89.4509 155.8018) (xy 96.9947 155.8018)
				(xy 96.9947 148.639) (xy 98.1377 147.496) (xy 99.9665 147.496) (xy 101.1349 148.6644) (xy 101.1349 160.0436)
				(xy 101.4143 160.323) (xy 111.5235 160.323) (xy 111.8283 160.0182) (xy 111.8283 152.6014) (xy 112.6411 151.7886)
				(xy 113.3523 151.7886) (xy 114.1651 152.6014) (xy 114.1651 160.0436) (xy 114.4953 160.3738) (xy 134.6375 160.3738)
				(xy 134.9931 160.0182) (xy 134.9931 147.6484) (xy 241.12608 147.64841) (xy 241.12609 49.6786) (xy 56.38209 49.67861)
				(xy 56.0753 49.9854) (xy 56.0753 155.8018)
			)
		)
	)
	(zone
		(net "+3.3V")
		(layer "In2.Cu")
		(hatch edge 0.5)
		(priority 44)
		(connect_pads yes
			(clearance 0.5)
		)
		(min_thickness 0.25)
		(fill yes
			(thermal_gap 0.2032)
			(thermal_bridge_width 0.254)
			(island_removal_mode 0)
		)
		(polygon
			(pts
				(xy 81.6261 125.9162) (xy 86.4261 125.9162) (xy 86.4261 129.1162) (xy 81.6261 129.1162)
			)
		)
	)
	(zone
		(net "+3.3V")
		(layer "In2.Cu")
		(hatch edge 0.5)
		(priority 10)
		(connect_pads yes
			(clearance 0.5)
		)
		(min_thickness 0.25)
		(fill yes
			(thermal_gap 0.2032)
			(thermal_bridge_width 0.254)
			(island_removal_mode 0)
		)
		(polygon
			(pts
				(xy 226.2261 123.2162) (xy 226.2261 128.8162) (xy 232.9261 128.8162) (xy 232.9261 123.2162)
			)
		)
	)
	(zone
		(net "+12V")
		(layer "In2.Cu")
		(hatch edge 0.5)
		(priority 50)
		(connect_pads yes
			(clearance 0.5)
		)
		(min_thickness 0.25)
		(fill yes
			(thermal_gap 0.2032)
			(thermal_bridge_width 0.254)
			(island_removal_mode 0)
		)
		(polygon
			(pts
				(xy 156.9261 83.1162) (xy 156.9261 71.0162) (xy 209.7261 71.0162) (xy 209.7261 76.0162) (xy 163.8261 76.0162)
				(xy 163.8261 83.1162)
			)
		)
	)
	(zone
		(net "+5.0V")
		(layer "In2.Cu")
		(hatch edge 0.5)
		(priority 2)
		(connect_pads yes
			(clearance 0.5)
		)
		(min_thickness 0.25)
		(fill yes
			(thermal_gap 0.2032)
			(thermal_bridge_width 0.254)
			(island_removal_mode 0)
		)
		(polygon
			(pts
				(xy 160.5261 87.9162) (xy 145.7261 87.9162) (xy 145.7261 82.1162) (xy 145.5261 82.1162) (xy 145.5261 76.2162)
				(xy 107.6261 76.2162) (xy 107.6261 81.3162) (xy 88.8261 81.3162) (xy 88.8261 75.8162) (xy 76.9261 75.8162)
				(xy 76.9261 63.9162) (xy 99.3261 63.9162) (xy 99.3261 70.5162) (xy 150.7261 70.5162) (xy 150.7261 79.0162)
				(xy 151.7261 79.0162) (xy 151.7261 85.3162) (xy 160.5261 85.3162)
			)
		)
	)
	(zone
		(net "+3.3V")
		(layer "In2.Cu")
		(hatch edge 0.5)
		(priority 7)
		(connect_pads yes
			(clearance 0.5)
		)
		(min_thickness 0.25)
		(fill yes
			(thermal_gap 0.2032)
			(thermal_bridge_width 0.254)
			(island_removal_mode 0)
		)
		(polygon
			(pts
				(xy 239.0261 93.7162) (xy 239.0261 128.8162) (xy 226.2261 128.8162) (xy 226.2261 99.4162) (xy 227.8261 99.4162)
				(xy 227.8261 93.7162)
			)
		)
	)
	(zone
		(net "+12V")
		(layer "In2.Cu")
		(hatch edge 0.5)
		(priority 15)
		(connect_pads yes
			(clearance 0.5)
		)
		(min_thickness 0.25)
		(fill yes
			(thermal_gap 0.2032)
			(thermal_bridge_width 0.254)
			(island_removal_mode 0)
		)
		(polygon
			(pts
				(xy 211.2261 87.8162) (xy 208.1261 87.8162) (xy 208.1261 88.5162) (xy 207.7261 88.5162) (xy 207.7261 104.0162)
				(xy 211.7261 104.0162) (xy 211.7261 106.7162) (xy 216.9261 106.7162) (xy 216.9261 101.3162) (xy 211.2261 101.3162)
				(xy 211.2261 92.3162)
			)
		)
	)
	(zone
		(net "+5.0V")
		(layer "In3.Cu")
		(hatch edge 0.5)
		(priority 82)
		(connect_pads yes
			(clearance 0.5)
		)
		(min_thickness 0.25)
		(fill yes
			(thermal_gap 0.2032)
			(thermal_bridge_width 0.254)
			(island_removal_mode 0)
		)
		(polygon
			(pts
				(xy 157.2261 87.7162) (xy 167.9261 87.7162) (xy 167.9261 94.9162) (xy 175.8261 94.9162) (xy 175.8261 108.3162)
				(xy 201.8261 108.3162) (xy 201.8261 101.1162) (xy 182.2261 101.1162) (xy 182.2261 86.5162) (xy 177.1261 86.5162)
				(xy 177.1261 83.1162) (xy 173.4261 83.1162) (xy 157.2261 83.1162)
			)
		)
	)
	(zone
		(net "+12V")
		(layer "In3.Cu")
		(hatch edge 0.5)
		(priority 84)
		(connect_pads yes
			(clearance 0.5)
		)
		(min_thickness 0.25)
		(fill yes
			(thermal_gap 0.2032)
			(thermal_bridge_width 0.254)
			(island_removal_mode 0)
		)
		(polygon
			(pts
				(xy 211.2261 90.5162) (xy 202.8261 90.5162) (xy 202.8261 70.1162) (xy 212.1261 70.1162) (xy 212.1261 74.8162)
				(xy 206.2261 74.8162) (xy 206.2261 86.3162) (xy 211.2261 86.3162)
			)
		)
	)
	(zone
		(net "+3.3V")
		(layer "In3.Cu")
		(hatch edge 0.5)
		(priority 76)
		(connect_pads yes
			(clearance 0.5)
		)
		(min_thickness 0.25)
		(fill yes
			(thermal_gap 0.2032)
			(thermal_bridge_width 0.254)
			(island_removal_mode 0)
		)
		(polygon
			(pts
				(xy 220.02615 50.6162) (xy 109.8761 50.6162) (xy 109.8761 90.61619) (xy 220.02605 90.61621)
			)
		)
	)
	(zone
		(net "+3.3V")
		(layer "In3.Cu")
		(hatch edge 0.5)
		(priority 8)
		(connect_pads yes
			(clearance 0.5)
		)
		(min_thickness 0.25)
		(fill yes
			(thermal_gap 0.2032)
			(thermal_bridge_width 0.254)
			(island_removal_mode 0)
		)
		(polygon
			(pts
				(xy 228.2261 94.5162) (xy 228.2261 98.8162) (xy 239.1261 98.8162) (xy 239.1261 83.2162) (xy 234.3261 83.2162)
				(xy 234.3261 58.6162) (xy 215.5261 58.6162) (xy 215.5261 76.4162) (xy 221.2261 76.4162) (xy 221.2261 85.4162)
				(xy 228.2261 85.4162) (xy 228.2261 93.0162)
			)
		)
	)
	(zone
		(net "+5.0V")
		(layer "In3.Cu")
		(hatch edge 0.5)
		(priority 11)
		(connect_pads yes
			(clearance 0.5)
		)
		(min_thickness 0.25)
		(fill yes
			(thermal_gap 0.2032)
			(thermal_bridge_width 0.254)
			(island_removal_mode 0)
		)
		(polygon
			(pts
				(xy 197.2261 101.6162) (xy 197.2261 99.2162) (xy 202.8261 99.2162) (xy 202.8261 104.1162) (xy 219.8261 104.1162)
				(xy 219.8261 107.3162) (xy 237.7261 107.3162) (xy 237.7261 98.8162) (xy 218.7261 98.8162) (xy 218.7261 92.6162)
				(xy 201.5261 92.6162) (xy 201.5261 91.88743) (xy 190.7261 91.88743) (xy 190.7261 101.5162)
			)
		)
	)
	(zone
		(net "+3.3V")
		(layer "In3.Cu")
		(hatch edge 0.5)
		(priority 16)
		(connect_pads yes
			(clearance 0.5)
		)
		(min_thickness 0.25)
		(fill yes
			(thermal_gap 0.2032)
			(thermal_bridge_width 0.254)
			(island_removal_mode 0)
		)
		(polygon
			(pts
				(xy 77.9261 146.6162) (xy 94.1261 146.6162) (xy 94.1261 61.7412) (xy 77.9261 61.7412)
			)
		)
	)
	(zone
		(net "+3.3V")
		(layer "In3.Cu")
		(hatch edge 0.5)
		(priority 79)
		(connect_pads yes
			(clearance 0.5)
		)
		(min_thickness 0.25)
		(fill yes
			(thermal_gap 0.2032)
			(thermal_bridge_width 0.254)
			(island_removal_mode 0)
		)
		(polygon
			(pts
				(xy 69.6261 50.5786) (xy 69.6261 89.6162) (xy 113.3761 89.6162) (xy 113.3761 50.5786)
			)
		)
	)
	(zone
		(net "+12V")
		(layer "In3.Cu")
		(hatch edge 0.5)
		(priority 13)
		(connect_pads yes
			(clearance 0.5)
		)
		(min_thickness 0.25)
		(fill yes
			(thermal_gap 0.2032)
			(thermal_bridge_width 0.254)
			(island_removal_mode 0)
		)
		(polygon
			(pts
				(xy 212.2261 111.8162) (xy 207.9261 111.8162) (xy 207.9261 117.3162) (xy 213.7261 117.3162) (xy 213.7261 121.0162)
				(xy 209.1261 121.0162) (xy 209.1261 119.6162) (xy 205.3261 119.6162) (xy 205.3261 106.7162) (xy 212.2261 106.7162)
			)
		)
	)
	(zone
		(net "+12V")
		(layer "In3.Cu")
		(hatch edge 0.5)
		(priority 14)
		(connect_pads yes
			(clearance 0.5)
		)
		(min_thickness 0.25)
		(fill yes
			(thermal_gap 0.2032)
			(thermal_bridge_width 0.254)
			(island_removal_mode 0)
		)
		(polygon
			(pts
				(xy 211.8261 105.0162) (xy 211.8261 111.8162) (xy 213.7261 111.8162) (xy 213.7261 117.3162) (xy 209.1261 117.3162)
				(xy 209.1261 123.4162) (xy 215.0261 123.4162) (xy 215.0261 117.7162) (xy 216.3261 117.7162) (xy 216.3261 105.0162)
				(xy 215.1261 105.0162)
			)
		)
	)
	(zone
		(layer "In4.Cu")
		(hatch edge 0.5)
		(connect_pads
			(clearance 0)
		)
		(min_thickness 0.25)
		(keepout
			(tracks allowed)
			(vias allowed)
			(pads allowed)
			(copperpour not_allowed)
			(footprints allowed)
		)
		(placement
			(enabled no)
			(sheetname "")
		)
		(fill
			(thermal_gap 0.5)
			(thermal_bridge_width 0.5)
			(island_removal_mode 0)
		)
		(polygon
			(pts
				(xy 100.7261 160.9286) (xy 100.7261 154.8536) (xy 135.4761 154.8536) (xy 135.4761 161.1786)
			)
		)
	)
	(zone
		(net "GND")
		(layer "In4.Cu")
		(hatch edge 0.5)
		(priority 97)
		(connect_pads yes
			(clearance 0.5)
		)
		(min_thickness 0.25)
		(fill yes
			(thermal_gap 0.2032)
			(thermal_bridge_width 0.254)
			(island_removal_mode 0)
		)
		(polygon
			(pts
				(xy 70.5299 155.9016) (xy 70.5299 147.672) (xy 89.3259 147.672) (xy 89.3259 155.9016) (xy 96.8697 155.9016)
				(xy 96.8697 148.7388) (xy 98.0127 147.5958) (xy 99.8415 147.5958) (xy 101.0099 148.7642) (xy 101.0099 160.1434)
				(xy 101.2893 160.4228) (xy 111.3985 160.4228) (xy 111.7033 160.118) (xy 111.7033 152.7012) (xy 112.5161 151.8884)
				(xy 113.2273 151.8884) (xy 114.0401 152.7012) (xy 114.0401 160.1434) (xy 114.3703 160.4736) (xy 134.5125 160.4736)
				(xy 134.8681 160.118) (xy 134.8681 147.7482) (xy 241.12609 147.7482) (xy 241.12609 50.009) (xy 56.0265 50.009)
				(xy 55.9503 50.0852) (xy 55.9503 155.9016)
			)
		)
	)
)
